FILE_TYPE = LIBRARY_PARTS;
{ Packager-XL run on 16-Jun-2017 AT 17:50:48 }
primitive '120R2F-GP_RCL_GP-120R2F-GP,64.A';
  pin
    '1':
      PIN_NUMBER='(1)';
      PIN_TYPE='ANALOG';
      NO_LOAD_CHECK='Both';
      NO_IO_CHECK='Both';
      NO_ASSERT_CHECK='TRUE';
      NO_DIR_CHECK='TRUE';
      ALLOW_CONNECT='TRUE';
      PINUSE='UNSPEC';
    '2':
      PIN_NUMBER='(2)';
      PIN_TYPE='ANALOG';
      NO_LOAD_CHECK='Both';
      NO_IO_CHECK='Both';
      NO_ASSERT_CHECK='TRUE';
      NO_DIR_CHECK='TRUE';
      ALLOW_CONNECT='TRUE';
      PINUSE='UNSPEC';
  end_pin;
  body
      PART_NAME='120R2F-GP';
      BODY_NAME='120R2F-GP';
      PHYS_DES_PREFIX='R';
      CLASS='DISCRETE';
      DESCRIPTION='CHIP RES 120 F 1/16W 0402';
      JEDEC_TYPE='R402H16';
      PARENT_PART_TYPE='120R2F-GP';
      PARENT_PPT='120R2F-GP';
      PARENT_PPT_PART='120R2F-GP_RCL_GP-120R2F-GP,64.12005.6DL,120OHM,1%,1/16W,0402';
  end_body;
end_primitive;
primitive '18KR2F-GP_RCL_GP-18KR2F-GP,64.A';
  pin
    '1':
      PIN_NUMBER='(1)';
      PIN_TYPE='ANALOG';
      NO_LOAD_CHECK='Both';
      NO_IO_CHECK='Both';
      NO_ASSERT_CHECK='TRUE';
      NO_DIR_CHECK='TRUE';
      ALLOW_CONNECT='TRUE';
      PINUSE='UNSPEC';
    '2':
      PIN_NUMBER='(2)';
      PIN_TYPE='ANALOG';
      NO_LOAD_CHECK='Both';
      NO_IO_CHECK='Both';
      NO_ASSERT_CHECK='TRUE';
      NO_DIR_CHECK='TRUE';
      ALLOW_CONNECT='TRUE';
      PINUSE='UNSPEC';
  end_pin;
  body
      PART_NAME='18KR2F-GP';
      BODY_NAME='18KR2F-GP';
      PHYS_DES_PREFIX='R';
      CLASS='DISCRETE';
      DESCRIPTION='CHIP RES 18K F 1/16W 0402';
      JEDEC_TYPE='R402H16';
      PARENT_PART_TYPE='18KR2F-GP';
      PARENT_PPT='18KR2F-GP';
      PARENT_PPT_PART='18KR2F-GP_RCL_GP-18KR2F-GP,64.18025.6DL,18KOHM,1%,1/16W,0402';
  end_body;
end_primitive;
primitive '1K82R2F-1-GP_SMD-RG-1K82R2F-1-A';
  pin
    '1':
      PIN_NUMBER='(1)';
      PIN_TYPE='ANALOG';
      NO_LOAD_CHECK='Both';
      NO_IO_CHECK='Both';
      NO_ASSERT_CHECK='TRUE';
      NO_DIR_CHECK='TRUE';
      ALLOW_CONNECT='TRUE';
      PINUSE='UNSPEC';
    '2':
      PIN_NUMBER='(2)';
      PIN_TYPE='ANALOG';
      NO_LOAD_CHECK='Both';
      NO_IO_CHECK='Both';
      NO_ASSERT_CHECK='TRUE';
      NO_DIR_CHECK='TRUE';
      ALLOW_CONNECT='TRUE';
      PINUSE='UNSPEC';
  end_pin;
  body
      PART_NAME='1K82R2F-1-GP';
      BODY_NAME='1K82R2F-1-GP';
      PHYS_DES_PREFIX='R';
      CLASS='DISCRETE';
      DESCRIPTION='CHIP RES 1.82K F 1/16W 0402';
      JEDEC_TYPE='R402H16';
      PARENT_PART_TYPE='1K82R2F-1-GP_SMD-RG';
      PARENT_PPT='1K82R2F-1-GP';
      PARENT_PPT_PART='1K82R2F-1-GP_SMD-RG-1K82R2F-1-GP,64.18215.6DL,1.82KOHM,1%,1/16W,0402';
  end_body;
end_primitive;
primitive '1MR2F-L-GP_SMD-RG1-1MR2F-L-GP,A';
  pin
    '1':
      PIN_NUMBER='(1)';
      PIN_TYPE='ANALOG';
      NO_LOAD_CHECK='Both';
      NO_IO_CHECK='Both';
      NO_ASSERT_CHECK='TRUE';
      NO_DIR_CHECK='TRUE';
      ALLOW_CONNECT='TRUE';
      PINUSE='UNSPEC';
    '2':
      PIN_NUMBER='(2)';
      PIN_TYPE='ANALOG';
      NO_LOAD_CHECK='Both';
      NO_IO_CHECK='Both';
      NO_ASSERT_CHECK='TRUE';
      NO_DIR_CHECK='TRUE';
      ALLOW_CONNECT='TRUE';
      PINUSE='UNSPEC';
  end_pin;
  body
      PART_NAME='1MR2F-L-GP';
      BODY_NAME='1MR2F-L-GP';
      PHYS_DES_PREFIX='R';
      CLASS='DISCRETE';
      DESCRIPTION='CHIP RES 1M F 1/16W 0402';
      JEDEC_TYPE='R402H16';
      PARENT_PART_TYPE='1MR2F-L-GP_SMD-RG1';
      PARENT_PPT='1MR2F-L-GP';
      PARENT_PPT_PART='1MR2F-L-GP_SMD-RG1-1MR2F-L-GP,64.10045.L1L,1MOHM,1%,1/16W,0402';
  end_body;
end_primitive;
primitive '1R3F-GP_RCL_GP-1R3F-GP,64.1R00A';
  pin
    '1':
      PIN_NUMBER='(1)';
      PIN_TYPE='ANALOG';
      NO_LOAD_CHECK='Both';
      NO_IO_CHECK='Both';
      NO_ASSERT_CHECK='TRUE';
      NO_DIR_CHECK='TRUE';
      ALLOW_CONNECT='TRUE';
      PINUSE='UNSPEC';
    '2':
      PIN_NUMBER='(2)';
      PIN_TYPE='ANALOG';
      NO_LOAD_CHECK='Both';
      NO_IO_CHECK='Both';
      NO_ASSERT_CHECK='TRUE';
      NO_DIR_CHECK='TRUE';
      ALLOW_CONNECT='TRUE';
      PINUSE='UNSPEC';
  end_pin;
  body
      PART_NAME='1R3F-GP';
      BODY_NAME='1R3F-GP';
      PHYS_DES_PREFIX='R';
      CLASS='DISCRETE';
      DESCRIPTION='CHIP RES 1 F 1/10W 0603';
      JEDEC_TYPE='R603H22';
      PARENT_PART_TYPE='1R3F-GP';
      PARENT_PPT='1R3F-GP';
      PARENT_PPT_PART='1R3F-GP_RCL_GP-1R3F-GP,64.1R005.55L,1 OHM,1%,1/10W,0603';
  end_body;
end_primitive;
primitive '200R2F-L1-GP_SMD-RG4-200R2F-L1A';
  pin
    '1':
      PIN_NUMBER='(1)';
      PIN_TYPE='ANALOG';
      NO_LOAD_CHECK='Both';
      NO_IO_CHECK='Both';
      NO_ASSERT_CHECK='TRUE';
      NO_DIR_CHECK='TRUE';
      ALLOW_CONNECT='TRUE';
      PINUSE='UNSPEC';
    '2':
      PIN_NUMBER='(2)';
      PIN_TYPE='ANALOG';
      NO_LOAD_CHECK='Both';
      NO_IO_CHECK='Both';
      NO_ASSERT_CHECK='TRUE';
      NO_DIR_CHECK='TRUE';
      ALLOW_CONNECT='TRUE';
      PINUSE='UNSPEC';
  end_pin;
  body
      PART_NAME='200R2F-L1-GP';
      BODY_NAME='200R2F-L1-GP';
      PHYS_DES_PREFIX='R';
      CLASS='DISCRETE';
      DESCRIPTION='CHIP RES 200 F 1/16W 0402 13" REEL';
      JEDEC_TYPE='R402H16';
      PARENT_PART_TYPE='200R2F-L1-GP_SMD-RG4';
      PARENT_PPT='200R2F-L1-GP';
      PARENT_PPT_PART='200R2F-L1-GP_SMD-RG4-200R2F-L1-GP,64.20005.L0L,200 OHM,1%,1/16W,0402';
  end_body;
end_primitive;
primitive '21K5R2F-GP_RCL_GP-21K5R2F-GP,6A';
  pin
    '1':
      PIN_NUMBER='(1)';
      PIN_TYPE='ANALOG';
      NO_LOAD_CHECK='Both';
      NO_IO_CHECK='Both';
      NO_ASSERT_CHECK='TRUE';
      NO_DIR_CHECK='TRUE';
      ALLOW_CONNECT='TRUE';
      PINUSE='UNSPEC';
    '2':
      PIN_NUMBER='(2)';
      PIN_TYPE='ANALOG';
      NO_LOAD_CHECK='Both';
      NO_IO_CHECK='Both';
      NO_ASSERT_CHECK='TRUE';
      NO_DIR_CHECK='TRUE';
      ALLOW_CONNECT='TRUE';
      PINUSE='UNSPEC';
  end_pin;
  body
      PART_NAME='21K5R2F-GP';
      BODY_NAME='21K5R2F-GP';
      PHYS_DES_PREFIX='R';
      CLASS='DISCRETE';
      DESCRIPTION='CHIP RES 21.5K F 1/16W 0402';
      JEDEC_TYPE='R402H16';
      PARENT_PART_TYPE='21K5R2F-GP';
      PARENT_PPT='21K5R2F-GP';
      PARENT_PPT_PART='21K5R2F-GP_RCL_GP-21K5R2F-GP,64.21525.6DL,21.5KOHM,1%,1/16W,0402';
  end_body;
end_primitive;
primitive '232KR2F-2-GP_SMD-RG1-232KR2F-2A';
  pin
    '1':
      PIN_NUMBER='(1)';
      PIN_TYPE='ANALOG';
      NO_LOAD_CHECK='Both';
      NO_IO_CHECK='Both';
      NO_ASSERT_CHECK='TRUE';
      NO_DIR_CHECK='TRUE';
      ALLOW_CONNECT='TRUE';
      PINUSE='UNSPEC';
    '2':
      PIN_NUMBER='(2)';
      PIN_TYPE='ANALOG';
      NO_LOAD_CHECK='Both';
      NO_IO_CHECK='Both';
      NO_ASSERT_CHECK='TRUE';
      NO_DIR_CHECK='TRUE';
      ALLOW_CONNECT='TRUE';
      PINUSE='UNSPEC';
  end_pin;
  body
      PART_NAME='232KR2F-2-GP';
      BODY_NAME='232KR2F-2-GP';
      PHYS_DES_PREFIX='R';
      CLASS='DISCRETE';
      DESCRIPTION='CHIP RES 232K F 1/16W 0402';
      JEDEC_TYPE='R402H16';
      PARENT_PART_TYPE='232KR2F-2-GP';
      PARENT_PPT='232KR2F-2-GP';
      PARENT_PPT_PART='232KR2F-2-GP_SMD-RG1-232KR2F-2-GP,64.23235.L0L,232KOHM,1%,1/16W,0402';
  end_body;
end_primitive;
primitive '270KR2F-GP_RCL_GP-270KR2F-GP,6A';
  pin
    '1':
      PIN_NUMBER='(1)';
      PIN_TYPE='ANALOG';
      NO_LOAD_CHECK='Both';
      NO_IO_CHECK='Both';
      NO_ASSERT_CHECK='TRUE';
      NO_DIR_CHECK='TRUE';
      ALLOW_CONNECT='TRUE';
      PINUSE='UNSPEC';
    '2':
      PIN_NUMBER='(2)';
      PIN_TYPE='ANALOG';
      NO_LOAD_CHECK='Both';
      NO_IO_CHECK='Both';
      NO_ASSERT_CHECK='TRUE';
      NO_DIR_CHECK='TRUE';
      ALLOW_CONNECT='TRUE';
      PINUSE='UNSPEC';
  end_pin;
  body
      PART_NAME='270KR2F-GP';
      BODY_NAME='270KR2F-GP';
      PHYS_DES_PREFIX='R';
      CLASS='DISCRETE';
      DESCRIPTION='CHIP RES 270K F 1/16W 0402';
      JEDEC_TYPE='R402H16';
      PARENT_PART_TYPE='270KR2F-GP';
      PARENT_PPT='270KR2F-GP';
      PARENT_PPT_PART='270KR2F-GP_RCL_GP-270KR2F-GP,64.27035.6DL,270KOHM,1%,1/16W,0402';
  end_body;
end_primitive;
primitive '2K15R2F-1-GP_SMD-RG1-2K15R2F-1A';
  pin
    '1':
      PIN_NUMBER='(1)';
      PIN_TYPE='ANALOG';
      NO_LOAD_CHECK='Both';
      NO_IO_CHECK='Both';
      NO_ASSERT_CHECK='T2K15R2F-1-GPUE';
      NO_DIR_CHECK='T2K15R2F-1-GPUE';
      ALLOW_CONNECT='T2K15R2F-1-GPUE';
      PINUSE='UNSPEC';
    '2':
      PIN_NUMBER='(2)';
      PIN_TYPE='ANALOG';
      NO_LOAD_CHECK='Both';
      NO_IO_CHECK='Both';
      NO_ASSERT_CHECK='T2K15R2F-1-GPUE';
      NO_DIR_CHECK='T2K15R2F-1-GPUE';
      ALLOW_CONNECT='T2K15R2F-1-GPUE';
      PINUSE='UNSPEC';
  end_pin;
  body
      PART_NAME='2K15R2F-1-GP';
      BODY_NAME='2K15R2F-1-GP';
      PHYS_DES_PREFIX='R';
      CLASS='DISCRETE';
      DESCRIPTION='CHIP RES 2.15K F 1/16W 0402';
      JEDEC_TYPE='R402H16';
      PARENT_PART_TYPE='2K15R2F-1-GP';
      PARENT_PPT='2K15R2F-1-GP';
      PARENT_PPT_PART='2K15R2F-1-GP_SMD-RG1-2K15R2F-1-GP,64.21515.6DL,2.15K OHM,1%,1/16W,0402';
  end_body;
end_primitive;
primitive '2SB2907A-B0-00001-GP_DISCRET-GA';
  pin
    'C':
      PIN_NUMBER='(C)';
      PIN_TYPE='ANALOG';
      NO_LOAD_CHECK='Both';
      NO_IO_CHECK='Both';
      NO_ASSERT_CHECK='TRUE';
      NO_DIR_CHECK='TRUE';
      ALLOW_CONNECT='TRUE';
      PINUSE='UNSPEC';
    'B':
      PIN_NUMBER='(B)';
      PIN_TYPE='ANALOG';
      NO_LOAD_CHECK='Both';
      NO_IO_CHECK='Both';
      NO_ASSERT_CHECK='TRUE';
      NO_DIR_CHECK='TRUE';
      ALLOW_CONNECT='TRUE';
      PINUSE='UNSPEC';
    'E':
      PIN_NUMBER='(E)';
      PIN_TYPE='ANALOG';
      NO_LOAD_CHECK='Both';
      NO_IO_CHECK='Both';
      NO_ASSERT_CHECK='TRUE';
      NO_DIR_CHECK='TRUE';
      ALLOW_CONNECT='TRUE';
      PINUSE='UNSPEC';
  end_pin;
  body
      PART_NAME='2SB2907A-B0-00001-GP';
      BODY_NAME='2SB2907A-B0-00001-GP';
      PHYS_DES_PREFIX='Q';
      CLASS='DISCRETE';
      DESCRIPTION='XTOR PNP 2SB2907A_B0_00001 TO-92 AMMO';
      JEDEC_TYPE='TO-92-CBE-5537-1H362';
      PARENT_PART_TYPE='2SB2907A-B0-00001-GP';
      PARENT_PPT='2SB2907A-B0-00001-GP';
      PARENT_PPT_PART='2SB2907A-B0-00001-GP_DISCRET-GB1-2SB2907A-B0-00001-GP,006.02907.001A';
  end_body;
end_primitive;
primitive '374R2F-1-GP_SMD-RG-374R2F-1-GPA';
  pin
    '1':
      PIN_NUMBER='(1)';
      PIN_TYPE='ANALOG';
      NO_LOAD_CHECK='Both';
      NO_IO_CHECK='Both';
      NO_ASSERT_CHECK='T374R2F-1-GPUE';
      NO_DIR_CHECK='T374R2F-1-GPUE';
      ALLOW_CONNECT='T374R2F-1-GPUE';
      PINUSE='UNSPEC';
    '2':
      PIN_NUMBER='(2)';
      PIN_TYPE='ANALOG';
      NO_LOAD_CHECK='Both';
      NO_IO_CHECK='Both';
      NO_ASSERT_CHECK='T374R2F-1-GPUE';
      NO_DIR_CHECK='T374R2F-1-GPUE';
      ALLOW_CONNECT='T374R2F-1-GPUE';
      PINUSE='UNSPEC';
  end_pin;
  body
      PART_NAME='374R2F-1-GP';
      BODY_NAME='374R2F-1-GP';
      PHYS_DES_PREFIX='R';
      CLASS='DISCRETE';
      DESCRIPTION='CHIP RES 374 F 1/16W0402 (ROHS';
      JEDEC_TYPE='R402H16';
      PARENT_PART_TYPE='374R2F-1-GP';
      PARENT_PPT='374R2F-1-GP';
      PARENT_PPT_PART='374R2F-1-GP_SMD-RG-374R2F-1-GP,64.37405.6DL,374 OHM,1%,1/16W,0402';
  end_body;
end_primitive;
primitive '47KR2F-GP_RCL_GP-47KR2F-GP,64.A';
  pin
    '1':
      PIN_NUMBER='(1)';
      PIN_TYPE='ANALOG';
      NO_LOAD_CHECK='Both';
      NO_IO_CHECK='Both';
      NO_ASSERT_CHECK='TRUE';
      NO_DIR_CHECK='TRUE';
      ALLOW_CONNECT='TRUE';
      PINUSE='UNSPEC';
    '2':
      PIN_NUMBER='(2)';
      PIN_TYPE='ANALOG';
      NO_LOAD_CHECK='Both';
      NO_IO_CHECK='Both';
      NO_ASSERT_CHECK='TRUE';
      NO_DIR_CHECK='TRUE';
      ALLOW_CONNECT='TRUE';
      PINUSE='UNSPEC';
  end_pin;
  body
      PART_NAME='47KR2F-GP';
      BODY_NAME='47KR2F-GP';
      PHYS_DES_PREFIX='R';
      CLASS='DISCRETE';
      DESCRIPTION='CHIP RES 47K F 1/16W 0402';
      JEDEC_TYPE='R402H16';
      PARENT_PART_TYPE='47KR2F-GP_RCL_GP';
      PARENT_PPT='47KR2F-GP';
      PARENT_PPT_PART='47KR2F-GP_RCL_GP-47KR2F-GP,64.47025.6DL,47KOHM,1%,1/16W,0402';
  end_body;
end_primitive;
primitive '4D02R2F-GP_SMD-RG2-4D02R2F-GP,A';
  pin
    '1':
      PIN_NUMBER='(1)';
      PIN_TYPE='ANALOG';
      NO_LOAD_CHECK='Both';
      NO_IO_CHECK='Both';
      NO_ASSERT_CHECK='TRUE';
      NO_DIR_CHECK='TRUE';
      ALLOW_CONNECT='TRUE';
      PINUSE='UNSPEC';
    '2':
      PIN_NUMBER='(2)';
      PIN_TYPE='ANALOG';
      NO_LOAD_CHECK='Both';
      NO_IO_CHECK='Both';
      NO_ASSERT_CHECK='TRUE';
      NO_DIR_CHECK='TRUE';
      ALLOW_CONNECT='TRUE';
      PINUSE='UNSPEC';
  end_pin;
  body
      PART_NAME='4D02R2F-GP';
      BODY_NAME='4D02R2F-GP';
      PHYS_DES_PREFIX='R';
      CLASS='DISCRETE';
      DESCRIPTION='CHIP RES 4.02 F 1/16W 0402';
      JEDEC_TYPE='R402H16';
      PARENT_PART_TYPE='4D02R2F-GP';
      PARENT_PPT='4D02R2F-GP';
      PARENT_PPT_PART='4D02R2F-GP_SMD-RG2-4D02R2F-GP,64.4R025.6DL,4.02OHM,1%,1/16W,0402';
  end_body;
end_primitive;
primitive '4K42R2F-GP_SMD-RG-4K42R2F-GP,6A';
  pin
    '1':
      PIN_NUMBER='(1)';
      PIN_TYPE='ANALOG';
      NO_LOAD_CHECK='Both';
      NO_IO_CHECK='Both';
      NO_ASSERT_CHECK='TRUE';
      NO_DIR_CHECK='TRUE';
      ALLOW_CONNECT='TRUE';
      PINUSE='UNSPEC';
    '2':
      PIN_NUMBER='(2)';
      PIN_TYPE='ANALOG';
      NO_LOAD_CHECK='Both';
      NO_IO_CHECK='Both';
      NO_ASSERT_CHECK='TRUE';
      NO_DIR_CHECK='TRUE';
      ALLOW_CONNECT='TRUE';
      PINUSE='UNSPEC';
  end_pin;
  body
      PART_NAME='4K42R2F-GP';
      BODY_NAME='4K42R2F-GP';
      PHYS_DES_PREFIX='R';
      CLASS='DISCRETE';
      DESCRIPTION='CHIP RES 4.42K F 1/16W 0402(RO';
      JEDEC_TYPE='R402H16';
      PARENT_PART_TYPE='4K42R2F-GP_SMD-RG';
      PARENT_PPT='4K42R2F-GP';
      PARENT_PPT_PART='4K42R2F-GP_SMD-RG-4K42R2F-GP,64.44215.6DL,4.42KOHM,1%,1/16W,0402';
  end_body;
end_primitive;
primitive '5K1R2F-2-GP_SMD-RG-5K1R2F-2-GPA';
  pin
    '1':
      PIN_NUMBER='(1)';
      PIN_TYPE='ANALOG';
      NO_LOAD_CHECK='Both';
      NO_IO_CHECK='Both';
      NO_ASSERT_CHECK='TRUE';
      NO_DIR_CHECK='TRUE';
      ALLOW_CONNECT='TRUE';
      PINUSE='UNSPEC';
    '2':
      PIN_NUMBER='(2)';
      PIN_TYPE='ANALOG';
      NO_LOAD_CHECK='Both';
      NO_IO_CHECK='Both';
      NO_ASSERT_CHECK='TRUE';
      NO_DIR_CHECK='TRUE';
      ALLOW_CONNECT='TRUE';
      PINUSE='UNSPEC';
  end_pin;
  body
      PART_NAME='5K1R2F-2-GP';
      BODY_NAME='5K1R2F-2-GP';
      PHYS_DES_PREFIX='R';
      CLASS='DISCRETE';
      DESCRIPTION='CHIP RES 5.1K F 1/16W 0402';
      JEDEC_TYPE='R402H16';
      PARENT_PART_TYPE='5K1R2F-2-GP_SMD-RG';
      PARENT_PPT='5K1R2F-2-GP';
      PARENT_PPT_PART='5K1R2F-2-GP_SMD-RG-5K1R2F-2-GP,64.51015.6DL,5.1KOHM,1%,1/16W,0402';
  end_body;
end_primitive;
primitive '649R2F-GP_RCL_GP-649R2F-GP,64.A';
  pin
    '1':
      PIN_NUMBER='(1)';
      PIN_TYPE='ANALOG';
      NO_LOAD_CHECK='Both';
      NO_IO_CHECK='Both';
      NO_ASSERT_CHECK='TRUE';
      NO_DIR_CHECK='TRUE';
      ALLOW_CONNECT='TRUE';
      PINUSE='UNSPEC';
    '2':
      PIN_NUMBER='(2)';
      PIN_TYPE='ANALOG';
      NO_LOAD_CHECK='Both';
      NO_IO_CHECK='Both';
      NO_ASSERT_CHECK='TRUE';
      NO_DIR_CHECK='TRUE';
      ALLOW_CONNECT='TRUE';
      PINUSE='UNSPEC';
  end_pin;
  body
      PART_NAME='649R2F-GP';
      BODY_NAME='649R2F-GP';
      PHYS_DES_PREFIX='R';
      CLASS='DISCRETE';
      DESCRIPTION='CHIP RES 649 F 1/16W 0402';
      JEDEC_TYPE='R402H16';
      PARENT_PART_TYPE='649R2F-GP_RCL_GP';
      PARENT_PPT='649R2F-GP';
      PARENT_PPT_PART='649R2F-GP_RCL_GP-649R2F-GP,64.64905.6DL,649OHM,1%,1/16W,0402';
  end_body;
end_primitive;
primitive '665KR2B-GP_SMD-RG2-665KR2B-GP,A';
  pin
    '1':
      PIN_NUMBER='(1)';
      PIN_TYPE='ANALOG';
      NO_LOAD_CHECK='Both';
      NO_IO_CHECK='Both';
      NO_ASSERT_CHECK='TRUE';
      NO_DIR_CHECK='TRUE';
      ALLOW_CONNECT='TRUE';
      PINUSE='UNSPEC';
    '2':
      PIN_NUMBER='(2)';
      PIN_TYPE='ANALOG';
      NO_LOAD_CHECK='Both';
      NO_IO_CHECK='Both';
      NO_ASSERT_CHECK='TRUE';
      NO_DIR_CHECK='TRUE';
      ALLOW_CONNECT='TRUE';
      PINUSE='UNSPEC';
  end_pin;
  body
      PART_NAME='665KR2B-GP';
      BODY_NAME='665KR2B-GP';
      PHYS_DES_PREFIX='R';
      CLASS='DISCRETE';
      DESCRIPTION='CHIP RES 665K B 1/16W 0402 THICK';
      JEDEC_TYPE='R402H16';
      PARENT_PART_TYPE='665KR2B-GP';
      PARENT_PPT='665KR2B-GP';
      PARENT_PPT_PART='665KR2B-GP_SMD-RG2-665KR2B-GP,064.6653D.06DD,665KOHM,0.1%,1/16W,0402';
  end_body;
end_primitive;
primitive '665KR5B-1-GP_SMD-RG3-665KR5B-1A';
  pin
    '1':
      PIN_NUMBER='(1)';
      PIN_TYPE='ANALOG';
      NO_LOAD_CHECK='Both';
      NO_IO_CHECK='Both';
      NO_ASSERT_CHECK='T665KR5B-1-GPUE';
      NO_DIR_CHECK='T665KR5B-1-GPUE';
      ALLOW_CONNECT='T665KR5B-1-GPUE';
      PINUSE='UNSPEC';
    '2':
      PIN_NUMBER='(2)';
      PIN_TYPE='ANALOG';
      NO_LOAD_CHECK='Both';
      NO_IO_CHECK='Both';
      NO_ASSERT_CHECK='T665KR5B-1-GPUE';
      NO_DIR_CHECK='T665KR5B-1-GPUE';
      ALLOW_CONNECT='T665KR5B-1-GPUE';
      PINUSE='UNSPEC';
  end_pin;
  body
      PART_NAME='665KR5B-1-GP';
      BODY_NAME='665KR5B-1-GP';
      PHYS_DES_PREFIX='R';
      CLASS='DISCRETE';
      DESCRIPTION='CHIP RES 665K B 1/8W AT0805 50PPM(FIONA)';
      JEDEC_TYPE='R805H24';
      PARENT_PART_TYPE='665KR5B-1-GP';
      PARENT_PPT='665KR5B-1-GP';
      PARENT_PPT_PART='665KR5B-1-GP_SMD-RG3-665KR5B-1-GP,064.6653F.M001,665K OHM,0.1%,1/8W,AT0805';
  end_body;
end_primitive;
primitive '74CBTLV1G125_SMLF-IC,C88177-00A';
  pin
    'B':
      OUTPUT_LOAD='(20.0,-1.0)';
      PIN_NUMBER='(4)';
      PINUSE='OUT';
    'OE_N':
      INPUT_LOAD='(-0.6,0.02)';
      PIN_NUMBER='(1)';
      PIN_GROUP='1';
      PINUSE='IN';
    'A':
      INPUT_LOAD='(-0.6,0.02)';
      PIN_NUMBER='(2)';
      PIN_GROUP='1';
      PINUSE='IN';
  end_pin;
  body
      BODY_NAME='74CBTLV1G125';
      PART_NAME='74CBTLV1G125';
      ENVCOMP='YES;YES;UNK;UNK;ok;VLD';
      PART_NUMBER='C88177-001';
      JEDEC_TYPE='SSOP5_53_65MA';
      CLASS='IC';
      DESCRIPTION='FET BUS SW';
      HEIGHT='0.043 IN';
      COMPONENT_TYPE='SMALLSMT';
      LEAD_LENGTH='';
      LPID='';
      SPEED_URL='http://speed.intel.com:8081/speed/module/pdm/item/pdm_item_deta~
il_direct.asp?item_cde=C88177-001&item_rev=01&url_param=unused';
      STATUS='Conditional';
      RPL='YES';
      AML='1';
      BUS_UNIT='SMO_IC';
      DAYS='28';
      POWER_PINS='(P3V3_STBY:5;GND:3)';
      PARENT_PART_TYPE='74CBTLV1G125';
      SCH_MODIFIED_PART='TRUE';
      PARENT_PPT='74CBTLV1G125';
      PARENT_PPT_PART='74CBTLV1G125_SMLF-IC,C88177-001';
  end_body;
end_primitive;
primitive '82KR2F-1-GP_SMD-RG-82KR2F-1-GPA';
  pin
    '1':
      PIN_NUMBER='(1)';
      PIN_TYPE='ANALOG';
      NO_LOAD_CHECK='Both';
      NO_IO_CHECK='Both';
      NO_ASSERT_CHECK='TRUE';
      NO_DIR_CHECK='TRUE';
      ALLOW_CONNECT='TRUE';
      PINUSE='UNSPEC';
    '2':
      PIN_NUMBER='(2)';
      PIN_TYPE='ANALOG';
      NO_LOAD_CHECK='Both';
      NO_IO_CHECK='Both';
      NO_ASSERT_CHECK='TRUE';
      NO_DIR_CHECK='TRUE';
      ALLOW_CONNECT='TRUE';
      PINUSE='UNSPEC';
  end_pin;
  body
      PART_NAME='82KR2F-1-GP';
      BODY_NAME='82KR2F-1-GP';
      PHYS_DES_PREFIX='R';
      CLASS='DISCRETE';
      DESCRIPTION='CHIP RES 82K F 1/16W 0402';
      JEDEC_TYPE='R402H16';
      PARENT_PART_TYPE='82KR2F-1-GP_SMD-RG';
      PARENT_PPT='82KR2F-1-GP';
      PARENT_PPT_PART='82KR2F-1-GP_SMD-RG-82KR2F-1-GP,64.82025.6DL,82KOHM,1%,1/16W,0402';
  end_body;
end_primitive;
primitive '887R2F-L-GP_SMD-RG-887R2F-L-GPA';
  pin
    '1':
      PIN_NUMBER='(1)';
      PIN_TYPE='ANALOG';
      NO_LOAD_CHECK='Both';
      NO_IO_CHECK='Both';
      NO_ASSERT_CHECK='TRUE';
      NO_DIR_CHECK='TRUE';
      ALLOW_CONNECT='TRUE';
      PINUSE='UNSPEC';
    '2':
      PIN_NUMBER='(2)';
      PIN_TYPE='ANALOG';
      NO_LOAD_CHECK='Both';
      NO_IO_CHECK='Both';
      NO_ASSERT_CHECK='TRUE';
      NO_DIR_CHECK='TRUE';
      ALLOW_CONNECT='TRUE';
      PINUSE='UNSPEC';
  end_pin;
  body
      PART_NAME='887R2F-L-GP';
      BODY_NAME='887R2F-L-GP';
      PHYS_DES_PREFIX='R';
      CLASS='DISCRETE';
      DESCRIPTION='CHIP RES 887 F 1/16W 0402';
      JEDEC_TYPE='R402H16';
      PARENT_PART_TYPE='887R2F-L-GP';
      PARENT_PPT='887R2F-L-GP';
      PARENT_PPT_PART='887R2F-L-GP_SMD-RG-887R2F-L-GP,64.88705.6DL,887OHM,1%,1/16W,0402';
  end_body;
end_primitive;
primitive 'ADM1085_SMT-IC,H46130-001';
  pin
    'CEXT':
      PIN_NUMBER='(5)';
      PIN_TYPE='ANALOG';
      NO_LOAD_CHECK='Both';
      NO_IO_CHECK='Both';
      NO_ASSERT_CHECK='TRUE';
      NO_DIR_CHECK='TRUE';
      ALLOW_CONNECT='TRUE';
      PINUSE='UNSPEC';
    'ENIN':
      PIN_NUMBER='(1)';
      INPUT_LOAD='(-0.01,0.01)';
      PINUSE='IN';
    'ENOUT':
      PIN_NUMBER='(4)';
      OUTPUT_LOAD='(1.0,-1.0)';
      PINUSE='OUT';
    'GND':
      PIN_NUMBER='(2)';
      PINUSE='GROUND';
      NO_LOAD_CHECK='Both';
      NO_IO_CHECK='Both';
      NO_ASSERT_CHECK='TRUE';
      NO_DIR_CHECK='TRUE';
      ALLOW_CONNECT='TRUE';
    'VCC':
      PIN_NUMBER='(6)';
      PINUSE='POWER';
      NO_LOAD_CHECK='Both';
      NO_IO_CHECK='Both';
      NO_ASSERT_CHECK='TRUE';
      NO_DIR_CHECK='TRUE';
      ALLOW_CONNECT='TRUE';
    'VIN':
      PIN_NUMBER='(3)';
      INPUT_LOAD='(-0.01,0.01)';
      PINUSE='IN';
  end_pin;
  body
      PART_NAME='ADM1085';
      PHYS_DES_PREFIX='U';
      ENVCOMP='UNK;UNK;UNK;UNK;ok;CIP';
      PART_NUMBER='H46130-001';
      JEDEC_TYPE='SSOP6_53_65MC';
      DESCRIPTION='IC,LIN,SPRVSR,6SC70,ADM1085,AH';
      CLASS='IC';
      COMPONENT_TYPE='SMALLSMT';
      HEIGHT='0.043 IN';
      LPID='3211';
      SPEED_URL='http://speed.intel.com:8081/speed/module/pdm/item/pdm_item_deta~
il_direct.asp?item_cde=H46130-001&item_rev=01&url_param=unused';
      STATUS='Design';
      RPL='NO';
      AML='1';
      BUS_UNIT='APD';
      DAYS='???';
      PARENT_PART_TYPE='ADM1085_SMT';
      PARENT_PPT='ADM1085';
      PARENT_PPT_PART='ADM1085_SMT-IC,H46130-001';
  end_body;
end_primitive;
primitive 'ADM1278_SM-IC,G99251-001';
  pin
    'ADR1':
      PIN_NUMBER='(7)';
      PIN_TYPE='ANALOG';
      NO_LOAD_CHECK='Both';
      NO_IO_CHECK='Both';
      NO_ASSERT_CHECK='TRUE';
      NO_DIR_CHECK='TRUE';
      ALLOW_CONNECT='TRUE';
      PINUSE='UNSPEC';
    'ADR2':
      PIN_NUMBER='(8)';
      PIN_TYPE='ANALOG';
      NO_LOAD_CHECK='Both';
      NO_IO_CHECK='Both';
      NO_ASSERT_CHECK='TRUE';
      NO_DIR_CHECK='TRUE';
      ALLOW_CONNECT='TRUE';
      PINUSE='UNSPEC';
    'CSOUT':
      PIN_NUMBER='(19)';
      OUTPUT_LOAD='(1.0,-1.0)';
      PINUSE='OUT';
    'ENABLE':
      PIN_NUMBER='(12)';
      INPUT_LOAD='(-0.01,0.01)';
      PINUSE='IN';
    'EP':
      PIN_NUMBER='(33)';
      PINUSE='GROUND';
      NO_LOAD_CHECK='Both';
      NO_IO_CHECK='Both';
      NO_ASSERT_CHECK='TRUE';
      NO_DIR_CHECK='TRUE';
      ALLOW_CONNECT='TRUE';
    'FAULT_N':
      PIN_NUMBER='(6)';
      PIN_TYPE='ANALOG';
      NO_LOAD_CHECK='Both';
      NO_IO_CHECK='Both';
      NO_ASSERT_CHECK='TRUE';
      NO_DIR_CHECK='TRUE';
      ALLOW_CONNECT='TRUE';
      PINUSE='UNSPEC';
    'GATE':
      PIN_NUMBER='(24)';
      OUTPUT_LOAD='(1.0,-1.0)';
      PINUSE='OUT';
    'GND':
      PIN_NUMBER='(22)';
      PINUSE='GROUND';
      NO_LOAD_CHECK='Both';
      NO_IO_CHECK='Both';
      NO_ASSERT_CHECK='TRUE';
      NO_DIR_CHECK='TRUE';
      ALLOW_CONNECT='TRUE';
    'GPO1_ALERT1_N_CONV':
      PIN_NUMBER='(13)';
      BIDIRECTIONAL='TRUE';
      INPUT_LOAD='(-0.01,0.01)';
      OUTPUT_LOAD='(1.0,-1.0)';
      PINUSE='BI';
    'GPO2_ALERT2_N':
      PIN_NUMBER='(14)';
      BIDIRECTIONAL='TRUE';
      INPUT_LOAD='(-0.01,0.01)';
      OUTPUT_LOAD='(1.0,-1.0)';
      PINUSE='BI';
    'HSN':
      PIN_NUMBER='(27)';
      INPUT_LOAD='(-0.01,0.01)';
      PINUSE='IN';
    'HSP':
      PIN_NUMBER='(28)';
      INPUT_LOAD='(-0.01,0.01)';
      PINUSE='IN';
    'ISET':
      PIN_NUMBER='(3)';
      INPUT_LOAD='(-0.01,0.01)';
      PINUSE='IN';
    'ISTART':
      PIN_NUMBER='(4)';
      INPUT_LOAD='(-0.01,0.01)';
      PINUSE='IN';
    'MCLK':
      PIN_NUMBER='(10)';
      OUTPUT_LOAD='(1.0,-1.0)';
      PINUSE='OUT';
    'MDAT':
      PIN_NUMBER='(11)';
      OUTPUT_LOAD='(1.0,-1.0)';
      PINUSE='OUT';
    'MON':
      PIN_NUMBER='(26)';
      INPUT_LOAD='(-0.01,0.01)';
      PINUSE='IN';
    'MOP':
      PIN_NUMBER='(29)';
      INPUT_LOAD='(-0.01,0.01)';
      PINUSE='IN';
    'OV':
      PIN_NUMBER='(32)';
      INPUT_LOAD='(-0.01,0.01)';
      PINUSE='IN';
    'PGND':
      PIN_NUMBER='(23)';
      PINUSE='GROUND';
      NO_LOAD_CHECK='Both';
      NO_IO_CHECK='Both';
      NO_ASSERT_CHECK='TRUE';
      NO_DIR_CHECK='TRUE';
      ALLOW_CONNECT='TRUE';
    'PSET':
      PIN_NUMBER='(1)';
      INPUT_LOAD='(-0.01,0.01)';
      PINUSE='IN';
    'PWGIN':
      PIN_NUMBER='(21)';
      INPUT_LOAD='(-0.01,0.01)';
      PINUSE='IN';
    'PWRGD':
      PIN_NUMBER='(18)';
      PIN_TYPE='ANALOG';
      NO_LOAD_CHECK='Both';
      NO_IO_CHECK='Both';
      NO_ASSERT_CHECK='TRUE';
      NO_DIR_CHECK='TRUE';
      ALLOW_CONNECT='TRUE';
      PINUSE='UNSPEC';
    'RETRY_N':
      PIN_NUMBER='(17)';
      PIN_TYPE='ANALOG';
      NO_LOAD_CHECK='Both';
      NO_IO_CHECK='Both';
      NO_ASSERT_CHECK='TRUE';
      NO_DIR_CHECK='TRUE';
      ALLOW_CONNECT='TRUE';
      PINUSE='UNSPEC';
    'SCL':
      PIN_NUMBER='(16)';
      INPUT_LOAD='(-0.01,0.01)';
      PINUSE='IN';
    'SDA':
      PIN_NUMBER='(15)';
      BIDIRECTIONAL='TRUE';
      INPUT_LOAD='(-0.01,0.01)';
      OUTPUT_LOAD='(1.0,-1.0)';
      PINUSE='BI';
    'SPISS_N':
      PIN_NUMBER='(9)';
      PIN_TYPE='ANALOG';
      NO_LOAD_CHECK='Both';
      NO_IO_CHECK='Both';
      NO_ASSERT_CHECK='TRUE';
      NO_DIR_CHECK='TRUE';
      ALLOW_CONNECT='TRUE';
      PINUSE='UNSPEC';
    'TEMP':
      PIN_NUMBER='(25)';
      INPUT_LOAD='(-0.01,0.01)';
      PINUSE='IN';
    'TIMER':
      PIN_NUMBER='(5)';
      PIN_TYPE='ANALOG';
      NO_LOAD_CHECK='Both';
      NO_IO_CHECK='Both';
      NO_ASSERT_CHECK='TRUE';
      NO_DIR_CHECK='TRUE';
      ALLOW_CONNECT='TRUE';
      PINUSE='UNSPEC';
    'UV':
      PIN_NUMBER='(31)';
      INPUT_LOAD='(-0.01,0.01)';
      PINUSE='IN';
    'VCAP':
      PIN_NUMBER='(2)';
      INPUT_LOAD='(-0.01,0.01)';
      PINUSE='IN';
    'VCC':
      PIN_NUMBER='(30)';
      PINUSE='POWER';
      NO_LOAD_CHECK='Both';
      NO_IO_CHECK='Both';
      NO_ASSERT_CHECK='TRUE';
      NO_DIR_CHECK='TRUE';
      ALLOW_CONNECT='TRUE';
    'VOUT':
      PIN_NUMBER='(20)';
      OUTPUT_LOAD='(1.0,-1.0)';
      PINUSE='OUT';
  end_pin;
  body
      PART_NAME='ADM1278';
      PHYS_DES_PREFIX='EU';
      ENVCOMP='YES;YES;YES;UNK;ok;VLD';
      PART_NUMBER='G99251-001';
      JEDEC_TYPE='QFN32_20_5MB';
      DESCRIPTION='IC,LIN,CONT,20,LFCSP,ADM1278-1,PSP';
      CLASS='IC';
      COMPONENT_TYPE='LCC';
      HEIGHT='0.031 IN';
      LPID='2397';
      SPEED_URL='http://speed.intel.com:8081/speed/module/pdm/item/pdm_item_deta~
il_direct.asp?item_cde=G99251-001&item_rev=01&url_param=unused';
      STATUS='Design';
      RPL='NO';
      AML='1';
      BUS_UNIT='SMO_IC';
      DAYS='???';
      PARENT_PART_TYPE='ADM1278_SM';
      PARENT_PPT='ADM1278';
      PARENT_PPT_PART='ADM1278_SM-IC,G99251-001';
  end_body;
end_primitive;
primitive 'ADM809_SMLF-IC,D23047-001-GND=A';
  pin
    'VCC':
      PIN_NUMBER='(3)';
      PIN_TYPE='POWER';
      NO_LOAD_CHECK='Both';
      NO_IO_CHECK='Both';
      ALLOW_CONNECT='TRUE';
      PINUSE='POWER';
    'RESET_N':
      PIN_NUMBER='(2)';
      OUTPUT_LOAD='(10.0,-10.0)';
      PINUSE='OUT';
  end_pin;
  body
      PART_NAME='ADM809';
      PHYS_DES_PREFIX='U';
      CLASS='IC';
      ENVCOMP='YES;YES;UNK;UNK;ok;VLD';
      PART_NUMBER='D23047-001';
      JEDEC_TYPE='SOT23B';
      DESCRIPTION='3.3V RESET W/PUSH PULL ADM809S';
      HEIGHT='0.044 IN';
      COMPONENT_TYPE='SMALLSMT';
      LEAD_LENGTH='';
      LPID='801';
      SPEED_URL='http://speed.intel.com:8081/speed/module/pdm/item/pdm_item_deta~
il_direct.asp?item_cde=D23047-001&item_rev=01&url_param=unused';
      STATUS='Conditional';
      RPL='YES';
      AML='2';
      BUS_UNIT='SMO_IC';
      DAYS='84';
      POWER_PINS='(GND:1)';
      PARENT_PART_TYPE='ADM809';
      SCH_MODIFIED_PART='TRUE';
      PARENT_PPT='ADM809';
      PARENT_PPT_PART='ADM809_SMLF-IC,D23047-001';
  end_body;
end_primitive;
primitive 'AST2520A1-GP-GP_ASIC2-GB1-AST2A';
  pin
    'MDQ4':
      PIN_NUMBER='(U9,0,0,0,0,0,0)';
      BIDIRECTIONAL='TRUE';
      INPUT_LOAD='(-0.01,0.01)';
      OUTPUT_LOAD='(1.0,-1.0)';
      PINUSE='BI';
    'MDQ3':
      PIN_NUMBER='(AA10,0,0,0,0,0,0)';
      BIDIRECTIONAL='TRUE';
      INPUT_LOAD='(-0.01,0.01)';
      OUTPUT_LOAD='(1.0,-1.0)';
      PINUSE='BI';
    'MDQ2':
      PIN_NUMBER='(Y10,0,0,0,0,0,0)';
      BIDIRECTIONAL='TRUE';
      INPUT_LOAD='(-0.01,0.01)';
      OUTPUT_LOAD='(1.0,-1.0)';
      PINUSE='BI';
    'MDQ1':
      PIN_NUMBER='(W10,0,0,0,0,0,0)';
      BIDIRECTIONAL='TRUE';
      INPUT_LOAD='(-0.01,0.01)';
      OUTPUT_LOAD='(1.0,-1.0)';
      PINUSE='BI';
    'MDQ0':
      PIN_NUMBER='(U10,0,0,0,0,0,0)';
      BIDIRECTIONAL='TRUE';
      INPUT_LOAD='(-0.01,0.01)';
      OUTPUT_LOAD='(1.0,-1.0)';
      PINUSE='BI';
    'MA15':
      PIN_NUMBER='(U15,0,0,0,0,0,0)';
      OUTPUT_LOAD='(1.0,-1.0)';
      PINUSE='OUT';
    'MDQ15':
      PIN_NUMBER='(U7,0,0,0,0,0,0)';
      BIDIRECTIONAL='TRUE';
      INPUT_LOAD='(-0.01,0.01)';
      OUTPUT_LOAD='(1.0,-1.0)';
      PINUSE='BI';
    'MDQ14':
      PIN_NUMBER='(V7,0,0,0,0,0,0)';
      BIDIRECTIONAL='TRUE';
      INPUT_LOAD='(-0.01,0.01)';
      OUTPUT_LOAD='(1.0,-1.0)';
      PINUSE='BI';
    'MDM1':
      PIN_NUMBER='(AB8,0,0,0,0,0,0)';
      OUTPUT_LOAD='(1.0,-1.0)';
      PINUSE='OUT';
    'MIOZ':
      PIN_NUMBER='(W11,0,0,0,0,0,0)';
      PIN_TYPE='ANALOG';
      NO_LOAD_CHECK='Both';
      NO_IO_CHECK='Both';
      NO_ASSERT_CHECK='TRUE';
      NO_DIR_CHECK='TRUE';
      ALLOW_CONNECT='TRUE';
      PINUSE='UNSPEC';
    'MCAS#':
      PIN_NUMBER='(AB13,0,0,0,0,0,0)';
      OUTPUT_LOAD='(1.0,-1.0)';
      PINUSE='OUT';
    'MA10':
      PIN_NUMBER='(U13,0,0,0,0,0,0)';
      OUTPUT_LOAD='(1.0,-1.0)';
      PINUSE='OUT';
    'MA11':
      PIN_NUMBER='(AA14,0,0,0,0,0,0)';
      OUTPUT_LOAD='(1.0,-1.0)';
      PINUSE='OUT';
    'MVREF':
      PIN_NUMBER='(T9,0,0,0,0,0,0)';
      PIN_TYPE='ANALOG';
      NO_LOAD_CHECK='Both';
      NO_IO_CHECK='Both';
      NO_ASSERT_CHECK='TRUE';
      NO_DIR_CHECK='TRUE';
      ALLOW_CONNECT='TRUE';
      PINUSE='UNSPEC';
    'MDQ9':
      PIN_NUMBER='(Y8,0,0,0,0,0,0)';
      BIDIRECTIONAL='TRUE';
      INPUT_LOAD='(-0.01,0.01)';
      OUTPUT_LOAD='(1.0,-1.0)';
      PINUSE='BI';
    'MODT':
      PIN_NUMBER='(V11,0,0,0,0,0,0)';
      OUTPUT_LOAD='(1.0,-1.0)';
      PINUSE='OUT';
    'MCKE':
      PIN_NUMBER='(Y11,0,0,0,0,0,0)';
      OUTPUT_LOAD='(1.0,-1.0)';
      PINUSE='OUT';
    'MCKN':
      PIN_NUMBER='(AB12,0,0,0,0,0,0)';
      OUTPUT_LOAD='(1.0,-1.0)';
      PINUSE='OUT';
    'MBA2_MBG0':
      PIN_NUMBER='(W13,0,0,0,0,0,0)';
      OUTPUT_LOAD='(1.0,-1.0)';
      PINUSE='OUT';
    'MBA1':
      PIN_NUMBER='(Y13,0,0,0,0,0,0)';
      OUTPUT_LOAD='(1.0,-1.0)';
      PINUSE='OUT';
    'MBA0':
      PIN_NUMBER='(U12,0,0,0,0,0,0)';
      OUTPUT_LOAD='(1.0,-1.0)';
      PINUSE='OUT';
    'MA9':
      PIN_NUMBER='(Y16,0,0,0,0,0,0)';
      OUTPUT_LOAD='(1.0,-1.0)';
      PINUSE='OUT';
    'MA8':
      PIN_NUMBER='(W16,0,0,0,0,0,0)';
      OUTPUT_LOAD='(1.0,-1.0)';
      PINUSE='OUT';
    'MA7':
      PIN_NUMBER='(AA16,0,0,0,0,0,0)';
      OUTPUT_LOAD='(1.0,-1.0)';
      PINUSE='OUT';
    'MA6':
      PIN_NUMBER='(AB16,0,0,0,0,0,0)';
      OUTPUT_LOAD='(1.0,-1.0)';
      PINUSE='OUT';
    'MA5':
      PIN_NUMBER='(V15,0,0,0,0,0,0)';
      OUTPUT_LOAD='(1.0,-1.0)';
      PINUSE='OUT';
    'MA4':
      PIN_NUMBER='(W15,0,0,0,0,0,0)';
      OUTPUT_LOAD='(1.0,-1.0)';
      PINUSE='OUT';
    'MA3':
      PIN_NUMBER='(U14,0,0,0,0,0,0)';
      OUTPUT_LOAD='(1.0,-1.0)';
      PINUSE='OUT';
    'MA2':
      PIN_NUMBER='(W14,0,0,0,0,0,0)';
      OUTPUT_LOAD='(1.0,-1.0)';
      PINUSE='OUT';
    'MA12':
      PIN_NUMBER='(Y14,0,0,0,0,0,0)';
      OUTPUT_LOAD='(1.0,-1.0)';
      PINUSE='OUT';
    'MA1':
      PIN_NUMBER='(AB14,0,0,0,0,0,0)';
      OUTPUT_LOAD='(1.0,-1.0)';
      PINUSE='OUT';
    'MA0':
      PIN_NUMBER='(V13,0,0,0,0,0,0)';
      OUTPUT_LOAD='(1.0,-1.0)';
      PINUSE='OUT';
    'MDQS1P':
      PIN_NUMBER='(AB7,0,0,0,0,0,0)';
      BIDIRECTIONAL='TRUE';
      INPUT_LOAD='(-0.01,0.01)';
      OUTPUT_LOAD='(1.0,-1.0)';
      PINUSE='BI';
    'MDQS1N':
      PIN_NUMBER='(AB6,0,0,0,0,0,0)';
      BIDIRECTIONAL='TRUE';
      INPUT_LOAD='(-0.01,0.01)';
      OUTPUT_LOAD='(1.0,-1.0)';
      PINUSE='BI';
    'MDQS0P':
      PIN_NUMBER='(AB9,0,0,0,0,0,0)';
      BIDIRECTIONAL='TRUE';
      INPUT_LOAD='(-0.01,0.01)';
      OUTPUT_LOAD='(1.0,-1.0)';
      PINUSE='BI';
    'MDQS0N':
      PIN_NUMBER='(AB10,0,0,0,0,0,0)';
      BIDIRECTIONAL='TRUE';
      INPUT_LOAD='(-0.01,0.01)';
      OUTPUT_LOAD='(1.0,-1.0)';
      PINUSE='BI';
    'MDQ6':
      PIN_NUMBER='(W9,0,0,0,0,0,0)';
      BIDIRECTIONAL='TRUE';
      INPUT_LOAD='(-0.01,0.01)';
      OUTPUT_LOAD='(1.0,-1.0)';
      PINUSE='BI';
    'MDQ5':
      PIN_NUMBER='(Y9,0,0,0,0,0,0)';
      BIDIRECTIONAL='TRUE';
      INPUT_LOAD='(-0.01,0.01)';
      OUTPUT_LOAD='(1.0,-1.0)';
      PINUSE='BI';
    'MDQ13':
      PIN_NUMBER='(W7,0,0,0,0,0,0)';
      BIDIRECTIONAL='TRUE';
      INPUT_LOAD='(-0.01,0.01)';
      OUTPUT_LOAD='(1.0,-1.0)';
      PINUSE='BI';
    'MDQ12':
      PIN_NUMBER='(AA6,0,0,0,0,0,0)';
      BIDIRECTIONAL='TRUE';
      INPUT_LOAD='(-0.01,0.01)';
      OUTPUT_LOAD='(1.0,-1.0)';
      PINUSE='BI';
    'MDM0':
      PIN_NUMBER='(U8,0,0,0,0,0,0)';
      OUTPUT_LOAD='(1.0,-1.0)';
      PINUSE='OUT';
    'MA13':
      PIN_NUMBER='(AB15,0,0,0,0,0,0)';
      OUTPUT_LOAD='(1.0,-1.0)';
      PINUSE='OUT';
    'MA14_MACT#':
      PIN_NUMBER='(Y15,0,0,0,0,0,0)';
      OUTPUT_LOAD='(1.0,-1.0)';
      PINUSE='OUT';
    'MDQ11':
      PIN_NUMBER='(W8,0,0,0,0,0,0)';
      BIDIRECTIONAL='TRUE';
      INPUT_LOAD='(-0.01,0.01)';
      OUTPUT_LOAD='(1.0,-1.0)';
      PINUSE='BI';
    'MDQ10':
      PIN_NUMBER='(Y7,0,0,0,0,0,0)';
      BIDIRECTIONAL='TRUE';
      INPUT_LOAD='(-0.01,0.01)';
      OUTPUT_LOAD='(1.0,-1.0)';
      PINUSE='BI';
    'MWE#':
      PIN_NUMBER='(Y12,0,0,0,0,0,0)';
      OUTPUT_LOAD='(1.0,-1.0)';
      PINUSE='OUT';
    'MRAS#':
      PIN_NUMBER='(W12,0,0,0,0,0,0)';
      OUTPUT_LOAD='(1.0,-1.0)';
      PINUSE='OUT';
    'MDQ7':
      PIN_NUMBER='(V9,0,0,0,0,0,0)';
      BIDIRECTIONAL='TRUE';
      INPUT_LOAD='(-0.01,0.01)';
      OUTPUT_LOAD='(1.0,-1.0)';
      PINUSE='BI';
    'MDQ8':
      PIN_NUMBER='(AA8,0,0,0,0,0,0)';
      BIDIRECTIONAL='TRUE';
      INPUT_LOAD='(-0.01,0.01)';
      OUTPUT_LOAD='(1.0,-1.0)';
      PINUSE='BI';
    'MCKP':
      PIN_NUMBER='(AB11,0,0,0,0,0,0)';
      OUTPUT_LOAD='(1.0,-1.0)';
      PINUSE='OUT';
    'MCS#':
      PIN_NUMBER='(AA12,0,0,0,0,0,0)';
      OUTPUT_LOAD='(1.0,-1.0)';
      PINUSE='OUT';
    'GPIOB6_LPCPME#':
      PIN_NUMBER='(0,H22,0,0,0,0,0)';
      BIDIRECTIONAL='TRUE';
      INPUT_LOAD='(-0.01,0.01)';
      OUTPUT_LOAD='(1.0,-1.0)';
      PINUSE='BI';
    'GPIOB4_USBCKI':
      PIN_NUMBER='(0,J20,0,0,0,0,0)';
      BIDIRECTIONAL='TRUE';
      INPUT_LOAD='(-0.01,0.01)';
      OUTPUT_LOAD='(1.0,-1.0)';
      PINUSE='BI';
    'GPIOY4_SCL1':
      PIN_NUMBER='(0,M18,0,0,0,0,0)';
      BIDIRECTIONAL='TRUE';
      INPUT_LOAD='(-0.01,0.01)';
      OUTPUT_LOAD='(1.0,-1.0)';
      PINUSE='BI';
    'GPIOI7_SPI1MISO_VBMISO':
      PIN_NUMBER='(0,A15,0,0,0,0,0)';
      BIDIRECTIONAL='TRUE';
      INPUT_LOAD='(-0.01,0.01)';
      OUTPUT_LOAD='(1.0,-1.0)';
      PINUSE='BI';
    'DACRSET':
      PIN_NUMBER='(0,K4,0,0,0,0,0)';
      PIN_TYPE='ANALOG';
      NO_LOAD_CHECK='Both';
      NO_IO_CHECK='Both';
      NO_ASSERT_CHECK='TRUE';
      NO_DIR_CHECK='TRUE';
      ALLOW_CONNECT='TRUE';
      PINUSE='UNSPEC';
    'DACR':
      PIN_NUMBER='(0,J4,0,0,0,0,0)';
      OUTPUT_LOAD='(1.0,-1.0)';
      PINUSE='OUT';
    'DACG':
      PIN_NUMBER='(0,J3,0,0,0,0,0)';
      OUTPUT_LOAD='(1.0,-1.0)';
      PINUSE='OUT';
    'TMS':
      PIN_NUMBER='(0,C8,0,0,0,0,0)';
      BIDIRECTIONAL='TRUE';
      INPUT_LOAD='(-0.01,0.01)';
      OUTPUT_LOAD='(1.0,-1.0)';
      PINUSE='BI';
    'TDI':
      PIN_NUMBER='(0,D12,0,0,0,0,0)';
      BIDIRECTIONAL='TRUE';
      INPUT_LOAD='(-0.01,0.01)';
      OUTPUT_LOAD='(1.0,-1.0)';
      PINUSE='BI';
    'TCK':
      PIN_NUMBER='(0,C10,0,0,0,0,0)';
      BIDIRECTIONAL='TRUE';
      INPUT_LOAD='(-0.01,0.01)';
      OUTPUT_LOAD='(1.0,-1.0)';
      PINUSE='BI';
    'RTCK':
      PIN_NUMBER='(0,C9,0,0,0,0,0)';
      OUTPUT_LOAD='(1.0,-1.0)';
      PINUSE='OUT';
    'NTRST':
      PIN_NUMBER='(0,E11,0,0,0,0,0)';
      BIDIRECTIONAL='TRUE';
      INPUT_LOAD='(-0.01,0.01)';
      OUTPUT_LOAD='(1.0,-1.0)';
      PINUSE='BI';
    'GPIOI1_SYSCK':
      PIN_NUMBER='(0,E15,0,0,0,0,0)';
      BIDIRECTIONAL='TRUE';
      INPUT_LOAD='(-0.01,0.01)';
      OUTPUT_LOAD='(1.0,-1.0)';
      PINUSE='BI';
    'GPIOI0_SYSCS#':
      PIN_NUMBER='(0,C18,0,0,0,0,0)';
      BIDIRECTIONAL='TRUE';
      INPUT_LOAD='(-0.01,0.01)';
      OUTPUT_LOAD='(1.0,-1.0)';
      PINUSE='BI';
    'GPIOI5_SPI1CK_VBCK':
      PIN_NUMBER='(0,C15,0,0,0,0,0)';
      BIDIRECTIONAL='TRUE';
      INPUT_LOAD='(-0.01,0.01)';
      OUTPUT_LOAD='(1.0,-1.0)';
      PINUSE='BI';
    'GPIOI4_SPI1CS0#_VBCS#':
      PIN_NUMBER='(0,B15,0,0,0,0,0)';
      BIDIRECTIONAL='TRUE';
      INPUT_LOAD='(-0.01,0.01)';
      OUTPUT_LOAD='(1.0,-1.0)';
      PINUSE='BI';
    'GPIOI6_SPI1MOSI_VBMOSI':
      PIN_NUMBER='(0,A14,0,0,0,0,0)';
      BIDIRECTIONAL='TRUE';
      INPUT_LOAD='(-0.01,0.01)';
      OUTPUT_LOAD='(1.0,-1.0)';
      PINUSE='BI';
    'GPIOJ1_SGPMLD':
      PIN_NUMBER='(0,L2,0,0,0,0,0)';
      BIDIRECTIONAL='TRUE';
      INPUT_LOAD='(-0.01,0.01)';
      OUTPUT_LOAD='(1.0,-1.0)';
      PINUSE='BI';
    'GPIOJ0_SGPMCK':
      PIN_NUMBER='(0,R2,0,0,0,0,0)';
      BIDIRECTIONAL='TRUE';
      INPUT_LOAD='(-0.01,0.01)';
      OUTPUT_LOAD='(1.0,-1.0)';
      PINUSE='BI';
    'GPIOJ2_SGPMO':
      PIN_NUMBER='(0,N3,0,0,0,0,0)';
      BIDIRECTIONAL='TRUE';
      INPUT_LOAD='(-0.01,0.01)';
      OUTPUT_LOAD='(1.0,-1.0)';
      PINUSE='BI';
    'GPIOG3_SGPS1I1':
      PIN_NUMBER='(0,E16,0,0,0,0,0)';
      BIDIRECTIONAL='TRUE';
      INPUT_LOAD='(-0.01,0.01)';
      OUTPUT_LOAD='(1.0,-1.0)';
      PINUSE='BI';
    'GPIOG2_SGPS1I0':
      PIN_NUMBER='(0,C19,0,0,0,0,0)';
      BIDIRECTIONAL='TRUE';
      INPUT_LOAD='(-0.01,0.01)';
      OUTPUT_LOAD='(1.0,-1.0)';
      PINUSE='BI';
    'DACB':
      PIN_NUMBER='(0,J2,0,0,0,0,0)';
      OUTPUT_LOAD='(1.0,-1.0)';
      PINUSE='OUT';
    'GPIOY5_SDA1':
      PIN_NUMBER='(0,M19,0,0,0,0,0)';
      BIDIRECTIONAL='TRUE';
      INPUT_LOAD='(-0.01,0.01)';
      OUTPUT_LOAD='(1.0,-1.0)';
      PINUSE='BI';
    'TDO':
      PIN_NUMBER='(0,D11,0,0,0,0,0)';
      BIDIRECTIONAL='TRUE';
      INPUT_LOAD='(-0.01,0.01)';
      OUTPUT_LOAD='(1.0,-1.0)';
      PINUSE='BI';
    'GPIOB0':
      PIN_NUMBER='(0,K19,0,0,0,0,0)';
      BIDIRECTIONAL='TRUE';
      INPUT_LOAD='(-0.01,0.01)';
      OUTPUT_LOAD='(1.0,-1.0)';
      PINUSE='BI';
    'GPIOB1':
      PIN_NUMBER='(0,L19,0,0,0,0,0)';
      BIDIRECTIONAL='TRUE';
      INPUT_LOAD='(-0.01,0.01)';
      OUTPUT_LOAD='(1.0,-1.0)';
      PINUSE='BI';
    'GPIOB2':
      PIN_NUMBER='(0,L18,0,0,0,0,0)';
      BIDIRECTIONAL='TRUE';
      INPUT_LOAD='(-0.01,0.01)';
      OUTPUT_LOAD='(1.0,-1.0)';
      PINUSE='BI';
    'GPIOB3':
      PIN_NUMBER='(0,K18,0,0,0,0,0)';
      BIDIRECTIONAL='TRUE';
      INPUT_LOAD='(-0.01,0.01)';
      OUTPUT_LOAD='(1.0,-1.0)';
      PINUSE='BI';
    'GPIOB7':
      PIN_NUMBER='(0,H20,0,0,0,0,0)';
      BIDIRECTIONAL='TRUE';
      INPUT_LOAD='(-0.01,0.01)';
      OUTPUT_LOAD='(1.0,-1.0)';
      PINUSE='BI';
    'GPIOY6_SCL2':
      PIN_NUMBER='(0,M20,0,0,0,0,0)';
      BIDIRECTIONAL='TRUE';
      INPUT_LOAD='(-0.01,0.01)';
      OUTPUT_LOAD='(1.0,-1.0)';
      PINUSE='BI';
    'GPIOY7_SDA2':
      PIN_NUMBER='(0,P20,0,0,0,0,0)';
      BIDIRECTIONAL='TRUE';
      INPUT_LOAD='(-0.01,0.01)';
      OUTPUT_LOAD='(1.0,-1.0)';
      PINUSE='BI';
    'GPIOQ0_SCL3':
      PIN_NUMBER='(0,A11,0,0,0,0,0)';
      BIDIRECTIONAL='TRUE';
      INPUT_LOAD='(-0.01,0.01)';
      OUTPUT_LOAD='(1.0,-1.0)';
      PINUSE='BI';
    'GPIOQ1_SDA3':
      PIN_NUMBER='(0,A10,0,0,0,0,0)';
      BIDIRECTIONAL='TRUE';
      INPUT_LOAD='(-0.01,0.01)';
      OUTPUT_LOAD='(1.0,-1.0)';
      PINUSE='BI';
    'GPIOQ2_SCL4':
      PIN_NUMBER='(0,A9,0,0,0,0,0)';
      BIDIRECTIONAL='TRUE';
      INPUT_LOAD='(-0.01,0.01)';
      OUTPUT_LOAD='(1.0,-1.0)';
      PINUSE='BI';
    'GPIOQ3_SDA4':
      PIN_NUMBER='(0,B9,0,0,0,0,0)';
      BIDIRECTIONAL='TRUE';
      INPUT_LOAD='(-0.01,0.01)';
      OUTPUT_LOAD='(1.0,-1.0)';
      PINUSE='BI';
    'GPIOK0_SCL5':
      PIN_NUMBER='(0,L3,0,0,0,0,0)';
      BIDIRECTIONAL='TRUE';
      INPUT_LOAD='(-0.01,0.01)';
      OUTPUT_LOAD='(1.0,-1.0)';
      PINUSE='BI';
    'GPIOK1_SDA5':
      PIN_NUMBER='(0,L4,0,0,0,0,0)';
      BIDIRECTIONAL='TRUE';
      INPUT_LOAD='(-0.01,0.01)';
      OUTPUT_LOAD='(1.0,-1.0)';
      PINUSE='BI';
    'GPIOK2_SCL6':
      PIN_NUMBER='(0,L1,0,0,0,0,0)';
      BIDIRECTIONAL='TRUE';
      INPUT_LOAD='(-0.01,0.01)';
      OUTPUT_LOAD='(1.0,-1.0)';
      PINUSE='BI';
    'GPIOK3_SDA6':
      PIN_NUMBER='(0,N2,0,0,0,0,0)';
      BIDIRECTIONAL='TRUE';
      INPUT_LOAD='(-0.01,0.01)';
      OUTPUT_LOAD='(1.0,-1.0)';
      PINUSE='BI';
    'GPIOG1_SGPS1LD':
      PIN_NUMBER='(0,E19,0,0,0,0,0)';
      BIDIRECTIONAL='TRUE';
      INPUT_LOAD='(-0.01,0.01)';
      OUTPUT_LOAD='(1.0,-1.0)';
      PINUSE='BI';
    'GPIOG0_SGPS1CK':
      PIN_NUMBER='(0,A19,0,0,0,0,0)';
      BIDIRECTIONAL='TRUE';
      INPUT_LOAD='(-0.01,0.01)';
      OUTPUT_LOAD='(1.0,-1.0)';
      PINUSE='BI';
    'GPIOJ3_SGPMI':
      PIN_NUMBER='(0,N4,0,0,0,0,0)';
      BIDIRECTIONAL='TRUE';
      INPUT_LOAD='(-0.01,0.01)';
      OUTPUT_LOAD='(1.0,-1.0)';
      PINUSE='BI';
    'GPIOI2_SYSMOSI':
      PIN_NUMBER='(0,B16,0,0,0,0,0)';
      BIDIRECTIONAL='TRUE';
      INPUT_LOAD='(-0.01,0.01)';
      OUTPUT_LOAD='(1.0,-1.0)';
      PINUSE='BI';
    'GPIOI3_SYSMISO':
      PIN_NUMBER='(0,C16,0,0,0,0,0)';
      BIDIRECTIONAL='TRUE';
      INPUT_LOAD='(-0.01,0.01)';
      OUTPUT_LOAD='(1.0,-1.0)';
      PINUSE='BI';
    'GPIOA5_TIMER6_SDA9':
      PIN_NUMBER='(0,A13,0,0,0,0,0)';
      BIDIRECTIONAL='TRUE';
      INPUT_LOAD='(-0.01,0.01)';
      OUTPUT_LOAD='(1.0,-1.0)';
      PINUSE='BI';
    'GPIOA4_TIMER5_SCL9':
      PIN_NUMBER='(0,C14,0,0,0,0,0)';
      BIDIRECTIONAL='TRUE';
      INPUT_LOAD='(-0.01,0.01)';
      OUTPUT_LOAD='(1.0,-1.0)';
      PINUSE='BI';
    'GPIOK7_SDA8':
      PIN_NUMBER='(0,R1,0,0,0,0,0)';
      BIDIRECTIONAL='TRUE';
      INPUT_LOAD='(-0.01,0.01)';
      OUTPUT_LOAD='(1.0,-1.0)';
      PINUSE='BI';
    'GPIOK6_SCL8':
      PIN_NUMBER='(0,P2,0,0,0,0,0)';
      BIDIRECTIONAL='TRUE';
      INPUT_LOAD='(-0.01,0.01)';
      OUTPUT_LOAD='(1.0,-1.0)';
      PINUSE='BI';
    'GPIOK5_SDA7':
      PIN_NUMBER='(0,P1,0,0,0,0,0)';
      BIDIRECTIONAL='TRUE';
      INPUT_LOAD='(-0.01,0.01)';
      OUTPUT_LOAD='(1.0,-1.0)';
      PINUSE='BI';
    'GPIOK4_SCL7':
      PIN_NUMBER='(0,N1,0,0,0,0,0)';
      BIDIRECTIONAL='TRUE';
      INPUT_LOAD='(-0.01,0.01)';
      OUTPUT_LOAD='(1.0,-1.0)';
      PINUSE='BI';
    'GPIOB5_LPCPD#_LPCSMI#':
      PIN_NUMBER='(0,H21,0,0,0,0,0)';
      BIDIRECTIONAL='TRUE';
      INPUT_LOAD='(-0.01,0.01)';
      OUTPUT_LOAD='(1.0,-1.0)';
      PINUSE='BI';
    'GPIOQ4_SCL14':
      PIN_NUMBER='(0,N21,0,0,0,0,0)';
      BIDIRECTIONAL='TRUE';
      INPUT_LOAD='(-0.01,0.01)';
      OUTPUT_LOAD='(1.0,-1.0)';
      PINUSE='BI';
    'GPIOQ5_SDA14':
      PIN_NUMBER='(0,N22,0,0,0,0,0)';
      BIDIRECTIONAL='TRUE';
      INPUT_LOAD='(-0.01,0.01)';
      OUTPUT_LOAD='(1.0,-1.0)';
      PINUSE='BI';
    'GPIOC2_SD1DAT0_SCL11':
      PIN_NUMBER='(0,0,B12,0,0,0,0)';
      BIDIRECTIONAL='TRUE';
      INPUT_LOAD='(-0.01,0.01)';
      OUTPUT_LOAD='(1.0,-1.0)';
      PINUSE='BI';
    'GPIOC3_SD1DAT1_SDA11':
      PIN_NUMBER='(0,0,D9,0,0,0,0)';
      BIDIRECTIONAL='TRUE';
      INPUT_LOAD='(-0.01,0.01)';
      OUTPUT_LOAD='(1.0,-1.0)';
      PINUSE='BI';
    'GPIOC1_SD1CMD_SDA10':
      PIN_NUMBER='(0,0,A12,0,0,0,0)';
      BIDIRECTIONAL='TRUE';
      INPUT_LOAD='(-0.01,0.01)';
      OUTPUT_LOAD='(1.0,-1.0)';
      PINUSE='BI';
    'GPIOC0_SD1CLK_SCL10':
      PIN_NUMBER='(0,0,C12,0,0,0,0)';
      BIDIRECTIONAL='TRUE';
      INPUT_LOAD='(-0.01,0.01)';
      OUTPUT_LOAD='(1.0,-1.0)';
      PINUSE='BI';
    'GPIOA0_MAC1LINK':
      PIN_NUMBER='(0,0,B14,0,0,0,0)';
      BIDIRECTIONAL='TRUE';
      INPUT_LOAD='(-0.01,0.01)';
      OUTPUT_LOAD='(1.0,-1.0)';
      PINUSE='BI';
    'GPIOA1_MAC2LINK':
      PIN_NUMBER='(0,0,D14,0,0,0,0)';
      BIDIRECTIONAL='TRUE';
      INPUT_LOAD='(-0.01,0.01)';
      OUTPUT_LOAD='(1.0,-1.0)';
      PINUSE='BI';
    'GPIOY3_SIOONCTRL#':
      PIN_NUMBER='(0,0,P21,0,0,0,0)';
      BIDIRECTIONAL='TRUE';
      INPUT_LOAD='(-0.01,0.01)';
      OUTPUT_LOAD='(1.0,-1.0)';
      PINUSE='BI';
    'GPIOG6_SGPS2I0_SALT3':
      PIN_NUMBER='(0,0,D15,0,0,0,0)';
      BIDIRECTIONAL='TRUE';
      INPUT_LOAD='(-0.01,0.01)';
      OUTPUT_LOAD='(1.0,-1.0)';
      PINUSE='BI';
    'GPIOC6_SD1CD#_SCL13':
      PIN_NUMBER='(0,0,C11,0,0,0,0)';
      BIDIRECTIONAL='TRUE';
      INPUT_LOAD='(-0.01,0.01)';
      OUTPUT_LOAD='(1.0,-1.0)';
      PINUSE='BI';
    'GPIOC4_SD1DAT2_SCL12':
      PIN_NUMBER='(0,0,D10,0,0,0,0)';
      BIDIRECTIONAL='TRUE';
      INPUT_LOAD='(-0.01,0.01)';
      OUTPUT_LOAD='(1.0,-1.0)';
      PINUSE='BI';
    'GPIOG7_SGPS2I1_SALT4':
      PIN_NUMBER='(0,0,E14,0,0,0,0)';
      BIDIRECTIONAL='TRUE';
      INPUT_LOAD='(-0.01,0.01)';
      OUTPUT_LOAD='(1.0,-1.0)';
      PINUSE='BI';
    'GPIOA2_TIMER3_SPI1CS1#':
      PIN_NUMBER='(0,0,D13,0,0,0,0)';
      BIDIRECTIONAL='TRUE';
      INPUT_LOAD='(-0.01,0.01)';
      OUTPUT_LOAD='(1.0,-1.0)';
      PINUSE='BI';
    'GPIOG5_SGPS2LD_SALT2':
      PIN_NUMBER='(0,0,D16,0,0,0,0)';
      BIDIRECTIONAL='TRUE';
      INPUT_LOAD='(-0.01,0.01)';
      OUTPUT_LOAD='(1.0,-1.0)';
      PINUSE='BI';
    'GPIOG4_SGPS2CK_SALT1':
      PIN_NUMBER='(0,0,E17,0,0,0,0)';
      BIDIRECTIONAL='TRUE';
      INPUT_LOAD='(-0.01,0.01)';
      OUTPUT_LOAD='(1.0,-1.0)';
      PINUSE='BI';
    'GPIOF5_NRTS4_LHFRAME#':
      PIN_NUMBER='(0,0,H19,0,0,0,0)';
      BIDIRECTIONAL='TRUE';
      INPUT_LOAD='(-0.01,0.01)';
      OUTPUT_LOAD='(1.0,-1.0)';
      PINUSE='BI';
    'GPIOF7_RXD4_LHRST#':
      PIN_NUMBER='(0,0,H18,0,0,0,0)';
      BIDIRECTIONAL='TRUE';
      INPUT_LOAD='(-0.01,0.01)';
      OUTPUT_LOAD='(1.0,-1.0)';
      PINUSE='BI';
    'GPIOL2_NDSR1':
      PIN_NUMBER='(0,0,U1,0,0,0,0)';
      BIDIRECTIONAL='TRUE';
      INPUT_LOAD='(-0.01,0.01)';
      OUTPUT_LOAD='(1.0,-1.0)';
      PINUSE='BI';
    'GPIOL3_NRI1_VPIHS':
      PIN_NUMBER='(0,0,U2,0,0,0,0)';
      BIDIRECTIONAL='TRUE';
      INPUT_LOAD='(-0.01,0.01)';
      OUTPUT_LOAD='(1.0,-1.0)';
      PINUSE='BI';
    'GPIOL4_NDTR1_VPIVS':
      PIN_NUMBER='(0,0,P4,0,0,0,0)';
      BIDIRECTIONAL='TRUE';
      INPUT_LOAD='(-0.01,0.01)';
      OUTPUT_LOAD='(1.0,-1.0)';
      PINUSE='BI';
    'PEREFCLKN':
      PIN_NUMBER='(0,0,K22,0,0,0,0)';
      INPUT_LOAD='(-0.01,0.01)';
      PINUSE='IN';
    'PEREFCLKP':
      PIN_NUMBER='(0,0,K21,0,0,0,0)';
      INPUT_LOAD='(-0.01,0.01)';
      PINUSE='IN';
    'RXD5':
      PIN_NUMBER='(0,0,K2,0,0,0,0)';
      INPUT_LOAD='(-0.01,0.01)';
      PINUSE='IN';
    'PECI':
      PIN_NUMBER='(0,0,AB18,0,0,0,0)';
      BIDIRECTIONAL='TRUE';
      INPUT_LOAD='(-0.01,0.01)';
      OUTPUT_LOAD='(1.0,-1.0)';
      PINUSE='BI';
    'GPIOD3_SD2DAT1':
      PIN_NUMBER='(0,0,D20,0,0,0,0)';
      BIDIRECTIONAL='TRUE';
      INPUT_LOAD='(-0.01,0.01)';
      OUTPUT_LOAD='(1.0,-1.0)';
      PINUSE='BI';
    'GPIOD4_SD2DAT2':
      PIN_NUMBER='(0,0,D21,0,0,0,0)';
      BIDIRECTIONAL='TRUE';
      INPUT_LOAD='(-0.01,0.01)';
      OUTPUT_LOAD='(1.0,-1.0)';
      PINUSE='BI';
    'GPIOD1_SD2CMD':
      PIN_NUMBER='(0,0,E21,0,0,0,0)';
      BIDIRECTIONAL='TRUE';
      INPUT_LOAD='(-0.01,0.01)';
      OUTPUT_LOAD='(1.0,-1.0)';
      PINUSE='BI';
    'CLKIN':
      PIN_NUMBER='(0,0,W18,0,0,0,0)';
      INPUT_LOAD='(-0.01,0.01)';
      PINUSE='IN';
    'SRST#':
      PIN_NUMBER='(0,0,U18,0,0,0,0)';
      INPUT_LOAD='(-0.01,0.01)';
      PINUSE='IN';
    'GPIOA3_TIMER4':
      PIN_NUMBER='(0,0,E13,0,0,0,0)';
      BIDIRECTIONAL='TRUE';
      INPUT_LOAD='(-0.01,0.01)';
      OUTPUT_LOAD='(1.0,-1.0)';
      PINUSE='BI';
    'PERST#':
      PIN_NUMBER='(0,0,L20,0,0,0,0)';
      BIDIRECTIONAL='TRUE';
      INPUT_LOAD='(-0.01,0.01)';
      OUTPUT_LOAD='(1.0,-1.0)';
      PINUSE='BI';
    'PERXN':
      PIN_NUMBER='(0,0,M22,0,0,0,0)';
      INPUT_LOAD='(-0.01,0.01)';
      PINUSE='IN';
    'PERXP':
      PIN_NUMBER='(0,0,M21,0,0,0,0)';
      INPUT_LOAD='(-0.01,0.01)';
      PINUSE='IN';
    'GPIOM0_NCTS2_VPIB2':
      PIN_NUMBER='(0,0,Y1,0,0,0,0)';
      BIDIRECTIONAL='TRUE';
      INPUT_LOAD='(-0.01,0.01)';
      OUTPUT_LOAD='(1.0,-1.0)';
      PINUSE='BI';
    'GPIOM1_NDCD2_VPIB3':
      PIN_NUMBER='(0,0,AB2,0,0,0,0)';
      BIDIRECTIONAL='TRUE';
      INPUT_LOAD='(-0.01,0.01)';
      OUTPUT_LOAD='(1.0,-1.0)';
      PINUSE='BI';
    'GPIOM2_NDSR2_VPIB4':
      PIN_NUMBER='(0,0,AA1,0,0,0,0)';
      BIDIRECTIONAL='TRUE';
      INPUT_LOAD='(-0.01,0.01)';
      OUTPUT_LOAD='(1.0,-1.0)';
      PINUSE='BI';
    'GPIOM3_NRI2_VPIB5':
      PIN_NUMBER='(0,0,Y2,0,0,0,0)';
      BIDIRECTIONAL='TRUE';
      INPUT_LOAD='(-0.01,0.01)';
      OUTPUT_LOAD='(1.0,-1.0)';
      PINUSE='BI';
    'GPIOM4_NDTR2_VPIB6':
      PIN_NUMBER='(0,0,AA2,0,0,0,0)';
      BIDIRECTIONAL='TRUE';
      INPUT_LOAD='(-0.01,0.01)';
      OUTPUT_LOAD='(1.0,-1.0)';
      PINUSE='BI';
    'GPIOM5_NRTS2_VPIB7':
      PIN_NUMBER='(0,0,P5,0,0,0,0)';
      BIDIRECTIONAL='TRUE';
      INPUT_LOAD='(-0.01,0.01)';
      OUTPUT_LOAD='(1.0,-1.0)';
      PINUSE='BI';
    'GPIOM6_TXD2_VPIB8':
      PIN_NUMBER='(0,0,R5,0,0,0,0)';
      BIDIRECTIONAL='TRUE';
      INPUT_LOAD='(-0.01,0.01)';
      OUTPUT_LOAD='(1.0,-1.0)';
      PINUSE='BI';
    'GPIOM7_RXD2_VPIB9':
      PIN_NUMBER='(0,0,T5,0,0,0,0)';
      BIDIRECTIONAL='TRUE';
      INPUT_LOAD='(-0.01,0.01)';
      OUTPUT_LOAD='(1.0,-1.0)';
      PINUSE='BI';
    'GPIOL1_NDCD1_VPIDE':
      PIN_NUMBER='(0,0,T1,0,0,0,0)';
      BIDIRECTIONAL='TRUE';
      INPUT_LOAD='(-0.01,0.01)';
      OUTPUT_LOAD='(1.0,-1.0)';
      PINUSE='BI';
    'GPIOL5_NRTS1_VPICLK':
      PIN_NUMBER='(0,0,P3,0,0,0,0)';
      BIDIRECTIONAL='TRUE';
      INPUT_LOAD='(-0.01,0.01)';
      OUTPUT_LOAD='(1.0,-1.0)';
      PINUSE='BI';
    'GPIOL7_RXD1':
      PIN_NUMBER='(0,0,W1,0,0,0,0)';
      BIDIRECTIONAL='TRUE';
      INPUT_LOAD='(-0.01,0.01)';
      OUTPUT_LOAD='(1.0,-1.0)';
      PINUSE='BI';
    'GPIOF0_NCTS4_LHAD0':
      PIN_NUMBER='(0,0,J19,0,0,0,0)';
      BIDIRECTIONAL='TRUE';
      INPUT_LOAD='(-0.01,0.01)';
      OUTPUT_LOAD='(1.0,-1.0)';
      PINUSE='BI';
    'GPIOF1_NDCD4_LHAD1':
      PIN_NUMBER='(0,0,J18,0,0,0,0)';
      BIDIRECTIONAL='TRUE';
      INPUT_LOAD='(-0.01,0.01)';
      OUTPUT_LOAD='(1.0,-1.0)';
      PINUSE='BI';
    'GPIOF2_NDSR4_LHAD2':
      PIN_NUMBER='(0,0,B22,0,0,0,0)';
      BIDIRECTIONAL='TRUE';
      INPUT_LOAD='(-0.01,0.01)';
      OUTPUT_LOAD='(1.0,-1.0)';
      PINUSE='BI';
    'GPIOE2_NDSR3':
      PIN_NUMBER='(0,0,F18,0,0,0,0)';
      BIDIRECTIONAL='TRUE';
      INPUT_LOAD='(-0.01,0.01)';
      OUTPUT_LOAD='(1.0,-1.0)';
      PINUSE='BI';
    'GPIOE3_NRI3':
      PIN_NUMBER='(0,0,F17,0,0,0,0)';
      BIDIRECTIONAL='TRUE';
      INPUT_LOAD='(-0.01,0.01)';
      OUTPUT_LOAD='(1.0,-1.0)';
      PINUSE='BI';
    'GPIOE4_NDTR3':
      PIN_NUMBER='(0,0,E18,0,0,0,0)';
      BIDIRECTIONAL='TRUE';
      INPUT_LOAD='(-0.01,0.01)';
      OUTPUT_LOAD='(1.0,-1.0)';
      PINUSE='BI';
    'GPIOE6_TXD3':
      PIN_NUMBER='(0,0,A20,0,0,0,0)';
      BIDIRECTIONAL='TRUE';
      INPUT_LOAD='(-0.01,0.01)';
      OUTPUT_LOAD='(1.0,-1.0)';
      PINUSE='BI';
    'GPIOE7_RXD3':
      PIN_NUMBER='(0,0,B19,0,0,0,0)';
      BIDIRECTIONAL='TRUE';
      INPUT_LOAD='(-0.01,0.01)';
      OUTPUT_LOAD='(1.0,-1.0)';
      PINUSE='BI';
    'TXD5':
      PIN_NUMBER='(0,0,K1,0,0,0,0)';
      OUTPUT_LOAD='(1.0,-1.0)';
      PINUSE='OUT';
    'PEREXT':
      PIN_NUMBER='(0,0,K20,0,0,0,0)';
      PIN_TYPE='ANALOG';
      NO_LOAD_CHECK='Both';
      NO_IO_CHECK='Both';
      NO_ASSERT_CHECK='TRUE';
      NO_DIR_CHECK='TRUE';
      ALLOW_CONNECT='TRUE';
      PINUSE='UNSPEC';
    'PETXN':
      PIN_NUMBER='(0,0,L22,0,0,0,0)';
      OUTPUT_LOAD='(1.0,-1.0)';
      PINUSE='OUT';
    'PETXP':
      PIN_NUMBER='(0,0,L21,0,0,0,0)';
      OUTPUT_LOAD='(1.0,-1.0)';
      PINUSE='OUT';
    'GPIOE5_NRTS3':
      PIN_NUMBER='(0,0,D19,0,0,0,0)';
      BIDIRECTIONAL='TRUE';
      INPUT_LOAD='(-0.01,0.01)';
      OUTPUT_LOAD='(1.0,-1.0)';
      PINUSE='BI';
    'GPIOE1_NDCD3':
      PIN_NUMBER='(0,0,C20,0,0,0,0)';
      BIDIRECTIONAL='TRUE';
      INPUT_LOAD='(-0.01,0.01)';
      OUTPUT_LOAD='(1.0,-1.0)';
      PINUSE='BI';
    'GPIOE0_NCTS3':
      PIN_NUMBER='(0,0,B20,0,0,0,0)';
      BIDIRECTIONAL='TRUE';
      INPUT_LOAD='(-0.01,0.01)';
      OUTPUT_LOAD='(1.0,-1.0)';
      PINUSE='BI';
    'GPIOD0_SD2CLK':
      PIN_NUMBER='(0,0,F19,0,0,0,0)';
      BIDIRECTIONAL='TRUE';
      INPUT_LOAD='(-0.01,0.01)';
      OUTPUT_LOAD='(1.0,-1.0)';
      PINUSE='BI';
    'GPIOD2_SD2DAT0':
      PIN_NUMBER='(0,0,F20,0,0,0,0)';
      BIDIRECTIONAL='TRUE';
      INPUT_LOAD='(-0.01,0.01)';
      OUTPUT_LOAD='(1.0,-1.0)';
      PINUSE='BI';
    'GPIOD7_SD2WP#':
      PIN_NUMBER='(0,0,C21,0,0,0,0)';
      BIDIRECTIONAL='TRUE';
      INPUT_LOAD='(-0.01,0.01)';
      OUTPUT_LOAD='(1.0,-1.0)';
      PINUSE='BI';
    'GPIOC7_SD1WP#_SDA13':
      PIN_NUMBER='(0,0,B11,0,0,0,0)';
      BIDIRECTIONAL='TRUE';
      INPUT_LOAD='(-0.01,0.01)';
      OUTPUT_LOAD='(1.0,-1.0)';
      PINUSE='BI';
    'GPIOC5_SD1DAT3_SDA12':
      PIN_NUMBER='(0,0,E12,0,0,0,0)';
      BIDIRECTIONAL='TRUE';
      INPUT_LOAD='(-0.01,0.01)';
      OUTPUT_LOAD='(1.0,-1.0)';
      PINUSE='BI';
    'GPIOL0_NCTS1':
      PIN_NUMBER='(0,0,T2,0,0,0,0)';
      BIDIRECTIONAL='TRUE';
      INPUT_LOAD='(-0.01,0.01)';
      OUTPUT_LOAD='(1.0,-1.0)';
      PINUSE='BI';
    'GPIOF3_NRI4_LHAD3':
      PIN_NUMBER='(0,0,B21,0,0,0,0)';
      BIDIRECTIONAL='TRUE';
      INPUT_LOAD='(-0.01,0.01)';
      OUTPUT_LOAD='(1.0,-1.0)';
      PINUSE='BI';
    'GPIOF4_NDTR4_LHCLK':
      PIN_NUMBER='(0,0,A21,0,0,0,0)';
      BIDIRECTIONAL='TRUE';
      INPUT_LOAD='(-0.01,0.01)';
      OUTPUT_LOAD='(1.0,-1.0)';
      PINUSE='BI';
    'GPIOF6_TXD4_LHSIRQ#':
      PIN_NUMBER='(0,0,G17,0,0,0,0)';
      BIDIRECTIONAL='TRUE';
      INPUT_LOAD='(-0.01,0.01)';
      OUTPUT_LOAD='(1.0,-1.0)';
      PINUSE='BI';
    'GPIOL6_TXD1':
      PIN_NUMBER='(0,0,V1,0,0,0,0)';
      BIDIRECTIONAL='TRUE';
      INPUT_LOAD='(-0.01,0.01)';
      OUTPUT_LOAD='(1.0,-1.0)';
      PINUSE='BI';
    'GPIOD6_SD2CD#':
      PIN_NUMBER='(0,0,G18,0,0,0,0)';
      BIDIRECTIONAL='TRUE';
      INPUT_LOAD='(-0.01,0.01)';
      OUTPUT_LOAD='(1.0,-1.0)';
      PINUSE='BI';
    'GPIOD5_SD2DAT3':
      PIN_NUMBER='(0,0,E20,0,0,0,0)';
      BIDIRECTIONAL='TRUE';
      INPUT_LOAD='(-0.01,0.01)';
      OUTPUT_LOAD='(1.0,-1.0)';
      PINUSE='BI';
    'USB2BVRES':
      PIN_NUMBER='(0,0,0,B7,0,0,0)';
      PIN_TYPE='ANALOG';
      NO_LOAD_CHECK='Both';
      NO_IO_CHECK='Both';
      NO_ASSERT_CHECK='TRUE';
      NO_DIR_CHECK='TRUE';
      ALLOW_CONNECT='TRUE';
      PINUSE='UNSPEC';
    'USB2AVRES':
      PIN_NUMBER='(0,0,0,B8,0,0,0)';
      PIN_TYPE='ANALOG';
      NO_LOAD_CHECK='Both';
      NO_IO_CHECK='Both';
      NO_ASSERT_CHECK='TRUE';
      NO_DIR_CHECK='TRUE';
      ALLOW_CONNECT='TRUE';
      PINUSE='UNSPEC';
    'GPIOH0_NCTS6':
      PIN_NUMBER='(0,0,0,A18,0,0,0)';
      BIDIRECTIONAL='TRUE';
      INPUT_LOAD='(-0.01,0.01)';
      OUTPUT_LOAD='(1.0,-1.0)';
      PINUSE='BI';
    'GPIOH2_NDSR6':
      PIN_NUMBER='(0,0,0,D17,0,0,0)';
      BIDIRECTIONAL='TRUE';
      INPUT_LOAD='(-0.01,0.01)';
      OUTPUT_LOAD='(1.0,-1.0)';
      PINUSE='BI';
    'GPIOH1_NDCD6':
      PIN_NUMBER='(0,0,0,B18,0,0,0)';
      BIDIRECTIONAL='TRUE';
      INPUT_LOAD='(-0.01,0.01)';
      OUTPUT_LOAD='(1.0,-1.0)';
      PINUSE='BI';
    'GPIOH4_NDTR6':
      PIN_NUMBER='(0,0,0,A17,0,0,0)';
      BIDIRECTIONAL='TRUE';
      INPUT_LOAD='(-0.01,0.01)';
      OUTPUT_LOAD='(1.0,-1.0)';
      PINUSE='BI';
    'GPIOH3_NRI6':
      PIN_NUMBER='(0,0,0,C17,0,0,0)';
      BIDIRECTIONAL='TRUE';
      INPUT_LOAD='(-0.01,0.01)';
      OUTPUT_LOAD='(1.0,-1.0)';
      PINUSE='BI';
    'GPIOH5_NRTS6':
      PIN_NUMBER='(0,0,0,B17,0,0,0)';
      BIDIRECTIONAL='TRUE';
      INPUT_LOAD='(-0.01,0.01)';
      OUTPUT_LOAD='(1.0,-1.0)';
      PINUSE='BI';
    'GPIOH7_RXD6':
      PIN_NUMBER='(0,0,0,D18,0,0,0)';
      BIDIRECTIONAL='TRUE';
      INPUT_LOAD='(-0.01,0.01)';
      OUTPUT_LOAD='(1.0,-1.0)';
      PINUSE='BI';
    'GPIOH6_TXD6':
      PIN_NUMBER='(0,0,0,A16,0,0,0)';
      BIDIRECTIONAL='TRUE';
      INPUT_LOAD='(-0.01,0.01)';
      OUTPUT_LOAD='(1.0,-1.0)';
      PINUSE='BI';
    'GPIOS0_VPOB2_SPI2CS1#':
      PIN_NUMBER='(0,0,0,V20,0,0,0)';
      BIDIRECTIONAL='TRUE';
      INPUT_LOAD='(-0.01,0.01)';
      OUTPUT_LOAD='(1.0,-1.0)';
      PINUSE='BI';
    'GPIOS2_VPOB4_SALT5':
      PIN_NUMBER='(0,0,0,R18,0,0,0)';
      BIDIRECTIONAL='TRUE';
      INPUT_LOAD='(-0.01,0.01)';
      OUTPUT_LOAD='(1.0,-1.0)';
      PINUSE='BI';
    'GPIOZ1_VPOG3_NORA1_SIOPWRGD':
      PIN_NUMBER='(0,0,0,AB20,0,0,0)';
      BIDIRECTIONAL='TRUE';
      INPUT_LOAD='(-0.01,0.01)';
      OUTPUT_LOAD='(1.0,-1.0)';
      PINUSE='BI';
    'GPIOZ2_VPOG4_NORA2_SIOPBO#':
      PIN_NUMBER='(0,0,0,AB21,0,0,0)';
      BIDIRECTIONAL='TRUE';
      INPUT_LOAD='(-0.01,0.01)';
      OUTPUT_LOAD='(1.0,-1.0)';
      PINUSE='BI';
    'GPIOZ3_VPOG5_NORA3_SIOSCI#':
      PIN_NUMBER='(0,0,0,AA21,0,0,0)';
      BIDIRECTIONAL='TRUE';
      INPUT_LOAD='(-0.01,0.01)';
      OUTPUT_LOAD='(1.0,-1.0)';
      PINUSE='BI';
    'GPIOZ4_VPOG6_NORA4':
      PIN_NUMBER='(0,0,0,U21,0,0,0)';
      BIDIRECTIONAL='TRUE';
      INPUT_LOAD='(-0.01,0.01)';
      OUTPUT_LOAD='(1.0,-1.0)';
      PINUSE='BI';
    'GPIOZ5_VPOG7_NORA5':
      PIN_NUMBER='(0,0,0,W22,0,0,0)';
      BIDIRECTIONAL='TRUE';
      INPUT_LOAD='(-0.01,0.01)';
      OUTPUT_LOAD='(1.0,-1.0)';
      PINUSE='BI';
    'GPIOZ6_VPOG8_NORA6':
      PIN_NUMBER='(0,0,0,V22,0,0,0)';
      BIDIRECTIONAL='TRUE';
      INPUT_LOAD='(-0.01,0.01)';
      OUTPUT_LOAD='(1.0,-1.0)';
      PINUSE='BI';
    'GPIOZ7_VPOG9_NORA7':
      PIN_NUMBER='(0,0,0,W21,0,0,0)';
      BIDIRECTIONAL='TRUE';
      INPUT_LOAD='(-0.01,0.01)';
      OUTPUT_LOAD='(1.0,-1.0)';
      PINUSE='BI';
    'GPIOAA0_VPOR2_NORD0_SALT7':
      PIN_NUMBER='(0,0,0,Y21,0,0,0)';
      BIDIRECTIONAL='TRUE';
      INPUT_LOAD='(-0.01,0.01)';
      OUTPUT_LOAD='(1.0,-1.0)';
      PINUSE='BI';
    'GPIOS3_VPOB5_SALT6':
      PIN_NUMBER='(0,0,0,P18,0,0,0)';
      BIDIRECTIONAL='TRUE';
      INPUT_LOAD='(-0.01,0.01)';
      OUTPUT_LOAD='(1.0,-1.0)';
      PINUSE='BI';
    'GPIOS7_VPOB9':
      PIN_NUMBER='(0,0,0,AA20,0,0,0)';
      BIDIRECTIONAL='TRUE';
      INPUT_LOAD='(-0.01,0.01)';
      OUTPUT_LOAD='(1.0,-1.0)';
      PINUSE='BI';
    'GPIOZ0_VPOG2_NORA0_SIOPBI#':
      PIN_NUMBER='(0,0,0,Y20,0,0,0)';
      BIDIRECTIONAL='TRUE';
      INPUT_LOAD='(-0.01,0.01)';
      OUTPUT_LOAD='(1.0,-1.0)';
      PINUSE='BI';
    'GPIOAA2_VPOR4_NORD2_SALT9':
      PIN_NUMBER='(0,0,0,Y22,0,0,0)';
      BIDIRECTIONAL='TRUE';
      INPUT_LOAD='(-0.01,0.01)';
      OUTPUT_LOAD='(1.0,-1.0)';
      PINUSE='BI';
    'USB2A_DP':
      PIN_NUMBER='(0,0,0,A7,0,0,0)';
      BIDIRECTIONAL='TRUE';
      INPUT_LOAD='(-0.01,0.01)';
      OUTPUT_LOAD='(1.0,-1.0)';
      PINUSE='BI';
    'USB2A_DN':
      PIN_NUMBER='(0,0,0,A8,0,0,0)';
      BIDIRECTIONAL='TRUE';
      INPUT_LOAD='(-0.01,0.01)';
      OUTPUT_LOAD='(1.0,-1.0)';
      PINUSE='BI';
    'USB2B_DP':
      PIN_NUMBER='(0,0,0,B6,0,0,0)';
      BIDIRECTIONAL='TRUE';
      INPUT_LOAD='(-0.01,0.01)';
      OUTPUT_LOAD='(1.0,-1.0)';
      PINUSE='BI';
    'USB2B_DN':
      PIN_NUMBER='(0,0,0,A6,0,0,0)';
      BIDIRECTIONAL='TRUE';
      INPUT_LOAD='(-0.01,0.01)';
      OUTPUT_LOAD='(1.0,-1.0)';
      PINUSE='BI';
    'GPIOS6_VPOB8':
      PIN_NUMBER='(0,0,0,U20,0,0,0)';
      BIDIRECTIONAL='TRUE';
      INPUT_LOAD='(-0.01,0.01)';
      OUTPUT_LOAD='(1.0,-1.0)';
      PINUSE='BI';
    'GPIOS5_VPOB7':
      PIN_NUMBER='(0,0,0,W20,0,0,0)';
      BIDIRECTIONAL='TRUE';
      INPUT_LOAD='(-0.01,0.01)';
      OUTPUT_LOAD='(1.0,-1.0)';
      PINUSE='BI';
    'GPIOS4_VPOB6':
      PIN_NUMBER='(0,0,0,R19,0,0,0)';
      BIDIRECTIONAL='TRUE';
      INPUT_LOAD='(-0.01,0.01)';
      OUTPUT_LOAD='(1.0,-1.0)';
      PINUSE='BI';
    'GPIOS1_VPOB3_BMCINT':
      PIN_NUMBER='(0,0,0,U19,0,0,0)';
      BIDIRECTIONAL='TRUE';
      INPUT_LOAD='(-0.01,0.01)';
      OUTPUT_LOAD='(1.0,-1.0)';
      PINUSE='BI';
    'GPIOAA1_VPOR3_NORD1_SALT8':
      PIN_NUMBER='(0,0,0,V21,0,0,0)';
      BIDIRECTIONAL='TRUE';
      INPUT_LOAD='(-0.01,0.01)';
      OUTPUT_LOAD='(1.0,-1.0)';
      PINUSE='BI';
    'GPIOAA7_VPOR9_NORD7_SALT14':
      PIN_NUMBER='(0,0,0,P19,0,0,0)';
      BIDIRECTIONAL='TRUE';
      INPUT_LOAD='(-0.01,0.01)';
      OUTPUT_LOAD='(1.0,-1.0)';
      PINUSE='BI';
    'GPIOAA6_VPOR8_NORD6_SALT13':
      PIN_NUMBER='(0,0,0,N18,0,0,0)';
      BIDIRECTIONAL='TRUE';
      INPUT_LOAD='(-0.01,0.01)';
      OUTPUT_LOAD='(1.0,-1.0)';
      PINUSE='BI';
    'GPIOAA5_VPOR7_NORD5_SALT12':
      PIN_NUMBER='(0,0,0,T20,0,0,0)';
      BIDIRECTIONAL='TRUE';
      INPUT_LOAD='(-0.01,0.01)';
      OUTPUT_LOAD='(1.0,-1.0)';
      PINUSE='BI';
    'GPIOAA4_VPOR6_NORD4_SALT11':
      PIN_NUMBER='(0,0,0,U22,0,0,0)';
      BIDIRECTIONAL='TRUE';
      INPUT_LOAD='(-0.01,0.01)';
      OUTPUT_LOAD='(1.0,-1.0)';
      PINUSE='BI';
    'GPIOAA3_VPOR5_NORD3_SALT10':
      PIN_NUMBER='(0,0,0,AA22,0,0,0)';
      BIDIRECTIONAL='TRUE';
      INPUT_LOAD='(-0.01,0.01)';
      OUTPUT_LOAD='(1.0,-1.0)';
      PINUSE='BI';
    'GPIOAC7_ESPIRST#_LPCRST#':
      PIN_NUMBER='(0,0,0,0,G22,0,0)';
      BIDIRECTIONAL='TRUE';
      INPUT_LOAD='(-0.01,0.01)';
      OUTPUT_LOAD='(1.0,-1.0)';
      PINUSE='BI';
    'ENTEST':
      PIN_NUMBER='(0,0,0,0,K3,0,0)';
      INPUT_LOAD='(-0.01,0.01)';
      PINUSE='IN';
    'EXTRST#':
      PIN_NUMBER='(0,0,0,0,V18,0,0)';
      INPUT_LOAD='(-0.01,0.01)';
      PINUSE='IN';
    'GPIOQ6_OSCCLK':
      PIN_NUMBER='(0,0,0,0,B10,0,0)';
      BIDIRECTIONAL='TRUE';
      INPUT_LOAD='(-0.01,0.01)';
      OUTPUT_LOAD='(1.0,-1.0)';
      PINUSE='BI';
    'GPIOQ7_PEWAKE#':
      PIN_NUMBER='(0,0,0,0,N20,0,0)';
      BIDIRECTIONAL='TRUE';
      INPUT_LOAD='(-0.01,0.01)';
      OUTPUT_LOAD='(1.0,-1.0)';
      PINUSE='BI';
    'GPIOR5_SPI2MISO':
      PIN_NUMBER='(0,0,0,0,V19,0,0)';
      BIDIRECTIONAL='TRUE';
      INPUT_LOAD='(-0.01,0.01)';
      OUTPUT_LOAD='(1.0,-1.0)';
      PINUSE='BI';
    'GPIOR2_SPI2CS0#':
      PIN_NUMBER='(0,0,0,0,T17,0,0)';
      BIDIRECTIONAL='TRUE';
      INPUT_LOAD='(-0.01,0.01)';
      OUTPUT_LOAD='(1.0,-1.0)';
      PINUSE='BI';
    'GPIOR1_FWSPICS2#':
      PIN_NUMBER='(0,0,0,0,T19,0,0)';
      BIDIRECTIONAL='TRUE';
      INPUT_LOAD='(-0.01,0.01)';
      OUTPUT_LOAD='(1.0,-1.0)';
      PINUSE='BI';
    'GPIOR0_FWSPICS1#':
      PIN_NUMBER='(0,0,0,0,AA19,0,0)';
      BIDIRECTIONAL='TRUE';
      INPUT_LOAD='(-0.01,0.01)';
      OUTPUT_LOAD='(1.0,-1.0)';
      PINUSE='BI';
    'MRESET#':
      PIN_NUMBER='(0,0,0,0,AB17,0,0)';
      OUTPUT_LOAD='(1.0,-1.0)';
      PINUSE='OUT';
    'MALERT#':
      PIN_NUMBER='(0,0,0,0,U16,0,0)';
      BIDIRECTIONAL='TRUE';
      INPUT_LOAD='(-0.01,0.01)';
      OUTPUT_LOAD='(1.0,-1.0)';
      PINUSE='BI';
    'HBLED#':
      PIN_NUMBER='(0,0,0,0,Y18,0,0)';
      OUTPUT_LOAD='(1.0,-1.0)';
      PINUSE='OUT';
    'GPIOJ4_VGAHS':
      PIN_NUMBER='(0,0,0,0,N5,0,0)';
      BIDIRECTIONAL='TRUE';
      INPUT_LOAD='(-0.01,0.01)';
      OUTPUT_LOAD='(1.0,-1.0)';
      PINUSE='BI';
    'FWSPIMOSI':
      PIN_NUMBER='(0,0,0,0,U17,0,0)';
      BIDIRECTIONAL='TRUE';
      INPUT_LOAD='(-0.01,0.01)';
      OUTPUT_LOAD='(1.0,-1.0)';
      PINUSE='BI';
    'FWSPICK':
      PIN_NUMBER='(0,0,0,0,AA18,0,0)';
      BIDIRECTIONAL='TRUE';
      INPUT_LOAD='(-0.01,0.01)';
      OUTPUT_LOAD='(1.0,-1.0)';
      PINUSE='BI';
    'GPIOJ7_DDCDAT':
      PIN_NUMBER='(0,0,0,0,T3,0,0)';
      BIDIRECTIONAL='TRUE';
      INPUT_LOAD='(-0.01,0.01)';
      OUTPUT_LOAD='(1.0,-1.0)';
      PINUSE='BI';
    'GPIOJ6_DDCCLK':
      PIN_NUMBER='(0,0,0,0,R3,0,0)';
      BIDIRECTIONAL='TRUE';
      INPUT_LOAD='(-0.01,0.01)';
      OUTPUT_LOAD='(1.0,-1.0)';
      PINUSE='BI';
    'GPIOJ5_VGAVS':
      PIN_NUMBER='(0,0,0,0,R4,0,0)';
      BIDIRECTIONAL='TRUE';
      INPUT_LOAD='(-0.01,0.01)';
      OUTPUT_LOAD='(1.0,-1.0)';
      PINUSE='BI';
    'GPIOAB3_VPOCLK_WDTRST2':
      PIN_NUMBER='(0,0,0,0,R20,0,0)';
      BIDIRECTIONAL='TRUE';
      INPUT_LOAD='(-0.01,0.01)';
      OUTPUT_LOAD='(1.0,-1.0)';
      PINUSE='BI';
    'GPIOAB2_VPOVS_WDTRST1':
      PIN_NUMBER='(0,0,0,0,T22,0,0)';
      BIDIRECTIONAL='TRUE';
      INPUT_LOAD='(-0.01,0.01)';
      OUTPUT_LOAD='(1.0,-1.0)';
      PINUSE='BI';
    'GPIOAB1_VPOHS_NORWE#':
      PIN_NUMBER='(0,0,0,0,T21,0,0)';
      BIDIRECTIONAL='TRUE';
      INPUT_LOAD='(-0.01,0.01)';
      OUTPUT_LOAD='(1.0,-1.0)';
      PINUSE='BI';
    'GPIOAB0_VPODE_NOROE#':
      PIN_NUMBER='(0,0,0,0,N19,0,0)';
      BIDIRECTIONAL='TRUE';
      INPUT_LOAD='(-0.01,0.01)';
      OUTPUT_LOAD='(1.0,-1.0)';
      PINUSE='BI';
    'GPIOAC4_ESPICK_LCLK':
      PIN_NUMBER='(0,0,0,0,C22,0,0)';
      BIDIRECTIONAL='TRUE';
      INPUT_LOAD='(-0.01,0.01)';
      OUTPUT_LOAD='(1.0,-1.0)';
      PINUSE='BI';
    'GPIOAC3_ESPID3_LAD3':
      PIN_NUMBER='(0,0,0,0,E22,0,0)';
      BIDIRECTIONAL='TRUE';
      INPUT_LOAD='(-0.01,0.01)';
      OUTPUT_LOAD='(1.0,-1.0)';
      PINUSE='BI';
    'GPIOAC2_ESPID2_LAD2':
      PIN_NUMBER='(0,0,0,0,D22,0,0)';
      BIDIRECTIONAL='TRUE';
      INPUT_LOAD='(-0.01,0.01)';
      OUTPUT_LOAD='(1.0,-1.0)';
      PINUSE='BI';
    'GPIOAC1_ESPID1_LAD1':
      PIN_NUMBER='(0,0,0,0,G20,0,0)';
      BIDIRECTIONAL='TRUE';
      INPUT_LOAD='(-0.01,0.01)';
      OUTPUT_LOAD='(1.0,-1.0)';
      PINUSE='BI';
    'GPIOAC0_ESPID0_LAD0':
      PIN_NUMBER='(0,0,0,0,G21,0,0)';
      BIDIRECTIONAL='TRUE';
      INPUT_LOAD='(-0.01,0.01)';
      OUTPUT_LOAD='(1.0,-1.0)';
      PINUSE='BI';
    'FWSPIMISO':
      PIN_NUMBER='(0,0,0,0,T18,0,0)';
      BIDIRECTIONAL='TRUE';
      INPUT_LOAD='(-0.01,0.01)';
      OUTPUT_LOAD='(1.0,-1.0)';
      PINUSE='BI';
    'FWSPICS0#':
      PIN_NUMBER='(0,0,0,0,AB19,0,0)';
      BIDIRECTIONAL='TRUE';
      INPUT_LOAD='(-0.01,0.01)';
      OUTPUT_LOAD='(1.0,-1.0)';
      PINUSE='BI';
    'GPIOAC6_ESPIALT#_LSIRQ#':
      PIN_NUMBER='(0,0,0,0,F22,0,0)';
      BIDIRECTIONAL='TRUE';
      INPUT_LOAD='(-0.01,0.01)';
      OUTPUT_LOAD='(1.0,-1.0)';
      PINUSE='BI';
    'GPIOAC5_ESPICS#_LFRAME#':
      PIN_NUMBER='(0,0,0,0,F21,0,0)';
      BIDIRECTIONAL='TRUE';
      INPUT_LOAD='(-0.01,0.01)';
      OUTPUT_LOAD='(1.0,-1.0)';
      PINUSE='BI';
    'GPIOR3_SPI2CK':
      PIN_NUMBER='(0,0,0,0,Y19,0,0)';
      BIDIRECTIONAL='TRUE';
      INPUT_LOAD='(-0.01,0.01)';
      OUTPUT_LOAD='(1.0,-1.0)';
      PINUSE='BI';
    'GPIOR4_SPI2MOSI':
      PIN_NUMBER='(0,0,0,0,W19,0,0)';
      BIDIRECTIONAL='TRUE';
      INPUT_LOAD='(-0.01,0.01)';
      OUTPUT_LOAD='(1.0,-1.0)';
      PINUSE='BI';
    'ADC8_GPIX0':
      PIN_NUMBER='(0,0,0,0,0,F2,0)';
      INPUT_LOAD='(-0.01,0.01)';
      PINUSE='IN';
    'ADC7_GPIW7':
      PIN_NUMBER='(0,0,0,0,0,G4,0)';
      INPUT_LOAD='(-0.01,0.01)';
      PINUSE='IN';
    'GPIOA6_TIMER7_MDC2':
      PIN_NUMBER='(0,0,0,0,0,C13,0)';
      BIDIRECTIONAL='TRUE';
      INPUT_LOAD='(-0.01,0.01)';
      OUTPUT_LOAD='(1.0,-1.0)';
      PINUSE='BI';
    'GPIOA7_TIMER8_MDIO2':
      PIN_NUMBER='(0,0,0,0,0,B13,0)';
      BIDIRECTIONAL='TRUE';
      INPUT_LOAD='(-0.01,0.01)';
      OUTPUT_LOAD='(1.0,-1.0)';
      PINUSE='BI';
    'RGMIICK':
      PIN_NUMBER='(0,0,0,0,0,D3,0)';
      INPUT_LOAD='(-0.01,0.01)';
      PINUSE='IN';
    'GPION6_PWM6_VPIG6':
      PIN_NUMBER='(0,0,0,0,0,Y3,0)';
      BIDIRECTIONAL='TRUE';
      INPUT_LOAD='(-0.01,0.01)';
      OUTPUT_LOAD='(1.0,-1.0)';
      PINUSE='BI';
    'GPION7_PWM7_VPIG7':
      PIN_NUMBER='(0,0,0,0,0,T4,0)';
      BIDIRECTIONAL='TRUE';
      INPUT_LOAD='(-0.01,0.01)';
      OUTPUT_LOAD='(1.0,-1.0)';
      PINUSE='BI';
    'GPION4_PWM4_VPIG4':
      PIN_NUMBER='(0,0,0,0,0,W3,0)';
      BIDIRECTIONAL='TRUE';
      INPUT_LOAD='(-0.01,0.01)';
      OUTPUT_LOAD='(1.0,-1.0)';
      PINUSE='BI';
    'GPION5_PWM5_VPIG5':
      PIN_NUMBER='(0,0,0,0,0,AA3,0)';
      BIDIRECTIONAL='TRUE';
      INPUT_LOAD='(-0.01,0.01)';
      OUTPUT_LOAD='(1.0,-1.0)';
      PINUSE='BI';
    'GPION3_PWM3_VPIG3':
      PIN_NUMBER='(0,0,0,0,0,U3,0)';
      BIDIRECTIONAL='TRUE';
      INPUT_LOAD='(-0.01,0.01)';
      OUTPUT_LOAD='(1.0,-1.0)';
      PINUSE='BI';
    'GPION1_PWM1':
      PIN_NUMBER='(0,0,0,0,0,W2,0)';
      BIDIRECTIONAL='TRUE';
      INPUT_LOAD='(-0.01,0.01)';
      OUTPUT_LOAD='(1.0,-1.0)';
      PINUSE='BI';
    'GPION2_PWM2_VPIG2':
      PIN_NUMBER='(0,0,0,0,0,V3,0)';
      BIDIRECTIONAL='TRUE';
      INPUT_LOAD='(-0.01,0.01)';
      OUTPUT_LOAD='(1.0,-1.0)';
      PINUSE='BI';
    'GPION0_PWM0':
      PIN_NUMBER='(0,0,0,0,0,V2,0)';
      BIDIRECTIONAL='TRUE';
      INPUT_LOAD='(-0.01,0.01)';
      OUTPUT_LOAD='(1.0,-1.0)';
      PINUSE='BI';
    'ADCVREFP':
      PIN_NUMBER='(0,0,0,0,0,H2,0)';
      OUTPUT_LOAD='(1.0,-1.0)';
      PINUSE='OUT';
    'ADCREXT':
      PIN_NUMBER='(0,0,0,0,0,J1,0)';
      OUTPUT_LOAD='(1.0,-1.0)';
      PINUSE='OUT';
    'ADCVREFN':
      PIN_NUMBER='(0,0,0,0,0,H1,0)';
      OUTPUT_LOAD='(1.0,-1.0)';
      PINUSE='OUT';
    'ADC14_GPIX6':
      PIN_NUMBER='(0,0,0,0,0,H3,0)';
      INPUT_LOAD='(-0.01,0.01)';
      PINUSE='IN';
    'ADC15_GPIX7':
      PIN_NUMBER='(0,0,0,0,0,H4,0)';
      INPUT_LOAD='(-0.01,0.01)';
      PINUSE='IN';
    'ADC13_GPIX5':
      PIN_NUMBER='(0,0,0,0,0,G1,0)';
      INPUT_LOAD='(-0.01,0.01)';
      PINUSE='IN';
    'ADC12_GPIX4':
      PIN_NUMBER='(0,0,0,0,0,H5,0)';
      INPUT_LOAD='(-0.01,0.01)';
      PINUSE='IN';
    'ADC11_GPIX3':
      PIN_NUMBER='(0,0,0,0,0,F1,0)';
      INPUT_LOAD='(-0.01,0.01)';
      PINUSE='IN';
    'ADC9_GPIX1':
      PIN_NUMBER='(0,0,0,0,0,G3,0)';
      INPUT_LOAD='(-0.01,0.01)';
      PINUSE='IN';
    'ADC10_GPIX2':
      PIN_NUMBER='(0,0,0,0,0,G2,0)';
      INPUT_LOAD='(-0.01,0.01)';
      PINUSE='IN';
    'ADC6_GPIW6':
      PIN_NUMBER='(0,0,0,0,0,G5,0)';
      INPUT_LOAD='(-0.01,0.01)';
      PINUSE='IN';
    'ADC4_GPIW4':
      PIN_NUMBER='(0,0,0,0,0,F3,0)';
      INPUT_LOAD='(-0.01,0.01)';
      PINUSE='IN';
    'ADC5_GPIW5':
      PIN_NUMBER='(0,0,0,0,0,E3,0)';
      INPUT_LOAD='(-0.01,0.01)';
      PINUSE='IN';
    'ADC3_GPIW3':
      PIN_NUMBER='(0,0,0,0,0,E1,0)';
      INPUT_LOAD='(-0.01,0.01)';
      PINUSE='IN';
    'ADC2_GPIW2':
      PIN_NUMBER='(0,0,0,0,0,E2,0)';
      INPUT_LOAD='(-0.01,0.01)';
      PINUSE='IN';
    'ADC1_GPIW1':
      PIN_NUMBER='(0,0,0,0,0,F5,0)';
      INPUT_LOAD='(-0.01,0.01)';
      PINUSE='IN';
    'ADC0_GPIW0':
      PIN_NUMBER='(0,0,0,0,0,F4,0)';
      INPUT_LOAD='(-0.01,0.01)';
      PINUSE='IN';
    'GPIOP7_TACH15':
      PIN_NUMBER='(0,0,0,0,0,V6,0)';
      BIDIRECTIONAL='TRUE';
      INPUT_LOAD='(-0.01,0.01)';
      OUTPUT_LOAD='(1.0,-1.0)';
      PINUSE='BI';
    'GPIOP6_TACH14':
      PIN_NUMBER='(0,0,0,0,0,W6,0)';
      BIDIRECTIONAL='TRUE';
      INPUT_LOAD='(-0.01,0.01)';
      OUTPUT_LOAD='(1.0,-1.0)';
      PINUSE='BI';
    'GPIOP3_TACH11_VPIR9':
      PIN_NUMBER='(0,0,0,0,0,AB5,0)';
      BIDIRECTIONAL='TRUE';
      INPUT_LOAD='(-0.01,0.01)';
      OUTPUT_LOAD='(1.0,-1.0)';
      PINUSE='BI';
    'GPIOP4_TACH12':
      PIN_NUMBER='(0,0,0,0,0,Y6,0)';
      BIDIRECTIONAL='TRUE';
      INPUT_LOAD='(-0.01,0.01)';
      OUTPUT_LOAD='(1.0,-1.0)';
      PINUSE='BI';
    'GPIOP5_TACH13':
      PIN_NUMBER='(0,0,0,0,0,Y5,0)';
      BIDIRECTIONAL='TRUE';
      INPUT_LOAD='(-0.01,0.01)';
      OUTPUT_LOAD='(1.0,-1.0)';
      PINUSE='BI';
    'GPIOP2_TACH10_VPIR8':
      PIN_NUMBER='(0,0,0,0,0,AA5,0)';
      BIDIRECTIONAL='TRUE';
      INPUT_LOAD='(-0.01,0.01)';
      OUTPUT_LOAD='(1.0,-1.0)';
      PINUSE='BI';
    'GPIOP1_TACH9_VPIR7':
      PIN_NUMBER='(0,0,0,0,0,W5,0)';
      BIDIRECTIONAL='TRUE';
      INPUT_LOAD='(-0.01,0.01)';
      OUTPUT_LOAD='(1.0,-1.0)';
      PINUSE='BI';
    'GPIOO6_TACH6_VPIR4':
      PIN_NUMBER='(0,0,0,0,0,AA4,0)';
      BIDIRECTIONAL='TRUE';
      INPUT_LOAD='(-0.01,0.01)';
      OUTPUT_LOAD='(1.0,-1.0)';
      PINUSE='BI';
    'GPIOO7_TACH7_VPIR5':
      PIN_NUMBER='(0,0,0,0,0,W4,0)';
      BIDIRECTIONAL='TRUE';
      INPUT_LOAD='(-0.01,0.01)';
      OUTPUT_LOAD='(1.0,-1.0)';
      PINUSE='BI';
    'GPIOP0_TACH8_VPIR6':
      PIN_NUMBER='(0,0,0,0,0,V4,0)';
      BIDIRECTIONAL='TRUE';
      INPUT_LOAD='(-0.01,0.01)';
      OUTPUT_LOAD='(1.0,-1.0)';
      PINUSE='BI';
    'GPIOO4_TACH4_VPIR2':
      PIN_NUMBER='(0,0,0,0,0,AB3,0)';
      BIDIRECTIONAL='TRUE';
      INPUT_LOAD='(-0.01,0.01)';
      OUTPUT_LOAD='(1.0,-1.0)';
      PINUSE='BI';
    'GPIOO5_TACH5_VPIR3':
      PIN_NUMBER='(0,0,0,0,0,Y4,0)';
      BIDIRECTIONAL='TRUE';
      INPUT_LOAD='(-0.01,0.01)';
      OUTPUT_LOAD='(1.0,-1.0)';
      PINUSE='BI';
    'GPIOO3_TACH3':
      PIN_NUMBER='(0,0,0,0,0,AB4,0)';
      BIDIRECTIONAL='TRUE';
      INPUT_LOAD='(-0.01,0.01)';
      OUTPUT_LOAD='(1.0,-1.0)';
      PINUSE='BI';
    'GPIOO1_TACH1_VPIG9':
      PIN_NUMBER='(0,0,0,0,0,U4,0)';
      BIDIRECTIONAL='TRUE';
      INPUT_LOAD='(-0.01,0.01)';
      OUTPUT_LOAD='(1.0,-1.0)';
      PINUSE='BI';
    'GPIOO2_TACH2':
      PIN_NUMBER='(0,0,0,0,0,V5,0)';
      BIDIRECTIONAL='TRUE';
      INPUT_LOAD='(-0.01,0.01)';
      OUTPUT_LOAD='(1.0,-1.0)';
      PINUSE='BI';
    'GPIOO0_TACH0_VPIG8':
      PIN_NUMBER='(0,0,0,0,0,U5,0)';
      BIDIRECTIONAL='TRUE';
      INPUT_LOAD='(-0.01,0.01)';
      OUTPUT_LOAD='(1.0,-1.0)';
      PINUSE='BI';
    'RGMII2TXCTL_RMII2TXEN_GPIOT7':
      PIN_NUMBER='(0,0,0,0,0,B1,0)';
      OUTPUT_LOAD='(1.0,-1.0)';
      PINUSE='OUT';
    'RGMII2TXCK_RMII2RCLKO_GPIOT6':
      PIN_NUMBER='(0,0,0,0,0,B2,0)';
      OUTPUT_LOAD='(1.0,-1.0)';
      PINUSE='OUT';
    'RGMII2TXD2_GPIOU2':
      PIN_NUMBER='(0,0,0,0,0,D5,0)';
      OUTPUT_LOAD='(1.0,-1.0)';
      PINUSE='OUT';
    'RGMII2TXD3_GPIOU3':
      PIN_NUMBER='(0,0,0,0,0,D4,0)';
      OUTPUT_LOAD='(1.0,-1.0)';
      PINUSE='OUT';
    'RGMII2TXD1_RMII2TXD1_GPIOU1':
      PIN_NUMBER='(0,0,0,0,0,B3,0)';
      OUTPUT_LOAD='(1.0,-1.0)';
      PINUSE='OUT';
    'RGMII2TXD0_RMII2TXD0_GPIOU0':
      PIN_NUMBER='(0,0,0,0,0,A2,0)';
      OUTPUT_LOAD='(1.0,-1.0)';
      PINUSE='OUT';
    'RGMII1TXCK_RMII1RCLKO_GPIOT0':
      PIN_NUMBER='(0,0,0,0,0,B5,0)';
      OUTPUT_LOAD='(1.0,-1.0)';
      PINUSE='OUT';
    'RGMII1TXCTL_RMII1TXEN_GPIOT1':
      PIN_NUMBER='(0,0,0,0,0,E9,0)';
      OUTPUT_LOAD='(1.0,-1.0)';
      PINUSE='OUT';
    'RGMII1TXD2_GPIOT4':
      PIN_NUMBER='(0,0,0,0,0,E7,0)';
      OUTPUT_LOAD='(1.0,-1.0)';
      PINUSE='OUT';
    'RGMII1TXD3_GPIOT5':
      PIN_NUMBER='(0,0,0,0,0,D7,0)';
      OUTPUT_LOAD='(1.0,-1.0)';
      PINUSE='OUT';
    'RGMII1TXD0_RMII1TXD0_GPIOT2':
      PIN_NUMBER='(0,0,0,0,0,F9,0)';
      OUTPUT_LOAD='(1.0,-1.0)';
      PINUSE='OUT';
    'RGMII1TXD1_RMII1TXD1_GPIOT3':
      PIN_NUMBER='(0,0,0,0,0,A5,0)';
      OUTPUT_LOAD='(1.0,-1.0)';
      PINUSE='OUT';
    'RGMII2RXCTL_GPIOV3':
      PIN_NUMBER='(0,0,0,0,0,C1,0)';
      BIDIRECTIONAL='TRUE';
      INPUT_LOAD='(-0.01,0.01)';
      OUTPUT_LOAD='(1.0,-1.0)';
      PINUSE='BI';
    'GPIOR6_MDC1':
      PIN_NUMBER='(0,0,0,0,0,D8,0)';
      BIDIRECTIONAL='TRUE';
      INPUT_LOAD='(-0.01,0.01)';
      OUTPUT_LOAD='(1.0,-1.0)';
      PINUSE='BI';
    'GPIOR7_MDIO1':
      PIN_NUMBER='(0,0,0,0,0,E10,0)';
      BIDIRECTIONAL='TRUE';
      INPUT_LOAD='(-0.01,0.01)';
      OUTPUT_LOAD='(1.0,-1.0)';
      PINUSE='BI';
    'RGMII1RXD0_RMII1RXD0_GPIOU6':
      PIN_NUMBER='(0,0,0,0,0,A3,0)';
      BIDIRECTIONAL='TRUE';
      INPUT_LOAD='(-0.01,0.01)';
      OUTPUT_LOAD='(1.0,-1.0)';
      PINUSE='BI';
    'RGMII1RXD1_RMII1RXD1_GPIOU7':
      PIN_NUMBER='(0,0,0,0,0,D6,0)';
      BIDIRECTIONAL='TRUE';
      INPUT_LOAD='(-0.01,0.01)';
      OUTPUT_LOAD='(1.0,-1.0)';
      PINUSE='BI';
    'RGMII1RXD2_RMII1CRSDV_GPIOV0':
      PIN_NUMBER='(0,0,0,0,0,C5,0)';
      BIDIRECTIONAL='TRUE';
      INPUT_LOAD='(-0.01,0.01)';
      OUTPUT_LOAD='(1.0,-1.0)';
      PINUSE='BI';
    'RGMII1RXD3_RMII1RXER_GPIOV1':
      PIN_NUMBER='(0,0,0,0,0,C4,0)';
      BIDIRECTIONAL='TRUE';
      INPUT_LOAD='(-0.01,0.01)';
      OUTPUT_LOAD='(1.0,-1.0)';
      PINUSE='BI';
    'RGMII1RXCTL_GPIOU5':
      PIN_NUMBER='(0,0,0,0,0,A4,0)';
      BIDIRECTIONAL='TRUE';
      INPUT_LOAD='(-0.01,0.01)';
      OUTPUT_LOAD='(1.0,-1.0)';
      PINUSE='BI';
    'RGMII1RXCK_RMII1RCLKI_GPIOU4':
      PIN_NUMBER='(0,0,0,0,0,B4,0)';
      BIDIRECTIONAL='TRUE';
      INPUT_LOAD='(-0.01,0.01)';
      OUTPUT_LOAD='(1.0,-1.0)';
      PINUSE='BI';
    'RGMII2RXD0_RMII2RXD0_GPIOV4':
      PIN_NUMBER='(0,0,0,0,0,C3,0)';
      BIDIRECTIONAL='TRUE';
      INPUT_LOAD='(-0.01,0.01)';
      OUTPUT_LOAD='(1.0,-1.0)';
      PINUSE='BI';
    'RGMII2RXD1_RMII2RXD1_GPIOV5':
      PIN_NUMBER='(0,0,0,0,0,D1,0)';
      BIDIRECTIONAL='TRUE';
      INPUT_LOAD='(-0.01,0.01)';
      OUTPUT_LOAD='(1.0,-1.0)';
      PINUSE='BI';
    'RGMII2RXD2_RMII2CRSDV_GPIOV6':
      PIN_NUMBER='(0,0,0,0,0,D2,0)';
      BIDIRECTIONAL='TRUE';
      INPUT_LOAD='(-0.01,0.01)';
      OUTPUT_LOAD='(1.0,-1.0)';
      PINUSE='BI';
    'RGMII2RXD3_RMII2RXER_GPIOV7':
      PIN_NUMBER='(0,0,0,0,0,E6,0)';
      BIDIRECTIONAL='TRUE';
      INPUT_LOAD='(-0.01,0.01)';
      OUTPUT_LOAD='(1.0,-1.0)';
      PINUSE='BI';
    'RGMII2RXCK_RMII2RCLKI_GPIOV2':
      PIN_NUMBER='(0,0,0,0,0,C2,0)';
      BIDIRECTIONAL='TRUE';
      INPUT_LOAD='(-0.01,0.01)';
      OUTPUT_LOAD='(1.0,-1.0)';
      PINUSE='BI';
    'LPVDD1':
      PIN_NUMBER='(0,0,0,0,0,0,K17)';
      PINUSE='POWER';
      NO_LOAD_CHECK='Both';
      NO_IO_CHECK='Both';
      NO_ASSERT_CHECK='TRUE';
      NO_DIR_CHECK='TRUE';
      ALLOW_CONNECT='TRUE';
    'LPVDD0':
      PIN_NUMBER='(0,0,0,0,0,0,J17)';
      PINUSE='POWER';
      NO_LOAD_CHECK='Both';
      NO_IO_CHECK='Both';
      NO_ASSERT_CHECK='TRUE';
      NO_DIR_CHECK='TRUE';
      ALLOW_CONNECT='TRUE';
    'GND68':
      PIN_NUMBER='(0,0,0,0,0,0,E5)';
      PINUSE='POWER';
      NO_LOAD_CHECK='Both';
      NO_IO_CHECK='Both';
      NO_ASSERT_CHECK='TRUE';
      NO_DIR_CHECK='TRUE';
      ALLOW_CONNECT='TRUE';
    'DACAV33':
      PIN_NUMBER='(0,0,0,0,0,0,K6)';
      PINUSE='POWER';
      NO_LOAD_CHECK='Both';
      NO_IO_CHECK='Both';
      NO_ASSERT_CHECK='TRUE';
      NO_DIR_CHECK='TRUE';
      ALLOW_CONNECT='TRUE';
    'PV33D0':
      PIN_NUMBER='(0,0,0,0,0,0,F12)';
      PINUSE='POWER';
      NO_LOAD_CHECK='Both';
      NO_IO_CHECK='Both';
      NO_ASSERT_CHECK='TRUE';
      NO_DIR_CHECK='TRUE';
      ALLOW_CONNECT='TRUE';
    'MVDD4':
      PIN_NUMBER='(0,0,0,0,0,0,T8)';
      PINUSE='POWER';
      NO_LOAD_CHECK='Both';
      NO_IO_CHECK='Both';
      NO_ASSERT_CHECK='TRUE';
      NO_DIR_CHECK='TRUE';
      ALLOW_CONNECT='TRUE';
    'GPIOY2_SIOPWREQ#':
      PIN_NUMBER='(0,0,0,0,0,0,P22)';
      BIDIRECTIONAL='TRUE';
      INPUT_LOAD='(-0.01,0.01)';
      OUTPUT_LOAD='(1.0,-1.0)';
      PINUSE='BI';
    'GPIOY1_SIOS5#':
      PIN_NUMBER='(0,0,0,0,0,0,R21)';
      BIDIRECTIONAL='TRUE';
      INPUT_LOAD='(-0.01,0.01)';
      OUTPUT_LOAD='(1.0,-1.0)';
      PINUSE='BI';
    'GPIOY0_SIOS3#':
      PIN_NUMBER='(0,0,0,0,0,0,R22)';
      BIDIRECTIONAL='TRUE';
      INPUT_LOAD='(-0.01,0.01)';
      OUTPUT_LOAD='(1.0,-1.0)';
      PINUSE='BI';
    'IV11D0':
      PIN_NUMBER='(0,0,0,0,0,0,F6)';
      PINUSE='POWER';
      NO_LOAD_CHECK='Both';
      NO_IO_CHECK='Both';
      NO_ASSERT_CHECK='TRUE';
      NO_DIR_CHECK='TRUE';
      ALLOW_CONNECT='TRUE';
    'IV11D1':
      PIN_NUMBER='(0,0,0,0,0,0,G10)';
      PINUSE='POWER';
      NO_LOAD_CHECK='Both';
      NO_IO_CHECK='Both';
      NO_ASSERT_CHECK='TRUE';
      NO_DIR_CHECK='TRUE';
      ALLOW_CONNECT='TRUE';
    'IV11D2':
      PIN_NUMBER='(0,0,0,0,0,0,G11)';
      PINUSE='POWER';
      NO_LOAD_CHECK='Both';
      NO_IO_CHECK='Both';
      NO_ASSERT_CHECK='TRUE';
      NO_DIR_CHECK='TRUE';
      ALLOW_CONNECT='TRUE';
    'IV11D3':
      PIN_NUMBER='(0,0,0,0,0,0,G12)';
      PINUSE='POWER';
      NO_LOAD_CHECK='Both';
      NO_IO_CHECK='Both';
      NO_ASSERT_CHECK='TRUE';
      NO_DIR_CHECK='TRUE';
      ALLOW_CONNECT='TRUE';
    'IV11D4':
      PIN_NUMBER='(0,0,0,0,0,0,G13)';
      PINUSE='POWER';
      NO_LOAD_CHECK='Both';
      NO_IO_CHECK='Both';
      NO_ASSERT_CHECK='TRUE';
      NO_DIR_CHECK='TRUE';
      ALLOW_CONNECT='TRUE';
    'IV11D5':
      PIN_NUMBER='(0,0,0,0,0,0,G14)';
      PINUSE='POWER';
      NO_LOAD_CHECK='Both';
      NO_IO_CHECK='Both';
      NO_ASSERT_CHECK='TRUE';
      NO_DIR_CHECK='TRUE';
      ALLOW_CONNECT='TRUE';
    'IV11D6':
      PIN_NUMBER='(0,0,0,0,0,0,G15)';
      PINUSE='POWER';
      NO_LOAD_CHECK='Both';
      NO_IO_CHECK='Both';
      NO_ASSERT_CHECK='TRUE';
      NO_DIR_CHECK='TRUE';
      ALLOW_CONNECT='TRUE';
    'IV11D7':
      PIN_NUMBER='(0,0,0,0,0,0,G7)';
      PINUSE='POWER';
      NO_LOAD_CHECK='Both';
      NO_IO_CHECK='Both';
      NO_ASSERT_CHECK='TRUE';
      NO_DIR_CHECK='TRUE';
      ALLOW_CONNECT='TRUE';
    'IV11D8':
      PIN_NUMBER='(0,0,0,0,0,0,G8)';
      PINUSE='POWER';
      NO_LOAD_CHECK='Both';
      NO_IO_CHECK='Both';
      NO_ASSERT_CHECK='TRUE';
      NO_DIR_CHECK='TRUE';
      ALLOW_CONNECT='TRUE';
    'IV11D9':
      PIN_NUMBER='(0,0,0,0,0,0,G9)';
      PINUSE='POWER';
      NO_LOAD_CHECK='Both';
      NO_IO_CHECK='Both';
      NO_ASSERT_CHECK='TRUE';
      NO_DIR_CHECK='TRUE';
      ALLOW_CONNECT='TRUE';
    'IV11D10':
      PIN_NUMBER='(0,0,0,0,0,0,H16)';
      PINUSE='POWER';
      NO_LOAD_CHECK='Both';
      NO_IO_CHECK='Both';
      NO_ASSERT_CHECK='TRUE';
      NO_DIR_CHECK='TRUE';
      ALLOW_CONNECT='TRUE';
    'IV11D11':
      PIN_NUMBER='(0,0,0,0,0,0,J16)';
      PINUSE='POWER';
      NO_LOAD_CHECK='Both';
      NO_IO_CHECK='Both';
      NO_ASSERT_CHECK='TRUE';
      NO_DIR_CHECK='TRUE';
      ALLOW_CONNECT='TRUE';
    'IV11D12':
      PIN_NUMBER='(0,0,0,0,0,0,L7)';
      PINUSE='POWER';
      NO_LOAD_CHECK='Both';
      NO_IO_CHECK='Both';
      NO_ASSERT_CHECK='TRUE';
      NO_DIR_CHECK='TRUE';
      ALLOW_CONNECT='TRUE';
    'IV11D13':
      PIN_NUMBER='(0,0,0,0,0,0,N16)';
      PINUSE='POWER';
      NO_LOAD_CHECK='Both';
      NO_IO_CHECK='Both';
      NO_ASSERT_CHECK='TRUE';
      NO_DIR_CHECK='TRUE';
      ALLOW_CONNECT='TRUE';
    'IV11D14':
      PIN_NUMBER='(0,0,0,0,0,0,N7)';
      PINUSE='POWER';
      NO_LOAD_CHECK='Both';
      NO_IO_CHECK='Both';
      NO_ASSERT_CHECK='TRUE';
      NO_DIR_CHECK='TRUE';
      ALLOW_CONNECT='TRUE';
    'IV11D15':
      PIN_NUMBER='(0,0,0,0,0,0,P10)';
      PINUSE='POWER';
      NO_LOAD_CHECK='Both';
      NO_IO_CHECK='Both';
      NO_ASSERT_CHECK='TRUE';
      NO_DIR_CHECK='TRUE';
      ALLOW_CONNECT='TRUE';
    'IV11D16':
      PIN_NUMBER='(0,0,0,0,0,0,P11)';
      PINUSE='POWER';
      NO_LOAD_CHECK='Both';
      NO_IO_CHECK='Both';
      NO_ASSERT_CHECK='TRUE';
      NO_DIR_CHECK='TRUE';
      ALLOW_CONNECT='TRUE';
    'IV11D17':
      PIN_NUMBER='(0,0,0,0,0,0,P12)';
      PINUSE='POWER';
      NO_LOAD_CHECK='Both';
      NO_IO_CHECK='Both';
      NO_ASSERT_CHECK='TRUE';
      NO_DIR_CHECK='TRUE';
      ALLOW_CONNECT='TRUE';
    'IV11D18':
      PIN_NUMBER='(0,0,0,0,0,0,P13)';
      PINUSE='POWER';
      NO_LOAD_CHECK='Both';
      NO_IO_CHECK='Both';
      NO_ASSERT_CHECK='TRUE';
      NO_DIR_CHECK='TRUE';
      ALLOW_CONNECT='TRUE';
    'IV11D19':
      PIN_NUMBER='(0,0,0,0,0,0,P14)';
      PINUSE='POWER';
      NO_LOAD_CHECK='Both';
      NO_IO_CHECK='Both';
      NO_ASSERT_CHECK='TRUE';
      NO_DIR_CHECK='TRUE';
      ALLOW_CONNECT='TRUE';
    'IV11D20':
      PIN_NUMBER='(0,0,0,0,0,0,P16)';
      PINUSE='POWER';
      NO_LOAD_CHECK='Both';
      NO_IO_CHECK='Both';
      NO_ASSERT_CHECK='TRUE';
      NO_DIR_CHECK='TRUE';
      ALLOW_CONNECT='TRUE';
    'IV11D21':
      PIN_NUMBER='(0,0,0,0,0,0,P7)';
      PINUSE='POWER';
      NO_LOAD_CHECK='Both';
      NO_IO_CHECK='Both';
      NO_ASSERT_CHECK='TRUE';
      NO_DIR_CHECK='TRUE';
      ALLOW_CONNECT='TRUE';
    'IV11D22':
      PIN_NUMBER='(0,0,0,0,0,0,P9)';
      PINUSE='POWER';
      NO_LOAD_CHECK='Both';
      NO_IO_CHECK='Both';
      NO_ASSERT_CHECK='TRUE';
      NO_DIR_CHECK='TRUE';
      ALLOW_CONNECT='TRUE';
    'IV11D23':
      PIN_NUMBER='(0,0,0,0,0,0,R16)';
      PINUSE='POWER';
      NO_LOAD_CHECK='Both';
      NO_IO_CHECK='Both';
      NO_ASSERT_CHECK='TRUE';
      NO_DIR_CHECK='TRUE';
      ALLOW_CONNECT='TRUE';
    'IV11D24':
      PIN_NUMBER='(0,0,0,0,0,0,R7)';
      PINUSE='POWER';
      NO_LOAD_CHECK='Both';
      NO_IO_CHECK='Both';
      NO_ASSERT_CHECK='TRUE';
      NO_DIR_CHECK='TRUE';
      ALLOW_CONNECT='TRUE';
    'VPLLAV110':
      PIN_NUMBER='(0,0,0,0,0,0,L5)';
      PINUSE='POWER';
      NO_LOAD_CHECK='Both';
      NO_IO_CHECK='Both';
      NO_ASSERT_CHECK='TRUE';
      NO_DIR_CHECK='TRUE';
      ALLOW_CONNECT='TRUE';
    'VPLLAV111':
      PIN_NUMBER='(0,0,0,0,0,0,L6)';
      PINUSE='POWER';
      NO_LOAD_CHECK='Both';
      NO_IO_CHECK='Both';
      NO_ASSERT_CHECK='TRUE';
      NO_DIR_CHECK='TRUE';
      ALLOW_CONNECT='TRUE';
    'PEAV11':
      PIN_NUMBER='(0,0,0,0,0,0,L17)';
      PINUSE='POWER';
      NO_LOAD_CHECK='Both';
      NO_IO_CHECK='Both';
      NO_ASSERT_CHECK='TRUE';
      NO_DIR_CHECK='TRUE';
      ALLOW_CONNECT='TRUE';
    'PLLDV11':
      PIN_NUMBER='(0,0,0,0,0,0,V17)';
      PINUSE='POWER';
      NO_LOAD_CHECK='Both';
      NO_IO_CHECK='Both';
      NO_ASSERT_CHECK='TRUE';
      NO_DIR_CHECK='TRUE';
      ALLOW_CONNECT='TRUE';
    'PECIVDD':
      PIN_NUMBER='(0,0,0,0,0,0,AA17)';
      PINUSE='POWER';
      NO_LOAD_CHECK='Both';
      NO_IO_CHECK='Both';
      NO_ASSERT_CHECK='TRUE';
      NO_DIR_CHECK='TRUE';
      ALLOW_CONNECT='TRUE';
    'MVDD0':
      PIN_NUMBER='(0,0,0,0,0,0,T10)';
      PINUSE='POWER';
      NO_LOAD_CHECK='Both';
      NO_IO_CHECK='Both';
      NO_ASSERT_CHECK='TRUE';
      NO_DIR_CHECK='TRUE';
      ALLOW_CONNECT='TRUE';
    'MVDD1':
      PIN_NUMBER='(0,0,0,0,0,0,T12)';
      PINUSE='POWER';
      NO_LOAD_CHECK='Both';
      NO_IO_CHECK='Both';
      NO_ASSERT_CHECK='TRUE';
      NO_DIR_CHECK='TRUE';
      ALLOW_CONNECT='TRUE';
    'MVDD2':
      PIN_NUMBER='(0,0,0,0,0,0,T13)';
      PINUSE='POWER';
      NO_LOAD_CHECK='Both';
      NO_IO_CHECK='Both';
      NO_ASSERT_CHECK='TRUE';
      NO_DIR_CHECK='TRUE';
      ALLOW_CONNECT='TRUE';
    'MVDD3':
      PIN_NUMBER='(0,0,0,0,0,0,T14)';
      PINUSE='POWER';
      NO_LOAD_CHECK='Both';
      NO_IO_CHECK='Both';
      NO_ASSERT_CHECK='TRUE';
      NO_DIR_CHECK='TRUE';
      ALLOW_CONNECT='TRUE';
    'PV33D1':
      PIN_NUMBER='(0,0,0,0,0,0,F13)';
      PINUSE='POWER';
      NO_LOAD_CHECK='Both';
      NO_IO_CHECK='Both';
      NO_ASSERT_CHECK='TRUE';
      NO_DIR_CHECK='TRUE';
      ALLOW_CONNECT='TRUE';
    'PV33D2':
      PIN_NUMBER='(0,0,0,0,0,0,F14)';
      PINUSE='POWER';
      NO_LOAD_CHECK='Both';
      NO_IO_CHECK='Both';
      NO_ASSERT_CHECK='TRUE';
      NO_DIR_CHECK='TRUE';
      ALLOW_CONNECT='TRUE';
    'PV33D3':
      PIN_NUMBER='(0,0,0,0,0,0,F15)';
      PINUSE='POWER';
      NO_LOAD_CHECK='Both';
      NO_IO_CHECK='Both';
      NO_ASSERT_CHECK='TRUE';
      NO_DIR_CHECK='TRUE';
      ALLOW_CONNECT='TRUE';
    'PV33D4':
      PIN_NUMBER='(0,0,0,0,0,0,G16)';
      PINUSE='POWER';
      NO_LOAD_CHECK='Both';
      NO_IO_CHECK='Both';
      NO_ASSERT_CHECK='TRUE';
      NO_DIR_CHECK='TRUE';
      ALLOW_CONNECT='TRUE';
    'PV33D5':
      PIN_NUMBER='(0,0,0,0,0,0,H17)';
      PINUSE='POWER';
      NO_LOAD_CHECK='Both';
      NO_IO_CHECK='Both';
      NO_ASSERT_CHECK='TRUE';
      NO_DIR_CHECK='TRUE';
      ALLOW_CONNECT='TRUE';
    'PV33D6':
      PIN_NUMBER='(0,0,0,0,0,0,K7)';
      PINUSE='POWER';
      NO_LOAD_CHECK='Both';
      NO_IO_CHECK='Both';
      NO_ASSERT_CHECK='TRUE';
      NO_DIR_CHECK='TRUE';
      ALLOW_CONNECT='TRUE';
    'PV33D7':
      PIN_NUMBER='(0,0,0,0,0,0,N17)';
      PINUSE='POWER';
      NO_LOAD_CHECK='Both';
      NO_IO_CHECK='Both';
      NO_ASSERT_CHECK='TRUE';
      NO_DIR_CHECK='TRUE';
      ALLOW_CONNECT='TRUE';
    'PV33D8':
      PIN_NUMBER='(0,0,0,0,0,0,N6)';
      PINUSE='POWER';
      NO_LOAD_CHECK='Both';
      NO_IO_CHECK='Both';
      NO_ASSERT_CHECK='TRUE';
      NO_DIR_CHECK='TRUE';
      ALLOW_CONNECT='TRUE';
    'PV33D9':
      PIN_NUMBER='(0,0,0,0,0,0,P17)';
      PINUSE='POWER';
      NO_LOAD_CHECK='Both';
      NO_IO_CHECK='Both';
      NO_ASSERT_CHECK='TRUE';
      NO_DIR_CHECK='TRUE';
      ALLOW_CONNECT='TRUE';
    'PV33D10':
      PIN_NUMBER='(0,0,0,0,0,0,P6)';
      PINUSE='POWER';
      NO_LOAD_CHECK='Both';
      NO_IO_CHECK='Both';
      NO_ASSERT_CHECK='TRUE';
      NO_DIR_CHECK='TRUE';
      ALLOW_CONNECT='TRUE';
    'PV33D11':
      PIN_NUMBER='(0,0,0,0,0,0,R17)';
      PINUSE='POWER';
      NO_LOAD_CHECK='Both';
      NO_IO_CHECK='Both';
      NO_ASSERT_CHECK='TRUE';
      NO_DIR_CHECK='TRUE';
      ALLOW_CONNECT='TRUE';
    'PV33D12':
      PIN_NUMBER='(0,0,0,0,0,0,R6)';
      PINUSE='POWER';
      NO_LOAD_CHECK='Both';
      NO_IO_CHECK='Both';
      NO_ASSERT_CHECK='TRUE';
      NO_DIR_CHECK='TRUE';
      ALLOW_CONNECT='TRUE';
    'PV33D13':
      PIN_NUMBER='(0,0,0,0,0,0,T11)';
      PINUSE='POWER';
      NO_LOAD_CHECK='Both';
      NO_IO_CHECK='Both';
      NO_ASSERT_CHECK='TRUE';
      NO_DIR_CHECK='TRUE';
      ALLOW_CONNECT='TRUE';
    'PV33D14':
      PIN_NUMBER='(0,0,0,0,0,0,T15)';
      PINUSE='POWER';
      NO_LOAD_CHECK='Both';
      NO_IO_CHECK='Both';
      NO_ASSERT_CHECK='TRUE';
      NO_DIR_CHECK='TRUE';
      ALLOW_CONNECT='TRUE';
    'PLLAV330':
      PIN_NUMBER='(0,0,0,0,0,0,Y17)';
      PINUSE='POWER';
      NO_LOAD_CHECK='Both';
      NO_IO_CHECK='Both';
      NO_ASSERT_CHECK='TRUE';
      NO_DIR_CHECK='TRUE';
      ALLOW_CONNECT='TRUE';
    'PLLAV331':
      PIN_NUMBER='(0,0,0,0,0,0,W17)';
      PINUSE='POWER';
      NO_LOAD_CHECK='Both';
      NO_IO_CHECK='Both';
      NO_ASSERT_CHECK='TRUE';
      NO_DIR_CHECK='TRUE';
      ALLOW_CONNECT='TRUE';
    'VPLLAV330':
      PIN_NUMBER='(0,0,0,0,0,0,J7)';
      PINUSE='POWER';
      NO_LOAD_CHECK='Both';
      NO_IO_CHECK='Both';
      NO_ASSERT_CHECK='TRUE';
      NO_DIR_CHECK='TRUE';
      ALLOW_CONNECT='TRUE';
    'VPLLAV331':
      PIN_NUMBER='(0,0,0,0,0,0,H7)';
      PINUSE='POWER';
      NO_LOAD_CHECK='Both';
      NO_IO_CHECK='Both';
      NO_ASSERT_CHECK='TRUE';
      NO_DIR_CHECK='TRUE';
      ALLOW_CONNECT='TRUE';
    'PEAV33':
      PIN_NUMBER='(0,0,0,0,0,0,L16)';
      PINUSE='POWER';
      NO_LOAD_CHECK='Both';
      NO_IO_CHECK='Both';
      NO_ASSERT_CHECK='TRUE';
      NO_DIR_CHECK='TRUE';
      ALLOW_CONNECT='TRUE';
    'BATVDD':
      PIN_NUMBER='(0,0,0,0,0,0,E4)';
      PINUSE='POWER';
      NO_LOAD_CHECK='Both';
      NO_IO_CHECK='Both';
      NO_ASSERT_CHECK='TRUE';
      NO_DIR_CHECK='TRUE';
      ALLOW_CONNECT='TRUE';
    'USB2AV33':
      PIN_NUMBER='(0,0,0,0,0,0,C7)';
      PINUSE='POWER';
      NO_LOAD_CHECK='Both';
      NO_IO_CHECK='Both';
      NO_ASSERT_CHECK='TRUE';
      NO_DIR_CHECK='TRUE';
      ALLOW_CONNECT='TRUE';
    'DACDV33':
      PIN_NUMBER='(0,0,0,0,0,0,K5)';
      PINUSE='POWER';
      NO_LOAD_CHECK='Both';
      NO_IO_CHECK='Both';
      NO_ASSERT_CHECK='TRUE';
      NO_DIR_CHECK='TRUE';
      ALLOW_CONNECT='TRUE';
    'ADCAV33':
      PIN_NUMBER='(0,0,0,0,0,0,J6)';
      PINUSE='POWER';
      NO_LOAD_CHECK='Both';
      NO_IO_CHECK='Both';
      NO_ASSERT_CHECK='TRUE';
      NO_DIR_CHECK='TRUE';
      ALLOW_CONNECT='TRUE';
    'R2VDD0':
      PIN_NUMBER='(0,0,0,0,0,0,F7)';
      PINUSE='POWER';
      NO_LOAD_CHECK='Both';
      NO_IO_CHECK='Both';
      NO_ASSERT_CHECK='TRUE';
      NO_DIR_CHECK='TRUE';
      ALLOW_CONNECT='TRUE';
    'R2VDD1':
      PIN_NUMBER='(0,0,0,0,0,0,F8)';
      PINUSE='POWER';
      NO_LOAD_CHECK='Both';
      NO_IO_CHECK='Both';
      NO_ASSERT_CHECK='TRUE';
      NO_DIR_CHECK='TRUE';
      ALLOW_CONNECT='TRUE';
    'R1VDD0':
      PIN_NUMBER='(0,0,0,0,0,0,F10)';
      PINUSE='POWER';
      NO_LOAD_CHECK='Both';
      NO_IO_CHECK='Both';
      NO_ASSERT_CHECK='TRUE';
      NO_DIR_CHECK='TRUE';
      ALLOW_CONNECT='TRUE';
    'R1VDD1':
      PIN_NUMBER='(0,0,0,0,0,0,F11)';
      PINUSE='POWER';
      NO_LOAD_CHECK='Both';
      NO_IO_CHECK='Both';
      NO_ASSERT_CHECK='TRUE';
      NO_DIR_CHECK='TRUE';
      ALLOW_CONNECT='TRUE';
    'GND67':
      PIN_NUMBER='(0,0,0,0,0,0,V8)';
      PINUSE='POWER';
      NO_LOAD_CHECK='Both';
      NO_IO_CHECK='Both';
      NO_ASSERT_CHECK='TRUE';
      NO_DIR_CHECK='TRUE';
      ALLOW_CONNECT='TRUE';
    'GND66':
      PIN_NUMBER='(0,0,0,0,0,0,V16)';
      PINUSE='POWER';
      NO_LOAD_CHECK='Both';
      NO_IO_CHECK='Both';
      NO_ASSERT_CHECK='TRUE';
      NO_DIR_CHECK='TRUE';
      ALLOW_CONNECT='TRUE';
    'GND65':
      PIN_NUMBER='(0,0,0,0,0,0,V14)';
      PINUSE='POWER';
      NO_LOAD_CHECK='Both';
      NO_IO_CHECK='Both';
      NO_ASSERT_CHECK='TRUE';
      NO_DIR_CHECK='TRUE';
      ALLOW_CONNECT='TRUE';
    'GND60':
      PIN_NUMBER='(0,0,0,0,0,0,T7)';
      PINUSE='POWER';
      NO_LOAD_CHECK='Both';
      NO_IO_CHECK='Both';
      NO_ASSERT_CHECK='TRUE';
      NO_DIR_CHECK='TRUE';
      ALLOW_CONNECT='TRUE';
    'GND61':
      PIN_NUMBER='(0,0,0,0,0,0,U11)';
      PINUSE='POWER';
      NO_LOAD_CHECK='Both';
      NO_IO_CHECK='Both';
      NO_ASSERT_CHECK='TRUE';
      NO_DIR_CHECK='TRUE';
      ALLOW_CONNECT='TRUE';
    'GND64':
      PIN_NUMBER='(0,0,0,0,0,0,V12)';
      PINUSE='POWER';
      NO_LOAD_CHECK='Both';
      NO_IO_CHECK='Both';
      NO_ASSERT_CHECK='TRUE';
      NO_DIR_CHECK='TRUE';
      ALLOW_CONNECT='TRUE';
    'GND63':
      PIN_NUMBER='(0,0,0,0,0,0,V10)';
      PINUSE='POWER';
      NO_LOAD_CHECK='Both';
      NO_IO_CHECK='Both';
      NO_ASSERT_CHECK='TRUE';
      NO_DIR_CHECK='TRUE';
      ALLOW_CONNECT='TRUE';
    'GND62':
      PIN_NUMBER='(0,0,0,0,0,0,U6)';
      PINUSE='POWER';
      NO_LOAD_CHECK='Both';
      NO_IO_CHECK='Both';
      NO_ASSERT_CHECK='TRUE';
      NO_DIR_CHECK='TRUE';
      ALLOW_CONNECT='TRUE';
    'GND55':
      PIN_NUMBER='(0,0,0,0,0,0,N13)';
      PINUSE='POWER';
      NO_LOAD_CHECK='Both';
      NO_IO_CHECK='Both';
      NO_ASSERT_CHECK='TRUE';
      NO_DIR_CHECK='TRUE';
      ALLOW_CONNECT='TRUE';
    'GND56':
      PIN_NUMBER='(0,0,0,0,0,0,N14)';
      PINUSE='POWER';
      NO_LOAD_CHECK='Both';
      NO_IO_CHECK='Both';
      NO_ASSERT_CHECK='TRUE';
      NO_DIR_CHECK='TRUE';
      ALLOW_CONNECT='TRUE';
    'GND59':
      PIN_NUMBER='(0,0,0,0,0,0,T6)';
      PINUSE='POWER';
      NO_LOAD_CHECK='Both';
      NO_IO_CHECK='Both';
      NO_ASSERT_CHECK='TRUE';
      NO_DIR_CHECK='TRUE';
      ALLOW_CONNECT='TRUE';
    'GND58':
      PIN_NUMBER='(0,0,0,0,0,0,T16)';
      PINUSE='POWER';
      NO_LOAD_CHECK='Both';
      NO_IO_CHECK='Both';
      NO_ASSERT_CHECK='TRUE';
      NO_DIR_CHECK='TRUE';
      ALLOW_CONNECT='TRUE';
    'GND57':
      PIN_NUMBER='(0,0,0,0,0,0,N9)';
      PINUSE='POWER';
      NO_LOAD_CHECK='Both';
      NO_IO_CHECK='Both';
      NO_ASSERT_CHECK='TRUE';
      NO_DIR_CHECK='TRUE';
      ALLOW_CONNECT='TRUE';
    'GND50':
      PIN_NUMBER='(0,0,0,0,0,0,M7)';
      PINUSE='POWER';
      NO_LOAD_CHECK='Both';
      NO_IO_CHECK='Both';
      NO_ASSERT_CHECK='TRUE';
      NO_DIR_CHECK='TRUE';
      ALLOW_CONNECT='TRUE';
    'GND51':
      PIN_NUMBER='(0,0,0,0,0,0,M9)';
      PINUSE='POWER';
      NO_LOAD_CHECK='Both';
      NO_IO_CHECK='Both';
      NO_ASSERT_CHECK='TRUE';
      NO_DIR_CHECK='TRUE';
      ALLOW_CONNECT='TRUE';
    'GND54':
      PIN_NUMBER='(0,0,0,0,0,0,N12)';
      PINUSE='POWER';
      NO_LOAD_CHECK='Both';
      NO_IO_CHECK='Both';
      NO_ASSERT_CHECK='TRUE';
      NO_DIR_CHECK='TRUE';
      ALLOW_CONNECT='TRUE';
    'GND53':
      PIN_NUMBER='(0,0,0,0,0,0,N11)';
      PINUSE='POWER';
      NO_LOAD_CHECK='Both';
      NO_IO_CHECK='Both';
      NO_ASSERT_CHECK='TRUE';
      NO_DIR_CHECK='TRUE';
      ALLOW_CONNECT='TRUE';
    'GND52':
      PIN_NUMBER='(0,0,0,0,0,0,N10)';
      PINUSE='POWER';
      NO_LOAD_CHECK='Both';
      NO_IO_CHECK='Both';
      NO_ASSERT_CHECK='TRUE';
      NO_DIR_CHECK='TRUE';
      ALLOW_CONNECT='TRUE';
    'GND45':
      PIN_NUMBER='(0,0,0,0,0,0,M2)';
      PINUSE='POWER';
      NO_LOAD_CHECK='Both';
      NO_IO_CHECK='Both';
      NO_ASSERT_CHECK='TRUE';
      NO_DIR_CHECK='TRUE';
      ALLOW_CONNECT='TRUE';
    'GND46':
      PIN_NUMBER='(0,0,0,0,0,0,M3)';
      PINUSE='POWER';
      NO_LOAD_CHECK='Both';
      NO_IO_CHECK='Both';
      NO_ASSERT_CHECK='TRUE';
      NO_DIR_CHECK='TRUE';
      ALLOW_CONNECT='TRUE';
    'GND49':
      PIN_NUMBER='(0,0,0,0,0,0,M6)';
      PINUSE='POWER';
      NO_LOAD_CHECK='Both';
      NO_IO_CHECK='Both';
      NO_ASSERT_CHECK='TRUE';
      NO_DIR_CHECK='TRUE';
      ALLOW_CONNECT='TRUE';
    'GND48':
      PIN_NUMBER='(0,0,0,0,0,0,M5)';
      PINUSE='POWER';
      NO_LOAD_CHECK='Both';
      NO_IO_CHECK='Both';
      NO_ASSERT_CHECK='TRUE';
      NO_DIR_CHECK='TRUE';
      ALLOW_CONNECT='TRUE';
    'GND47':
      PIN_NUMBER='(0,0,0,0,0,0,M4)';
      PINUSE='POWER';
      NO_LOAD_CHECK='Both';
      NO_IO_CHECK='Both';
      NO_ASSERT_CHECK='TRUE';
      NO_DIR_CHECK='TRUE';
      ALLOW_CONNECT='TRUE';
    'GND40':
      PIN_NUMBER='(0,0,0,0,0,0,M12)';
      PINUSE='POWER';
      NO_LOAD_CHECK='Both';
      NO_IO_CHECK='Both';
      NO_ASSERT_CHECK='TRUE';
      NO_DIR_CHECK='TRUE';
      ALLOW_CONNECT='TRUE';
    'GND41':
      PIN_NUMBER='(0,0,0,0,0,0,M13)';
      PINUSE='POWER';
      NO_LOAD_CHECK='Both';
      NO_IO_CHECK='Both';
      NO_ASSERT_CHECK='TRUE';
      NO_DIR_CHECK='TRUE';
      ALLOW_CONNECT='TRUE';
    'GND44':
      PIN_NUMBER='(0,0,0,0,0,0,M17)';
      PINUSE='POWER';
      NO_LOAD_CHECK='Both';
      NO_IO_CHECK='Both';
      NO_ASSERT_CHECK='TRUE';
      NO_DIR_CHECK='TRUE';
      ALLOW_CONNECT='TRUE';
    'GND43':
      PIN_NUMBER='(0,0,0,0,0,0,M16)';
      PINUSE='POWER';
      NO_LOAD_CHECK='Both';
      NO_IO_CHECK='Both';
      NO_ASSERT_CHECK='TRUE';
      NO_DIR_CHECK='TRUE';
      ALLOW_CONNECT='TRUE';
    'GND42':
      PIN_NUMBER='(0,0,0,0,0,0,M14)';
      PINUSE='POWER';
      NO_LOAD_CHECK='Both';
      NO_IO_CHECK='Both';
      NO_ASSERT_CHECK='TRUE';
      NO_DIR_CHECK='TRUE';
      ALLOW_CONNECT='TRUE';
    'GND35':
      PIN_NUMBER='(0,0,0,0,0,0,L14)';
      PINUSE='POWER';
      NO_LOAD_CHECK='Both';
      NO_IO_CHECK='Both';
      NO_ASSERT_CHECK='TRUE';
      NO_DIR_CHECK='TRUE';
      ALLOW_CONNECT='TRUE';
    'GND39':
      PIN_NUMBER='(0,0,0,0,0,0,M11)';
      PINUSE='POWER';
      NO_LOAD_CHECK='Both';
      NO_IO_CHECK='Both';
      NO_ASSERT_CHECK='TRUE';
      NO_DIR_CHECK='TRUE';
      ALLOW_CONNECT='TRUE';
    'GND38':
      PIN_NUMBER='(0,0,0,0,0,0,M10)';
      PINUSE='POWER';
      NO_LOAD_CHECK='Both';
      NO_IO_CHECK='Both';
      NO_ASSERT_CHECK='TRUE';
      NO_DIR_CHECK='TRUE';
      ALLOW_CONNECT='TRUE';
    'GND37':
      PIN_NUMBER='(0,0,0,0,0,0,M1)';
      PINUSE='POWER';
      NO_LOAD_CHECK='Both';
      NO_IO_CHECK='Both';
      NO_ASSERT_CHECK='TRUE';
      NO_DIR_CHECK='TRUE';
      ALLOW_CONNECT='TRUE';
    'GND36':
      PIN_NUMBER='(0,0,0,0,0,0,L9)';
      PINUSE='POWER';
      NO_LOAD_CHECK='Both';
      NO_IO_CHECK='Both';
      NO_ASSERT_CHECK='TRUE';
      NO_DIR_CHECK='TRUE';
      ALLOW_CONNECT='TRUE';
    'GND30':
      PIN_NUMBER='(0,0,0,0,0,0,K9)';
      PINUSE='POWER';
      NO_LOAD_CHECK='Both';
      NO_IO_CHECK='Both';
      NO_ASSERT_CHECK='TRUE';
      NO_DIR_CHECK='TRUE';
      ALLOW_CONNECT='TRUE';
    'GND34':
      PIN_NUMBER='(0,0,0,0,0,0,L13)';
      PINUSE='POWER';
      NO_LOAD_CHECK='Both';
      NO_IO_CHECK='Both';
      NO_ASSERT_CHECK='TRUE';
      NO_DIR_CHECK='TRUE';
      ALLOW_CONNECT='TRUE';
    'GND33':
      PIN_NUMBER='(0,0,0,0,0,0,L12)';
      PINUSE='POWER';
      NO_LOAD_CHECK='Both';
      NO_IO_CHECK='Both';
      NO_ASSERT_CHECK='TRUE';
      NO_DIR_CHECK='TRUE';
      ALLOW_CONNECT='TRUE';
    'GND32':
      PIN_NUMBER='(0,0,0,0,0,0,L11)';
      PINUSE='POWER';
      NO_LOAD_CHECK='Both';
      NO_IO_CHECK='Both';
      NO_ASSERT_CHECK='TRUE';
      NO_DIR_CHECK='TRUE';
      ALLOW_CONNECT='TRUE';
    'GND31':
      PIN_NUMBER='(0,0,0,0,0,0,L10)';
      PINUSE='POWER';
      NO_LOAD_CHECK='Both';
      NO_IO_CHECK='Both';
      NO_ASSERT_CHECK='TRUE';
      NO_DIR_CHECK='TRUE';
      ALLOW_CONNECT='TRUE';
    'GND29':
      PIN_NUMBER='(0,0,0,0,0,0,K16)';
      PINUSE='POWER';
      NO_LOAD_CHECK='Both';
      NO_IO_CHECK='Both';
      NO_ASSERT_CHECK='TRUE';
      NO_DIR_CHECK='TRUE';
      ALLOW_CONNECT='TRUE';
    'GND25':
      PIN_NUMBER='(0,0,0,0,0,0,K11)';
      PINUSE='POWER';
      NO_LOAD_CHECK='Both';
      NO_IO_CHECK='Both';
      NO_ASSERT_CHECK='TRUE';
      NO_DIR_CHECK='TRUE';
      ALLOW_CONNECT='TRUE';
    'GND27':
      PIN_NUMBER='(0,0,0,0,0,0,K13)';
      PINUSE='POWER';
      NO_LOAD_CHECK='Both';
      NO_IO_CHECK='Both';
      NO_ASSERT_CHECK='TRUE';
      NO_DIR_CHECK='TRUE';
      ALLOW_CONNECT='TRUE';
    'GND28':
      PIN_NUMBER='(0,0,0,0,0,0,K14)';
      PINUSE='POWER';
      NO_LOAD_CHECK='Both';
      NO_IO_CHECK='Both';
      NO_ASSERT_CHECK='TRUE';
      NO_DIR_CHECK='TRUE';
      ALLOW_CONNECT='TRUE';
    'GND26':
      PIN_NUMBER='(0,0,0,0,0,0,K12)';
      PINUSE='POWER';
      NO_LOAD_CHECK='Both';
      NO_IO_CHECK='Both';
      NO_ASSERT_CHECK='TRUE';
      NO_DIR_CHECK='TRUE';
      ALLOW_CONNECT='TRUE';
    'GND24':
      PIN_NUMBER='(0,0,0,0,0,0,K10)';
      PINUSE='POWER';
      NO_LOAD_CHECK='Both';
      NO_IO_CHECK='Both';
      NO_ASSERT_CHECK='TRUE';
      NO_DIR_CHECK='TRUE';
      ALLOW_CONNECT='TRUE';
    'GND20':
      PIN_NUMBER='(0,0,0,0,0,0,J21)';
      PINUSE='POWER';
      NO_LOAD_CHECK='Both';
      NO_IO_CHECK='Both';
      NO_ASSERT_CHECK='TRUE';
      NO_DIR_CHECK='TRUE';
      ALLOW_CONNECT='TRUE';
    'GND23':
      PIN_NUMBER='(0,0,0,0,0,0,J9)';
      PINUSE='POWER';
      NO_LOAD_CHECK='Both';
      NO_IO_CHECK='Both';
      NO_ASSERT_CHECK='TRUE';
      NO_DIR_CHECK='TRUE';
      ALLOW_CONNECT='TRUE';
    'GND22':
      PIN_NUMBER='(0,0,0,0,0,0,J5)';
      PINUSE='POWER';
      NO_LOAD_CHECK='Both';
      NO_IO_CHECK='Both';
      NO_ASSERT_CHECK='TRUE';
      NO_DIR_CHECK='TRUE';
      ALLOW_CONNECT='TRUE';
    'GND21':
      PIN_NUMBER='(0,0,0,0,0,0,J22)';
      PINUSE='POWER';
      NO_LOAD_CHECK='Both';
      NO_IO_CHECK='Both';
      NO_ASSERT_CHECK='TRUE';
      NO_DIR_CHECK='TRUE';
      ALLOW_CONNECT='TRUE';
    'GND19':
      PIN_NUMBER='(0,0,0,0,0,0,J14)';
      PINUSE='POWER';
      NO_LOAD_CHECK='Both';
      NO_IO_CHECK='Both';
      NO_ASSERT_CHECK='TRUE';
      NO_DIR_CHECK='TRUE';
      ALLOW_CONNECT='TRUE';
    'GND14':
      PIN_NUMBER='(0,0,0,0,0,0,H6)';
      PINUSE='POWER';
      NO_LOAD_CHECK='Both';
      NO_IO_CHECK='Both';
      NO_ASSERT_CHECK='TRUE';
      NO_DIR_CHECK='TRUE';
      ALLOW_CONNECT='TRUE';
    'GND15':
      PIN_NUMBER='(0,0,0,0,0,0,J10)';
      PINUSE='POWER';
      NO_LOAD_CHECK='Both';
      NO_IO_CHECK='Both';
      NO_ASSERT_CHECK='TRUE';
      NO_DIR_CHECK='TRUE';
      ALLOW_CONNECT='TRUE';
    'GND18':
      PIN_NUMBER='(0,0,0,0,0,0,J13)';
      PINUSE='POWER';
      NO_LOAD_CHECK='Both';
      NO_IO_CHECK='Both';
      NO_ASSERT_CHECK='TRUE';
      NO_DIR_CHECK='TRUE';
      ALLOW_CONNECT='TRUE';
    'GND17':
      PIN_NUMBER='(0,0,0,0,0,0,J12)';
      PINUSE='POWER';
      NO_LOAD_CHECK='Both';
      NO_IO_CHECK='Both';
      NO_ASSERT_CHECK='TRUE';
      NO_DIR_CHECK='TRUE';
      ALLOW_CONNECT='TRUE';
    'GND16':
      PIN_NUMBER='(0,0,0,0,0,0,J11)';
      PINUSE='POWER';
      NO_LOAD_CHECK='Both';
      NO_IO_CHECK='Both';
      NO_ASSERT_CHECK='TRUE';
      NO_DIR_CHECK='TRUE';
      ALLOW_CONNECT='TRUE';
    'GND9':
      PIN_NUMBER='(0,0,0,0,0,0,C6)';
      PINUSE='POWER';
      NO_LOAD_CHECK='Both';
      NO_IO_CHECK='Both';
      NO_ASSERT_CHECK='TRUE';
      NO_DIR_CHECK='TRUE';
      ALLOW_CONNECT='TRUE';
    'GND10':
      PIN_NUMBER='(0,0,0,0,0,0,E8)';
      PINUSE='POWER';
      NO_LOAD_CHECK='Both';
      NO_IO_CHECK='Both';
      NO_ASSERT_CHECK='TRUE';
      NO_DIR_CHECK='TRUE';
      ALLOW_CONNECT='TRUE';
    'GND13':
      PIN_NUMBER='(0,0,0,0,0,0,G6)';
      PINUSE='POWER';
      NO_LOAD_CHECK='Both';
      NO_IO_CHECK='Both';
      NO_ASSERT_CHECK='TRUE';
      NO_DIR_CHECK='TRUE';
      ALLOW_CONNECT='TRUE';
    'GND12':
      PIN_NUMBER='(0,0,0,0,0,0,G19)';
      PINUSE='POWER';
      NO_LOAD_CHECK='Both';
      NO_IO_CHECK='Both';
      NO_ASSERT_CHECK='TRUE';
      NO_DIR_CHECK='TRUE';
      ALLOW_CONNECT='TRUE';
    'GND11':
      PIN_NUMBER='(0,0,0,0,0,0,F16)';
      PINUSE='POWER';
      NO_LOAD_CHECK='Both';
      NO_IO_CHECK='Both';
      NO_ASSERT_CHECK='TRUE';
      NO_DIR_CHECK='TRUE';
      ALLOW_CONNECT='TRUE';
    'GND4':
      PIN_NUMBER='(0,0,0,0,0,0,AA15)';
      PINUSE='POWER';
      NO_LOAD_CHECK='Both';
      NO_IO_CHECK='Both';
      NO_ASSERT_CHECK='TRUE';
      NO_DIR_CHECK='TRUE';
      ALLOW_CONNECT='TRUE';
    'GND5':
      PIN_NUMBER='(0,0,0,0,0,0,AA7)';
      PINUSE='POWER';
      NO_LOAD_CHECK='Both';
      NO_IO_CHECK='Both';
      NO_ASSERT_CHECK='TRUE';
      NO_DIR_CHECK='TRUE';
      ALLOW_CONNECT='TRUE';
    'GND7':
      PIN_NUMBER='(0,0,0,0,0,0,AB1)';
      PINUSE='POWER';
      NO_LOAD_CHECK='Both';
      NO_IO_CHECK='Both';
      NO_ASSERT_CHECK='TRUE';
      NO_DIR_CHECK='TRUE';
      ALLOW_CONNECT='TRUE';
    'GND8':
      PIN_NUMBER='(0,0,0,0,0,0,AB22)';
      PINUSE='POWER';
      NO_LOAD_CHECK='Both';
      NO_IO_CHECK='Both';
      NO_ASSERT_CHECK='TRUE';
      NO_DIR_CHECK='TRUE';
      ALLOW_CONNECT='TRUE';
    'GND6':
      PIN_NUMBER='(0,0,0,0,0,0,AA9)';
      PINUSE='POWER';
      NO_LOAD_CHECK='Both';
      NO_IO_CHECK='Both';
      NO_ASSERT_CHECK='TRUE';
      NO_DIR_CHECK='TRUE';
      ALLOW_CONNECT='TRUE';
    'GND3':
      PIN_NUMBER='(0,0,0,0,0,0,AA13)';
      PINUSE='POWER';
      NO_LOAD_CHECK='Both';
      NO_IO_CHECK='Both';
      NO_ASSERT_CHECK='TRUE';
      NO_DIR_CHECK='TRUE';
      ALLOW_CONNECT='TRUE';
    'GND2':
      PIN_NUMBER='(0,0,0,0,0,0,AA11)';
      PINUSE='POWER';
      NO_LOAD_CHECK='Both';
      NO_IO_CHECK='Both';
      NO_ASSERT_CHECK='TRUE';
      NO_DIR_CHECK='TRUE';
      ALLOW_CONNECT='TRUE';
    'GND1':
      PIN_NUMBER='(0,0,0,0,0,0,A22)';
      PINUSE='POWER';
      NO_LOAD_CHECK='Both';
      NO_IO_CHECK='Both';
      NO_ASSERT_CHECK='TRUE';
      NO_DIR_CHECK='TRUE';
      ALLOW_CONNECT='TRUE';
    'GND0':
      PIN_NUMBER='(0,0,0,0,0,0,A1)';
      PINUSE='POWER';
      NO_LOAD_CHECK='Both';
      NO_IO_CHECK='Both';
      NO_ASSERT_CHECK='TRUE';
      NO_DIR_CHECK='TRUE';
      ALLOW_CONNECT='TRUE';
  end_pin;
  body
      PART_NAME='AST2520A1-GP-GP';
      BODY_NAME='AST2520A1-GP-GP';
      PHYS_DES_PREFIX='U';
      CLASS='IC';
      DESCRIPTION='IC VGA AST2520A1-GP TFBGA 456P(FIONA)';
      JEDEC_TYPE='BGA456D19H58';
      PARENT_PART_TYPE='AST2520A1-GP-GP';
      PARENT_PPT='AST2520A1-GP-GP';
      PARENT_PPT_PART='AST2520A1-GP-GP_ASIC2-GB1-AST2520A1-GP-GP,071.2520A.M001';
  end_body;
end_primitive;
primitive 'AT24C64_SOICLF-IC,C47049-001-GA';
  pin
    'A0':
      PIN_NUMBER='(1)';
      INPUT_LOAD='(-0.01,0.01)';
      PINUSE='IN';
    'A1':
      PIN_NUMBER='(2)';
      INPUT_LOAD='(-0.01,0.01)';
      PINUSE='IN';
    'A2':
      PIN_NUMBER='(3)';
      INPUT_LOAD='(-0.01,0.01)';
      PINUSE='IN';
    'SCL':
      PIN_NUMBER='(6)';
      INPUT_LOAD='(-0.01,0.01)';
      PINUSE='IN';
    'WP':
      PIN_NUMBER='(7)';
      INPUT_LOAD='(-0.01,0.01)';
      PINUSE='IN';
    'SDA':
      PIN_NUMBER='(5)';
      INPUT_LOAD='(-0.01,0.01)';
      OUTPUT_LOAD='(1.00,-1.00)';
      OUTPUT_TYPE='(TS,TS)';
      BIDIRECTIONAL='TRUE';
      PINUSE='BI';
  end_pin;
  body
      CLASS='IC';
      PART_NAME='AT24C64';
      PHYS_DES_PREFIX='U';
      ENVCOMP='YES;YES;YES;UNK;ok;VLD';
      PART_NUMBER='C47049-001';
      JEDEC_TYPE='SOI8_15_50IA';
      DESCRIPTION='EEPROM';
      COMPONENT_TYPE='SOIC';
      HEIGHT='.069 IN';
      LEAD_LENGTH='';
      LPID='';
      SPEED_URL='http://speed.intel.com:8081/speed/module/pdm/item/pdm_item_deta~
il_direct.asp?item_cde=C47049-001&item_rev=01&url_param=unused';
      STATUS='Conditional';
      RPL='YES';
      AML='14';
      BUS_UNIT='SMO_IC';
      DAYS='84';
      POWER_PINS='(P3V3_STBY:8;GND:4)';
      PARENT_PART_TYPE='AT24C64';
      SCH_MODIFIED_PART='TRUE';
      PARENT_PPT='AT24C64';
      PARENT_PPT_PART='AT24C64_SOICLF-IC,C47049-001';
  end_body;
end_primitive;
primitive 'BATTERY_PLCLF-202168-001';
  pin
  end_pin;
  body
      CLASS='MECHANICAL';
      PART_NAME='BATTERY';
      PINCOUNT='0';
      BODY_NAME='BATTERY';
      PHYS_DES_PREFIX='XBT';
      ENVCOMP='Excl;Excl;Excl;Excl;ok;Excl';
      PART_NUMBER='202168-001';
      DESCRIPTION='BATTERY_ONLY';
      JEDEC_TYPE='PLC_HOLDER';
      HEIGHT='0.16 IN';
      COMPONENT_TYPE='PSEUDO';
      LPID='';
      SPEED_URL='http://speed.intel.com:8081/speed/module/pdm/item/pdm_item_deta~
il_direct.asp?item_cde=202168-001&item_rev=01&url_param=unused';
      STATUS='Approved';
      RPL='YES';
      AML='12';
      BUS_UNIT='SMO_BOARDS';
      DAYS='42';
      PARENT_PART_TYPE='BATTERY';
      PARENT_PPT='BATTERY';
      PARENT_PPT_PART='BATTERY_PLCLF-202168-001';
  end_body;
end_primitive;
primitive 'BLM15AG121SN-1GP_DISCRET-G-BLMA';
  pin
    '1':
      PIN_NUMBER='(1)';
      PIN_TYPE='ANALOG';
      NO_LOAD_CHECK='Both';
      NO_IO_CHECK='Both';
      NO_ASSERT_CHECK='TRUE';
      NO_DIR_CHECK='TRUE';
      ALLOW_CONNECT='TRUE';
      PINUSE='UNSPEC';
    '2':
      PIN_NUMBER='(2)';
      PIN_TYPE='ANALOG';
      NO_LOAD_CHECK='Both';
      NO_IO_CHECK='Both';
      NO_ASSERT_CHECK='TRUE';
      NO_DIR_CHECK='TRUE';
      ALLOW_CONNECT='TRUE';
      PINUSE='UNSPEC';
  end_pin;
  body
      PART_NAME='BLM15AG121SN-1GP';
      BODY_NAME='BLM15AG121SN-1GP';
      PHYS_DES_PREFIX='L';
      CLASS='DISCRETE';
      DESCRIPTION='CHIP BAED BLM15AG121SN1D';
      JEDEC_TYPE='L402H22';
      PARENT_PART_TYPE='BLM15AG121SN-1GP';
      PARENT_PPT='BLM15AG121SN-1GP';
      PARENT_PPT_PART='BLM15AG121SN-1GP_DISCRET-G-BLM15AG121SN-1GP,68.00084.921';
  end_body;
end_primitive;
primitive 'BLM31SN500SN1L-GP_DISCRET-GB1-A';
  pin
    '1':
      PIN_NUMBER='(1)';
      PIN_TYPE='ANALOG';
      NO_LOAD_CHECK='Both';
      NO_IO_CHECK='Both';
      NO_ASSERT_CHECK='TRUE';
      NO_DIR_CHECK='TRUE';
      ALLOW_CONNECT='TRUE';
      PINUSE='UNSPEC';
    '2':
      PIN_NUMBER='(2)';
      PIN_TYPE='ANALOG';
      NO_LOAD_CHECK='Both';
      NO_IO_CHECK='Both';
      NO_ASSERT_CHECK='TRUE';
      NO_DIR_CHECK='TRUE';
      ALLOW_CONNECT='TRUE';
      PINUSE='UNSPEC';
  end_pin;
  body
      PART_NAME='BLM31SN500SN1L-GP';
      BODY_NAME='BLM31SN500SN1L-GP';
      PHYS_DES_PREFIX='L';
      CLASS='DISCRETE';
      DESCRIPTION='CHIP BEAD BLM31SN500SN1L';
      JEDEC_TYPE='L1206-0716-UH52';
      PARENT_PART_TYPE='BLM31SN500SN1L-GP';
      PARENT_PPT='BLM31SN500SN1L-GP';
      PARENT_PPT_PART='BLM31SN500SN1L-GP_DISCRET-GB1-BLM31SN500SN1L-GP,068.00007.0011,50OHM@100MHZ,1MA,DCR=1.6MOHM';
  end_body;
end_primitive;
primitive 'BSL308C-H6327-GP_DISCRET-GB1-BA';
  pin
    'GATE#1':
      PIN_NUMBER='(1)';
      PIN_TYPE='ANALOG';
      NO_LOAD_CHECK='Both';
      NO_IO_CHECK='Both';
      NO_ASSERT_CHECK='TRUE';
      NO_DIR_CHECK='TRUE';
      ALLOW_CONNECT='TRUE';
      PINUSE='UNSPEC';
    'SOURCE#2':
      PIN_NUMBER='(2)';
      PIN_TYPE='ANALOG';
      NO_LOAD_CHECK='Both';
      NO_IO_CHECK='Both';
      NO_ASSERT_CHECK='TRUE';
      NO_DIR_CHECK='TRUE';
      ALLOW_CONNECT='TRUE';
      PINUSE='UNSPEC';
    'DRAIN#6':
      PIN_NUMBER='(6)';
      PIN_TYPE='ANALOG';
      NO_LOAD_CHECK='Both';
      NO_IO_CHECK='Both';
      NO_ASSERT_CHECK='TRUE';
      NO_DIR_CHECK='TRUE';
      ALLOW_CONNECT='TRUE';
      PINUSE='UNSPEC';
    'SOURCE#5':
      PIN_NUMBER='(5)';
      PIN_TYPE='ANALOG';
      NO_LOAD_CHECK='Both';
      NO_IO_CHECK='Both';
      NO_ASSERT_CHECK='TRUE';
      NO_DIR_CHECK='TRUE';
      ALLOW_CONNECT='TRUE';
      PINUSE='UNSPEC';
    'GATE#3':
      PIN_NUMBER='(3)';
      PIN_TYPE='ANALOG';
      NO_LOAD_CHECK='Both';
      NO_IO_CHECK='Both';
      NO_ASSERT_CHECK='TRUE';
      NO_DIR_CHECK='TRUE';
      ALLOW_CONNECT='TRUE';
      PINUSE='UNSPEC';
    'DRAIN#4':
      PIN_NUMBER='(4)';
      PIN_TYPE='ANALOG';
      NO_LOAD_CHECK='Both';
      NO_IO_CHECK='Both';
      NO_ASSERT_CHECK='TRUE';
      NO_DIR_CHECK='TRUE';
      ALLOW_CONNECT='TRUE';
      PINUSE='UNSPEC';
  end_pin;
  body
      PART_NAME='BSL308C-H6327-GP';
      BODY_NAME='BSL308C-H6327-GP';
      PHYS_DES_PREFIX='Q';
      CLASS='DISCRETE';
      DESCRIPTION='IC MOSFET BSL308C H6327 6P';
      JEDEC_TYPE='TSOP6-2H44';
      PARENT_PART_TYPE='BSL308C-H6327-GP';
      PARENT_PPT='BSL308C-H6327-GP';
      PARENT_PPT_PART='BSL308C-H6327-GP_DISCRET-GB1-BSL308C-H6327-GP,075.00308.007C';
  end_body;
end_primitive;
primitive 'CAPP_2626-270UF,16V,20%,OSCON,A';
  pin
    'A':
      PIN_NUMBER='(1)';
      PIN_TYPE='UNSPEC';
      NO_LOAD_CHECK='BOTH';
      NO_IO_CHECK='BOTH';
      ALLOW_CONNECT='TRUE';
      PINUSE='UNSPEC';
    'B':
      PIN_NUMBER='(2)';
      PIN_TYPE='UNSPEC';
      NO_LOAD_CHECK='BOTH';
      NO_IO_CHECK='BOTH';
      ALLOW_CONNECT='TRUE';
      PINUSE='UNSPEC';
  end_pin;
  body
      PART_NAME='CAPP';
      PHYS_DES_PREFIX='C';
      ENVCOMP='YES;YES;YES;UNK;ok;VLD';
      PART_NUMBER='A31228-047';
      JEDEC_TYPE='SMC2626_ALEL_C';
      VALUE='270uF';
      RATED_VOLTAGE='16V';
      TOL='20%';
      CLASS='DISCRETE';
      DESCRIPTION='CAPA,270.00UF,6.3X9.9,16.00V,SM';
      HEIGHT='0.394 IN';
      COMPONENT_TYPE='SMTOTHER';
      LEAD_LENGTH='';
      LPID='1792';
      SPEED_URL='http://speed.intel.com:8081/speed/module/pdm/item/pdm_item_deta~
il_direct.asp?item_cde=A31228-047&item_rev=01&url_param=unused';
      STATUS='Design';
      RPL='YES';
      AML='1';
      BUS_UNIT='SMO_BOARDS';
      DAYS='???';
      PARENT_PART_TYPE='CAPP';
      PARENT_PPT='CAPP';
      PARENT_PPT_PART='CAPP_2626-270UF,16V,20%,OSCON,A31228-047';
  end_body;
end_primitive;
primitive 'CAPP_3018-470UF,2.5V,20%,ALUM,A';
  pin
    'A':
      PIN_NUMBER='(1)';
      PIN_TYPE='UNSPEC';
      NO_LOAD_CHECK='BOTH';
      NO_IO_CHECK='BOTH';
      ALLOW_CONNECT='TRUE';
      PINUSE='UNSPEC';
    'B':
      PIN_NUMBER='(2)';
      PIN_TYPE='UNSPEC';
      NO_LOAD_CHECK='BOTH';
      NO_IO_CHECK='BOTH';
      ALLOW_CONNECT='TRUE';
      PINUSE='UNSPEC';
  end_pin;
  body
      PART_NAME='CAPP';
      PHYS_DES_PREFIX='C';
      ENVCOMP='YES;YES;YES;UNK;ok;VLD';
      PART_NUMBER='699013-049';
      JEDEC_TYPE='SMC3018B';
      VALUE='470uF';
      RATED_VOLTAGE='2.5V';
      TOL='20%';
      CLASS='DISCRETE';
      DESCRIPTION='CAPS,TA-P,D4,470.00uF,2.5V,+/- 20%';
      HEIGHT='0.079 IN';
      COMPONENT_TYPE='SMTOTHER';
      LEAD_LENGTH='';
      LPID='481';
      SPEED_URL='http://speed.intel.com:8081/speed/module/pdm/item/pdm_item_deta~
il_direct.asp?item_cde=699013-049&item_rev=01&url_param=unused';
      STATUS='Design';
      RPL='N/A';
      AML='1';
      BUS_UNIT='SMO_BOARDS';
      DAYS='56';
      PARENT_PART_TYPE='CAPP';
      PARENT_PPT='CAPP';
      PARENT_PPT_PART='CAPP_3018-470UF,2.5V,20%,ALUM,699013-049';
  end_body;
end_primitive;
primitive 'CAPP_3018-68UF,16V,20%,TANT,72A';
  pin
    'A':
      PIN_NUMBER='(1)';
      PIN_TYPE='UNSPEC';
      NO_LOAD_CHECK='BOTH';
      NO_IO_CHECK='BOTH';
      ALLOW_CONNECT='TRUE';
      PINUSE='UNSPEC';
    'B':
      PIN_NUMBER='(2)';
      PIN_TYPE='UNSPEC';
      NO_LOAD_CHECK='BOTH';
      NO_IO_CHECK='BOTH';
      ALLOW_CONNECT='TRUE';
      PINUSE='UNSPEC';
  end_pin;
  body
      PART_NAME='CAPP';
      PHYS_DES_PREFIX='C';
      ENVCOMP='YES;YES;YES;UNK;ok;VLD';
      PART_NUMBER='724613-112';
      JEDEC_TYPE='SMC3018B';
      VALUE='68uF';
      RATED_VOLTAGE='16V';
      TOL='20%';
      CLASS='DISCRETE';
      DESCRIPTION='68uF POLARIZED CAP';
      HEIGHT='0.079 IN';
      COMPONENT_TYPE='SMTOTHER';
      LEAD_LENGTH='';
      LPID='481';
      SPEED_URL='http://speed.intel.com:8081/speed/module/pdm/item/pdm_item_deta~
il_direct.asp?item_cde=724613-112&item_rev=01&url_param=unused';
      STATUS='Unqual';
      RPL='N/A';
      AML='2';
      BUS_UNIT='SMO_BOARDS';
      DAYS='112';
      PARENT_PART_TYPE='CAPP';
      PARENT_PPT='CAPP';
      PARENT_PPT_PART='CAPP_3018-68UF,16V,20%,TANT,724613-112';
  end_body;
end_primitive;
primitive 'CAPP_4040LF-470UF,16V,20%,ALUMA';
  pin
    'A':
      PIN_NUMBER='(1)';
      PIN_TYPE='UNSPEC';
      NO_LOAD_CHECK='BOTH';
      NO_IO_CHECK='BOTH';
      ALLOW_CONNECT='TRUE';
      PINUSE='UNSPEC';
    'B':
      PIN_NUMBER='(2)';
      PIN_TYPE='UNSPEC';
      NO_LOAD_CHECK='BOTH';
      NO_IO_CHECK='BOTH';
      ALLOW_CONNECT='TRUE';
      PINUSE='UNSPEC';
  end_pin;
  body
      PART_NAME='CAPP';
      PHYS_DES_PREFIX='C';
      ENVCOMP='YES;YES;UNK;UNK;ok;CIP';
      PART_NUMBER='A93539-036';
      JEDEC_TYPE='SMC4040_ALEL_B';
      VALUE='470uF';
      RATED_VOLTAGE='16V';
      TOL='20%';
      CLASS='DISCRETE';
      DESCRIPTION='470uF POLARIZED CAP';
      HEIGHT='0.394 IN';
      COMPONENT_TYPE='SMTOTHER';
      LEAD_LENGTH='';
      LPID='494';
      SPEED_URL='http://speed.intel.com:8081/speed/module/pdm/item/pdm_item_deta~
il_direct.asp?item_cde=A93539-036&item_rev=01&url_param=unused';
      STATUS='Approved';
      RPL='YES';
      AML='8';
      BUS_UNIT='SMO_BOARDS';
      DAYS='84';
      PARENT_PART_TYPE='CAPP';
      PARENT_PPT='CAPP';
      PARENT_PPT_PART='CAPP_4040LF-470UF,16V,20%,ALUM,A93539-036';
  end_body;
end_primitive;
primitive 'CAPP_7343-220UF,4V,20%,POSCAP,A';
  pin
    'A':
      PIN_NUMBER='(1)';
      PIN_TYPE='UNSPEC';
      NO_LOAD_CHECK='BOTH';
      NO_IO_CHECK='BOTH';
      ALLOW_CONNECT='TRUE';
      PINUSE='UNSPEC';
    'B':
      PIN_NUMBER='(2)';
      PIN_TYPE='UNSPEC';
      NO_LOAD_CHECK='BOTH';
      NO_IO_CHECK='BOTH';
      ALLOW_CONNECT='TRUE';
      PINUSE='UNSPEC';
  end_pin;
  body
      PART_NAME='CAPP';
      PHYS_DES_PREFIX='C';
      ENVCOMP='';
      PART_NUMBER='724613-067';
      JEDEC_TYPE='SMC7343B';
      VALUE='220uF';
      RATED_VOLTAGE='4V';
      TOL='20%';
      CLASS='DISCRETE';
      DESCRIPTION='CAPS,TA-P,V,220.000 uF,4.000V,+/- 20%';
      HEIGHT='0.075 IN';
      COMPONENT_TYPE='SMTOTHER';
      LEAD_LENGTH='';
      LPID='481';
      SPEED_URL='http://speed.intel.com:8081/speed/module/pdm/item/pdm_item_deta~
il_direct.asp?item_cde=724613-067&item_rev=01&url_param=unused';
      STATUS='';
      RPL='';
      AML='';
      BUS_UNIT='';
      DAYS='';
      PARENT_PART_TYPE='CAPP';
      PARENT_PPT='CAPP';
      PARENT_PPT_PART='CAPP_7343-220UF,4V,20%,POSCAP,724613-067';
  end_body;
end_primitive;
primitive 'CAPP_7343HLF-330UF,10V,20%,POSA';
  pin
    'A':
      PIN_NUMBER='(1)';
      PIN_TYPE='UNSPEC';
      NO_LOAD_CHECK='BOTH';
      NO_IO_CHECK='BOTH';
      ALLOW_CONNECT='TRUE';
      PINUSE='UNSPEC';
    'B':
      PIN_NUMBER='(2)';
      PIN_TYPE='UNSPEC';
      NO_LOAD_CHECK='BOTH';
      NO_IO_CHECK='BOTH';
      ALLOW_CONNECT='TRUE';
      PINUSE='UNSPEC';
  end_pin;
  body
      PART_NAME='CAPP';
      PHYS_DES_PREFIX='C';
      ENVCOMP='YES;YES;YES;UNK;ok;VLD';
      PART_NUMBER='724613-043';
      JEDEC_TYPE='SMC7343HB';
      VALUE='330uF';
      RATED_VOLTAGE='10V';
      TOL='20%';
      CLASS='DISCRETE';
      DESCRIPTION='330uF POLARIZED CAP';
      HEIGHT='0.157 IN';
      COMPONENT_TYPE='SMTOTHER';
      LEAD_LENGTH='';
      LPID='481';
      SPEED_URL='http://speed.intel.com:8081/speed/module/pdm/item/pdm_item_deta~
il_direct.asp?item_cde=724613-043&item_rev=01&url_param=unused';
      STATUS='Conditional';
      RPL='YES';
      AML='2';
      BUS_UNIT='SMO_BOARDS';
      DAYS='70';
      PARENT_PART_TYPE='CAPP';
      PARENT_PPT='CAPP';
      PARENT_PPT_PART='CAPP_7343HLF-330UF,10V,20%,POSCAP,724613-043';
  end_body;
end_primitive;
primitive 'CAPP_7343LF-330UF,6.3V,20%,POSA';
  pin
    'A':
      PIN_NUMBER='(1)';
      PIN_TYPE='UNSPEC';
      NO_LOAD_CHECK='BOTH';
      NO_IO_CHECK='BOTH';
      ALLOW_CONNECT='TRUE';
      PINUSE='UNSPEC';
    'B':
      PIN_NUMBER='(2)';
      PIN_TYPE='UNSPEC';
      NO_LOAD_CHECK='BOTH';
      NO_IO_CHECK='BOTH';
      ALLOW_CONNECT='TRUE';
      PINUSE='UNSPEC';
  end_pin;
  body
      PART_NAME='CAPP';
      PHYS_DES_PREFIX='C';
      ENVCOMP='YES;YES;YES;UNK;ok;VLD';
      PART_NUMBER='724613-042';
      JEDEC_TYPE='SMC7343B';
      VALUE='330uF';
      RATED_VOLTAGE='6.3V';
      TOL='20%';
      CLASS='DISCRETE';
      DESCRIPTION='330uF POLARIZED CAP';
      HEIGHT='0.150 IN';
      COMPONENT_TYPE='SMTOTHER';
      LEAD_LENGTH='';
      LPID='481';
      SPEED_URL='http://speed.intel.com:8081/speed/module/pdm/item/pdm_item_deta~
il_direct.asp?item_cde=724613-042&item_rev=01&url_param=unused';
      STATUS='Conditional';
      RPL='YES';
      AML='4';
      BUS_UNIT='SMO_BOARDS';
      DAYS='56';
      PARENT_PART_TYPE='CAPP';
      PARENT_PPT='CAPP';
      PARENT_PPT_PART='CAPP_7343LF-330UF,6.3V,20%,POSCAP,724613-042';
  end_body;
end_primitive;
primitive 'CAPP_SM-470UF,2V,20%,ALUM,6990A';
  pin
    'A':
      PIN_NUMBER='(1)';
      PIN_TYPE='UNSPEC';
      NO_LOAD_CHECK='BOTH';
      NO_IO_CHECK='BOTH';
      ALLOW_CONNECT='TRUE';
      PINUSE='UNSPEC';
    'B':
      PIN_NUMBER='(2)';
      PIN_TYPE='UNSPEC';
      NO_LOAD_CHECK='BOTH';
      NO_IO_CHECK='BOTH';
      ALLOW_CONNECT='TRUE';
      PINUSE='UNSPEC';
  end_pin;
  body
      PART_NAME='CAPP';
      PHYS_DES_PREFIX='C';
      ENVCOMP='YES;YES;YES;UNK;ok;VLD';
      PART_NUMBER='699013-031';
      JEDEC_TYPE='SMC3018B';
      VALUE='470uF';
      RATED_VOLTAGE='2V';
      TOL='20%';
      CLASS='DISCRETE';
      DESCRIPTION='470uF POLARIZED CAP';
      HEIGHT='0.083 IN';
      COMPONENT_TYPE='SMTOTHER';
      LEAD_LENGTH='';
      LPID='481';
      SPEED_URL='http://speed.intel.com:8081/speed/module/pdm/item/pdm_item_deta~
il_direct.asp?item_cde=699013-031&item_rev=01&url_param=unused';
      STATUS='Conditional';
      RPL='NO';
      AML='1';
      BUS_UNIT='SMO_BOARDS';
      DAYS='42';
      PARENT_PART_TYPE='CAPP';
      PARENT_PPT='CAPP';
      PARENT_PPT_PART='CAPP_SM-470UF,2V,20%,ALUM,699013-031';
  end_body;
end_primitive;
primitive 'CAP_0402-0.027UF,16V,10%,X7R,AA';
  pin
    'A':
      PIN_NUMBER='(1)';
      PINUSE='UNSPEC';
      NO_LOAD_CHECK='BOTH';
      NO_IO_CHECK='BOTH';
      ALLOW_CONNECT='TRUE';
      PIN_GROUP='1';
    'B':
      PIN_NUMBER='(2)';
      PINUSE='UNSPEC';
      NO_LOAD_CHECK='BOTH';
      NO_IO_CHECK='BOTH';
      ALLOW_CONNECT='TRUE';
      PIN_GROUP='1';
  end_pin;
  body
      PART_NAME='CAP';
      PHYS_DES_PREFIX='C';
      ENVCOMP='UNK;UNK;UNK;UNK;ok;CIP';
      PART_NUMBER='A36096-129';
      JEDEC_TYPE='SMC0402A';
      ALT_SYMBOLS='(SMX0402,SMX0402A,SMX0402B)';
      VALUE='0.027uF';
      RATED_VOLTAGE='16V';
      TOL='10%';
      CLASS='DISCRETE';
      DESCRIPTION='CHIP0402';
      HEIGHT='0.022 IN';
      COMPONENT_TYPE='CHIP0402';
      LEAD_LENGTH='';
      LPID='1142';
      SPEED_URL='http://speed.intel.com:8081/speed/module/pdm/item/pdm_item_deta~
il_direct.asp?item_cde=A36096-129&item_rev=01&url_param=unused';
      STATUS='Design';
      RPL='YES';
      AML='2';
      BUS_UNIT='SMO_BOARDS';
      DAYS='???';
      PARENT_PART_TYPE='CAP_0402';
      PARENT_PPT='CAP';
      PARENT_PPT_PART='CAP_0402-0.027UF,16V,10%,X7R,A36096-129';
  end_body;
end_primitive;
primitive 'CAP_0402-0.047UF,25V,10%,X7R,AA';
  pin
    'A':
      PIN_NUMBER='(1)';
      PINUSE='UNSPEC';
      NO_LOAD_CHECK='BOTH';
      NO_IO_CHECK='BOTH';
      ALLOW_CONNECT='TRUE';
      PIN_GROUP='1';
    'B':
      PIN_NUMBER='(2)';
      PINUSE='UNSPEC';
      NO_LOAD_CHECK='BOTH';
      NO_IO_CHECK='BOTH';
      ALLOW_CONNECT='TRUE';
      PIN_GROUP='1';
  end_pin;
  body
      PART_NAME='CAP';
      PHYS_DES_PREFIX='C';
      ENVCOMP='YES;YES;YES;UNK;ok;VLD';
      PART_NUMBER='A36096-090';
      JEDEC_TYPE='SMC0402A';
      ALT_SYMBOLS='(SMX0402,SMX0402A,SMX0402B)';
      VALUE='0.047uF';
      RATED_VOLTAGE='25V';
      TOL='10%';
      CLASS='DISCRETE';
      DESCRIPTION='CHIP0402';
      HEIGHT='0.020 IN';
      COMPONENT_TYPE='CHIP0402';
      LEAD_LENGTH='';
      LPID='1142';
      SPEED_URL='http://speed.intel.com:8081/speed/module/pdm/item/pdm_item_deta~
il_direct.asp?item_cde=A36096-090&item_rev=01&url_param=unused';
      STATUS='Conditional';
      RPL='YES';
      AML='5';
      BUS_UNIT='SMO_BOARDS';
      DAYS='14';
      PARENT_PART_TYPE='CAP_0402';
      PARENT_PPT='CAP';
      PARENT_PPT_PART='CAP_0402-0.047UF,25V,10%,X7R,A36096-090';
  end_body;
end_primitive;
primitive 'CAP_0402-0.220UF,16V,10%,X7R,AA';
  pin
    'A':
      PIN_NUMBER='(1)';
      PINUSE='UNSPEC';
      NO_LOAD_CHECK='BOTH';
      NO_IO_CHECK='BOTH';
      ALLOW_CONNECT='TRUE';
      PIN_GROUP='1';
    'B':
      PIN_NUMBER='(2)';
      PINUSE='UNSPEC';
      NO_LOAD_CHECK='BOTH';
      NO_IO_CHECK='BOTH';
      ALLOW_CONNECT='TRUE';
      PIN_GROUP='1';
  end_pin;
  body
      PART_NAME='CAP';
      PHYS_DES_PREFIX='C';
      ENVCOMP='YES;YES;YES;UNK;ok;VLD';
      PART_NUMBER='A36096-104';
      JEDEC_TYPE='SMC0402A';
      ALT_SYMBOLS='(SMX0402,SMX0402A,SMX0402B)';
      VALUE='0.220uF';
      RATED_VOLTAGE='16V';
      TOL='10%';
      CLASS='DISCRETE';
      DESCRIPTION='CHIP0402';
      HEIGHT='0.022 IN';
      COMPONENT_TYPE='CHIP0402';
      LEAD_LENGTH='';
      LPID='1142';
      SPEED_URL='http://speed.intel.com:8081/speed/module/pdm/item/pdm_item_deta~
il_direct.asp?item_cde=A36096-104&item_rev=01&url_param=unused';
      STATUS='Conditional';
      RPL='YES';
      AML='3';
      BUS_UNIT='SMO_BOARDS';
      DAYS='56';
      PARENT_PART_TYPE='CAP_0402';
      PARENT_PPT='CAP';
      PARENT_PPT_PART='CAP_0402-0.220UF,16V,10%,X7R,A36096-104';
  end_body;
end_primitive;
primitive 'CAP_0402-0.22UF,16V,10%,X7R,A3A';
  pin
    'A':
      PIN_NUMBER='(1)';
      PINUSE='UNSPEC';
      NO_LOAD_CHECK='BOTH';
      NO_IO_CHECK='BOTH';
      ALLOW_CONNECT='TRUE';
      PIN_GROUP='1';
    'B':
      PIN_NUMBER='(2)';
      PINUSE='UNSPEC';
      NO_LOAD_CHECK='BOTH';
      NO_IO_CHECK='BOTH';
      ALLOW_CONNECT='TRUE';
      PIN_GROUP='1';
  end_pin;
  body
      PART_NAME='CAP';
      PHYS_DES_PREFIX='C';
      ENVCOMP='';
      PART_NUMBER='A36096-155';
      JEDEC_TYPE='SMC0402A';
      ALT_SYMBOLS='(SMX0402,SMX0402A,SMX0402B)';
      VALUE='0.22uF';
      RATED_VOLTAGE='16V';
      TOL='10%';
      CLASS='DISCRETE';
      DESCRIPTION='CAPC,X7R,0402,0.22UF,16.00V,+/- 10%';
      HEIGHT='0.022 IN';
      COMPONENT_TYPE='CHIP0402';
      LEAD_LENGTH='';
      LPID='1142';
      SPEED_URL='http://speed.intel.com:8081/speed/module/pdm/item/pdm_item_deta~
il_direct.asp?item_cde=A36096-155&item_rev=01&url_param=unused';
      STATUS='';
      RPL='';
      AML='';
      BUS_UNIT='';
      DAYS='';
      PARENT_PART_TYPE='CAP_0402';
      PARENT_PPT='CAP';
      PARENT_PPT_PART='CAP_0402-0.22UF,16V,10%,X7R,A36096-155';
  end_body;
end_primitive;
primitive 'CAP_0402-1.0UF,16V,10%,X6S,D97A';
  pin
    'A':
      PIN_NUMBER='(1)';
      PINUSE='UNSPEC';
      NO_LOAD_CHECK='BOTH';
      NO_IO_CHECK='BOTH';
      ALLOW_CONNECT='TRUE';
      PIN_GROUP='1';
    'B':
      PIN_NUMBER='(2)';
      PINUSE='UNSPEC';
      NO_LOAD_CHECK='BOTH';
      NO_IO_CHECK='BOTH';
      ALLOW_CONNECT='TRUE';
      PIN_GROUP='1';
  end_pin;
  body
      PART_NAME='CAP';
      PHYS_DES_PREFIX='C';
      ENVCOMP='';
      PART_NUMBER='D97712-011';
      JEDEC_TYPE='SMC0402A';
      ALT_SYMBOLS='(SMX0402,SMX0402A,SMX0402B)';
      VALUE='1.0uF';
      RATED_VOLTAGE='16V';
      TOL='10%';
      CLASS='DISCRETE';
      DESCRIPTION='CAPC,X6S,0402,1.00UF,16.00V,+/- 10%';
      HEIGHT='0.024 IN';
      COMPONENT_TYPE='CHIP0402';
      LEAD_LENGTH='';
      LPID='1142';
      SPEED_URL='http://speed.intel.com:8081/speed/module/pdm/item/pdm_item_deta~
il_direct.asp?item_cde=D97712-011&item_rev=01&url_param=unused';
      STATUS='';
      RPL='';
      AML='';
      BUS_UNIT='';
      DAYS='';
      PARENT_PART_TYPE='CAP_0402';
      PARENT_PPT='CAP';
      PARENT_PPT_PART='CAP_0402-1.0UF,16V,10%,X6S,D97712-011';
  end_body;
end_primitive;
primitive 'CAP_0402-1.0UF,16V,10%,X7S,G71A';
  pin
    'A':
      PIN_NUMBER='(1)';
      PINUSE='UNSPEC';
      NO_LOAD_CHECK='BOTH';
      NO_IO_CHECK='BOTH';
      ALLOW_CONNECT='TRUE';
      PIN_GROUP='1';
    'B':
      PIN_NUMBER='(2)';
      PINUSE='UNSPEC';
      NO_LOAD_CHECK='BOTH';
      NO_IO_CHECK='BOTH';
      ALLOW_CONNECT='TRUE';
      PIN_GROUP='1';
  end_pin;
  body
      PART_NAME='CAP';
      PHYS_DES_PREFIX='C';
      ENVCOMP='UNK;UNK;UNK;UNK;ok;CIP';
      PART_NUMBER='G71842-007';
      JEDEC_TYPE='SMC0402A';
      ALT_SYMBOLS='(SMX0402,SMX0402A,SMX0402B)';
      VALUE='1.0uF';
      RATED_VOLTAGE='16V';
      TOL='10%';
      CLASS='DISCRETE';
      DESCRIPTION='CAPC,X7S,0402,1.00UF,16.00V,+/- 10%';
      HEIGHT='0.024 IN';
      COMPONENT_TYPE='CHIP0402';
      LEAD_LENGTH='';
      LPID='1142';
      SPEED_URL='http://speed.intel.com:8081/speed/module/pdm/item/pdm_item_deta~
il_direct.asp?item_cde=G71842-007&item_rev=01&url_param=unused';
      STATUS='Design';
      RPL='NO';
      AML='1';
      BUS_UNIT='SMO_BOARDS';
      DAYS='???';
      PARENT_PART_TYPE='CAP_0402';
      PARENT_PPT='CAP';
      PARENT_PPT_PART='CAP_0402-1.0UF,16V,10%,X7S,G71842-007';
  end_body;
end_primitive;
primitive 'CAP_0402-1.0UF,6.3V,10%,EMPTY,A';
  pin
    'A':
      PIN_NUMBER='(1)';
      PINUSE='UNSPEC';
      NO_LOAD_CHECK='BOTH';
      NO_IO_CHECK='BOTH';
      ALLOW_CONNECT='TRUE';
      PIN_GROUP='1';
    'B':
      PIN_NUMBER='(2)';
      PINUSE='UNSPEC';
      NO_LOAD_CHECK='BOTH';
      NO_IO_CHECK='BOTH';
      ALLOW_CONNECT='TRUE';
      PIN_GROUP='1';
  end_pin;
  body
      PART_NAME='CAP';
      PHYS_DES_PREFIX='C';
      ENVCOMP='YES;YES;YES;UNK;ok;VLD';
      PART_NUMBER='D97712-004';
      JEDEC_TYPE='SMC0402A';
      ALT_SYMBOLS='(SMX0402,SMX0402A,SMX0402B)';
      VALUE='NA';
      RATED_VOLTAGE='6.3V';
      TOL='10%';
      CLASS='DISCRETE';
      DESCRIPTION='CHIP0402';
      HEIGHT='0.022 IN';
      COMPONENT_TYPE='CHIP0402';
      LEAD_LENGTH='';
      LPID='1142';
      SPEED_URL='http://speed.intel.com:8081/speed/module/pdm/item/pdm_item_deta~
il_direct.asp?item_cde=D97712-004&item_rev=01&url_param=unused';
      STATUS='Conditional';
      RPL='NO';
      AML='4';
      BUS_UNIT='SMO_BOARDS';
      DAYS='???';
      PARENT_PART_TYPE='CAP_0402';
      PARENT_PPT='CAP';
      PARENT_PPT_PART='CAP_0402-1.0UF,6.3V,10%,EMPTY,D97712-004';
  end_body;
end_primitive;
primitive 'CAP_0402LF-0.022UF,16V,10%,X7RA';
  pin
    'A':
      PIN_NUMBER='(1)';
      PINUSE='UNSPEC';
      NO_LOAD_CHECK='BOTH';
      NO_IO_CHECK='BOTH';
      ALLOW_CONNECT='TRUE';
      PIN_GROUP='1';
    'B':
      PIN_NUMBER='(2)';
      PINUSE='UNSPEC';
      NO_LOAD_CHECK='BOTH';
      NO_IO_CHECK='BOTH';
      ALLOW_CONNECT='TRUE';
      PIN_GROUP='1';
  end_pin;
  body
      PART_NAME='CAP';
      PHYS_DES_PREFIX='C';
      ENVCOMP='YES;YES;YES;UNK;ok;VLD';
      PART_NUMBER='A36096-073';
      JEDEC_TYPE='SMC0402A';
      ALT_SYMBOLS='(SMX0402,SMX0402A,SMX0402B)';
      VALUE='0.022uF';
      RATED_VOLTAGE='16V';
      TOL='10%';
      CLASS='DISCRETE';
      DESCRIPTION='CHIP0402';
      HEIGHT='0.024 IN';
      COMPONENT_TYPE='CHIP0402';
      LEAD_LENGTH='';
      LPID='1142';
      SPEED_URL='http://speed.intel.com:8081/speed/module/pdm/item/pdm_item_deta~
il_direct.asp?item_cde=A36096-073&item_rev=01&url_param=unused';
      STATUS='Approved';
      RPL='NO';
      AML='8';
      BUS_UNIT='SMO_BOARDS';
      DAYS='56';
      PARENT_PART_TYPE='CAP';
      PARENT_PPT='CAP';
      PARENT_PPT_PART='CAP_0402LF-0.022UF,16V,10%,X7R,A36096-073';
  end_body;
end_primitive;
primitive 'CAP_0402LF-0.039UF,25V,10%,X7RA';
  pin
    'A':
      PIN_NUMBER='(1)';
      PINUSE='UNSPEC';
      NO_LOAD_CHECK='BOTH';
      NO_IO_CHECK='BOTH';
      ALLOW_CONNECT='TRUE';
      PIN_GROUP='1';
    'B':
      PIN_NUMBER='(2)';
      PINUSE='UNSPEC';
      NO_LOAD_CHECK='BOTH';
      NO_IO_CHECK='BOTH';
      ALLOW_CONNECT='TRUE';
      PIN_GROUP='1';
  end_pin;
  body
      PART_NAME='CAP';
      PHYS_DES_PREFIX='C';
      ENVCOMP='YES;YES;YES;UNK;ok;VLD';
      PART_NUMBER='A36096-063';
      JEDEC_TYPE='SMC0402A';
      ALT_SYMBOLS='(SMX0402,SMX0402A,SMX0402B)';
      VALUE='0.039uF';
      RATED_VOLTAGE='25V';
      TOL='10%';
      CLASS='DISCRETE';
      DESCRIPTION='CHIP0402';
      HEIGHT='0.024 IN';
      COMPONENT_TYPE='CHIP0402';
      LEAD_LENGTH='';
      LPID='1142';
      SPEED_URL='http://speed.intel.com:8081/speed/module/pdm/item/pdm_item_deta~
il_direct.asp?item_cde=A36096-063&item_rev=01&url_param=unused';
      STATUS='Approved';
      RPL='NO';
      AML='7';
      BUS_UNIT='SMO_BOARDS';
      DAYS='56';
      PARENT_PART_TYPE='CAP';
      PARENT_PPT='CAP';
      PARENT_PPT_PART='CAP_0402LF-0.039UF,25V,10%,X7R,A36096-063';
  end_body;
end_primitive;
primitive 'CAP_0402LF-10.0PF,50V,5%,COG,AA';
  pin
    'A':
      PIN_NUMBER='(1)';
      PINUSE='UNSPEC';
      NO_LOAD_CHECK='BOTH';
      NO_IO_CHECK='BOTH';
      ALLOW_CONNECT='TRUE';
      PIN_GROUP='1';
    'B':
      PIN_NUMBER='(2)';
      PINUSE='UNSPEC';
      NO_LOAD_CHECK='BOTH';
      NO_IO_CHECK='BOTH';
      ALLOW_CONNECT='TRUE';
      PIN_GROUP='1';
  end_pin;
  body
      PART_NAME='CAP';
      PHYS_DES_PREFIX='C';
      ENVCOMP='YES;YES;YES;UNK;ok;VLD';
      PART_NUMBER='A36094-025';
      JEDEC_TYPE='SMC0402A';
      ALT_SYMBOLS='(SMX0402,SMX0402A,SMX0402B)';
      VALUE='10.0pF';
      RATED_VOLTAGE='50V';
      TOL='5%';
      CLASS='DISCRETE';
      DESCRIPTION='CHIP0402';
      HEIGHT='0.024 IN';
      COMPONENT_TYPE='CHIP0402';
      LEAD_LENGTH='';
      LPID='1142';
      SPEED_URL='http://speed.intel.com:8081/speed/module/pdm/item/pdm_item_deta~
il_direct.asp?item_cde=A36094-025&item_rev=01&url_param=unused';
      STATUS='Approved';
      RPL='YES';
      AML='12';
      BUS_UNIT='SMO_BOARDS';
      DAYS='56';
      PARENT_PART_TYPE='CAP';
      PARENT_PPT='CAP';
      PARENT_PPT_PART='CAP_0402LF-10.0PF,50V,5%,COG,A36094-025';
  end_body;
end_primitive;
primitive 'CAP_0402LF-100.0PF,50V,5%,COG,A';
  pin
    'A':
      PIN_NUMBER='(1)';
      PINUSE='UNSPEC';
      NO_LOAD_CHECK='BOTH';
      NO_IO_CHECK='BOTH';
      ALLOW_CONNECT='TRUE';
      PIN_GROUP='1';
    'B':
      PIN_NUMBER='(2)';
      PINUSE='UNSPEC';
      NO_LOAD_CHECK='BOTH';
      NO_IO_CHECK='BOTH';
      ALLOW_CONNECT='TRUE';
      PIN_GROUP='1';
  end_pin;
  body
      PART_NAME='CAP';
      PHYS_DES_PREFIX='C';
      ENVCOMP='YES;YES;YES;UNK;ok;VLD';
      PART_NUMBER='A36095-026';
      JEDEC_TYPE='SMC0402A';
      ALT_SYMBOLS='(SMX0402,SMX0402A,SMX0402B)';
      VALUE='100.0pF';
      RATED_VOLTAGE='50V';
      TOL='5%';
      CLASS='DISCRETE';
      DESCRIPTION='CHIP0402';
      HEIGHT='0.024 IN';
      COMPONENT_TYPE='CHIP0402';
      LEAD_LENGTH='';
      LPID='1142';
      SPEED_URL='http://speed.intel.com:8081/speed/module/pdm/item/pdm_item_deta~
il_direct.asp?item_cde=A36095-026&item_rev=01&url_param=unused';
      STATUS='Approved';
      RPL='NO';
      AML='12';
      BUS_UNIT='SMO_BOARDS';
      DAYS='56';
      PARENT_PART_TYPE='CAP';
      PARENT_PPT='CAP';
      PARENT_PPT_PART='CAP_0402LF-100.0PF,50V,5%,COG,A36095-026';
  end_body;
end_primitive;
primitive 'CAP_0402LF-1000PF,50V,10%,EMPTA';
  pin
    'A':
      PIN_NUMBER='(1)';
      PINUSE='UNSPEC';
      NO_LOAD_CHECK='BOTH';
      NO_IO_CHECK='BOTH';
      ALLOW_CONNECT='TRUE';
      PIN_GROUP='1';
    'B':
      PIN_NUMBER='(2)';
      PINUSE='UNSPEC';
      NO_LOAD_CHECK='BOTH';
      NO_IO_CHECK='BOTH';
      ALLOW_CONNECT='TRUE';
      PIN_GROUP='1';
  end_pin;
  body
      PART_NAME='CAP';
      PHYS_DES_PREFIX='C';
      ENVCOMP='YES;YES;YES;UNK;ok;CIP';
      PART_NUMBER='A36096-046';
      JEDEC_TYPE='SMC0402A';
      ALT_SYMBOLS='(SMX0402,SMX0402A,SMX0402B)';
      VALUE='NA';
      RATED_VOLTAGE='50V';
      TOL='10%';
      CLASS='DISCRETE';
      DESCRIPTION='CHIP0402';
      HEIGHT='0.024 IN';
      COMPONENT_TYPE='CHIP0402';
      LEAD_LENGTH='';
      LPID='1142';
      SPEED_URL='http://speed.intel.com:8081/speed/module/pdm/item/pdm_item_deta~
il_direct.asp?item_cde=A36096-046&item_rev=01&url_param=unused';
      STATUS='Approved';
      RPL='YES';
      AML='14';
      BUS_UNIT='SMO_BOARDS';
      DAYS='56';
      PARENT_PART_TYPE='CAP';
      PARENT_PPT='CAP';
      PARENT_PPT_PART='CAP_0402LF-1000PF,50V,10%,EMPTY,A36096-046';
  end_body;
end_primitive;
primitive 'CAP_0402LF-1000PF,50V,10%,X7R,A';
  pin
    'A':
      PIN_NUMBER='(1)';
      PINUSE='UNSPEC';
      NO_LOAD_CHECK='BOTH';
      NO_IO_CHECK='BOTH';
      ALLOW_CONNECT='TRUE';
      PIN_GROUP='1';
    'B':
      PIN_NUMBER='(2)';
      PINUSE='UNSPEC';
      NO_LOAD_CHECK='BOTH';
      NO_IO_CHECK='BOTH';
      ALLOW_CONNECT='TRUE';
      PIN_GROUP='1';
  end_pin;
  body
      PART_NAME='CAP';
      PHYS_DES_PREFIX='C';
      ENVCOMP='YES;YES;YES;UNK;ok;CIP';
      PART_NUMBER='A36096-046';
      JEDEC_TYPE='SMC0402A';
      ALT_SYMBOLS='(SMX0402,SMX0402A,SMX0402B)';
      VALUE='1000pF';
      RATED_VOLTAGE='50V';
      TOL='10%';
      CLASS='DISCRETE';
      DESCRIPTION='CHIP0402';
      HEIGHT='0.024 IN';
      COMPONENT_TYPE='CHIP0402';
      LEAD_LENGTH='';
      LPID='1142';
      SPEED_URL='http://speed.intel.com:8081/speed/module/pdm/item/pdm_item_deta~
il_direct.asp?item_cde=A36096-046&item_rev=01&url_param=unused';
      STATUS='Approved';
      RPL='YES';
      AML='14';
      BUS_UNIT='SMO_BOARDS';
      DAYS='56';
      PARENT_PART_TYPE='CAP';
      PARENT_PPT='CAP';
      PARENT_PPT_PART='CAP_0402LF-1000PF,50V,10%,X7R,A36096-046';
  end_body;
end_primitive;
primitive 'CAP_0402LF-12.0PF,50V,5%,COG,AA';
  pin
    'A':
      PIN_NUMBER='(1)';
      PINUSE='UNSPEC';
      NO_LOAD_CHECK='BOTH';
      NO_IO_CHECK='BOTH';
      ALLOW_CONNECT='TRUE';
      PIN_GROUP='1';
    'B':
      PIN_NUMBER='(2)';
      PINUSE='UNSPEC';
      NO_LOAD_CHECK='BOTH';
      NO_IO_CHECK='BOTH';
      ALLOW_CONNECT='TRUE';
      PIN_GROUP='1';
  end_pin;
  body
      PART_NAME='CAP';
      PHYS_DES_PREFIX='C';
      ENVCOMP='YES;YES;YES;UNK;ok;VLD';
      PART_NUMBER='A36095-043';
      JEDEC_TYPE='SMC0402A';
      ALT_SYMBOLS='(SMX0402,SMX0402A,SMX0402B)';
      VALUE='12.0pF';
      RATED_VOLTAGE='50V';
      TOL='5%';
      CLASS='DISCRETE';
      DESCRIPTION='CHIP0402';
      HEIGHT='0.024 IN';
      COMPONENT_TYPE='CHIP0402';
      LEAD_LENGTH='';
      LPID='1142';
      SPEED_URL='http://speed.intel.com:8081/speed/module/pdm/item/pdm_item_deta~
il_direct.asp?item_cde=A36095-043&item_rev=01&url_param=unused';
      STATUS='Approved';
      RPL='YES';
      AML='8';
      BUS_UNIT='SMO_BOARDS';
      DAYS='56';
      PARENT_PART_TYPE='CAP';
      PARENT_PPT='CAP';
      PARENT_PPT_PART='CAP_0402LF-12.0PF,50V,5%,COG,A36095-043';
  end_body;
end_primitive;
primitive 'CAP_0402LF-15.0PF,50V,5%,COG,AA';
  pin
    'A':
      PIN_NUMBER='(1)';
      PINUSE='UNSPEC';
      NO_LOAD_CHECK='BOTH';
      NO_IO_CHECK='BOTH';
      ALLOW_CONNECT='TRUE';
      PIN_GROUP='1';
    'B':
      PIN_NUMBER='(2)';
      PINUSE='UNSPEC';
      NO_LOAD_CHECK='BOTH';
      NO_IO_CHECK='BOTH';
      ALLOW_CONNECT='TRUE';
      PIN_GROUP='1';
  end_pin;
  body
      PART_NAME='CAP';
      PHYS_DES_PREFIX='C';
      ENVCOMP='YES;YES;YES;UNK;ok;VLD';
      PART_NUMBER='A36095-047';
      JEDEC_TYPE='SMC0402A';
      ALT_SYMBOLS='(SMX0402,SMX0402A,SMX0402B)';
      VALUE='15.0pF';
      RATED_VOLTAGE='50V';
      TOL='5%';
      CLASS='DISCRETE';
      DESCRIPTION='CHIP0402';
      HEIGHT='0.024 IN';
      COMPONENT_TYPE='CHIP0402';
      LEAD_LENGTH='';
      LPID='1142';
      SPEED_URL='http://speed.intel.com:8081/speed/module/pdm/item/pdm_item_deta~
il_direct.asp?item_cde=A36095-047&item_rev=01&url_param=unused';
      STATUS='Approved';
      RPL='YES';
      AML='13';
      BUS_UNIT='SMO_BOARDS';
      DAYS='56';
      PARENT_PART_TYPE='CAP';
      PARENT_PPT='CAP';
      PARENT_PPT_PART='CAP_0402LF-15.0PF,50V,5%,COG,A36095-047';
  end_body;
end_primitive;
primitive 'CAP_0402LF-2200PF,50V,10%,X7R,A';
  pin
    'A':
      PIN_NUMBER='(1)';
      PINUSE='UNSPEC';
      NO_LOAD_CHECK='BOTH';
      NO_IO_CHECK='BOTH';
      ALLOW_CONNECT='TRUE';
      PIN_GROUP='1';
    'B':
      PIN_NUMBER='(2)';
      PINUSE='UNSPEC';
      NO_LOAD_CHECK='BOTH';
      NO_IO_CHECK='BOTH';
      ALLOW_CONNECT='TRUE';
      PIN_GROUP='1';
  end_pin;
  body
      PART_NAME='CAP';
      PHYS_DES_PREFIX='C';
      ENVCOMP='YES;YES;YES;UNK;ok;CIP';
      PART_NUMBER='A36096-075';
      JEDEC_TYPE='SMC0402A';
      ALT_SYMBOLS='(SMX0402,SMX0402A,SMX0402B)';
      VALUE='2200pF';
      RATED_VOLTAGE='50V';
      TOL='10%';
      CLASS='DISCRETE';
      DESCRIPTION='CHIP0402';
      HEIGHT='0.024 IN';
      COMPONENT_TYPE='CHIP0402';
      LEAD_LENGTH='';
      LPID='1142';
      SPEED_URL='http://speed.intel.com:8081/speed/module/pdm/item/pdm_item_deta~
il_direct.asp?item_cde=A36096-075&item_rev=01&url_param=unused';
      STATUS='Approved';
      RPL='NO';
      AML='7';
      BUS_UNIT='SMO_BOARDS';
      DAYS='56';
      PARENT_PART_TYPE='CAP';
      PARENT_PPT='CAP';
      PARENT_PPT_PART='CAP_0402LF-2200PF,50V,10%,X7R,A36096-075';
  end_body;
end_primitive;
primitive 'CAP_0402LF-220PF,50V,10%,X7R,AA';
  pin
    'A':
      PIN_NUMBER='(1)';
      PINUSE='UNSPEC';
      NO_LOAD_CHECK='BOTH';
      NO_IO_CHECK='BOTH';
      ALLOW_CONNECT='TRUE';
      PIN_GROUP='1';
    'B':
      PIN_NUMBER='(2)';
      PINUSE='UNSPEC';
      NO_LOAD_CHECK='BOTH';
      NO_IO_CHECK='BOTH';
      ALLOW_CONNECT='TRUE';
      PIN_GROUP='1';
  end_pin;
  body
      PART_NAME='CAP';
      PHYS_DES_PREFIX='C';
      ENVCOMP='YES;YES;YES;UNK;ok;VLD';
      PART_NUMBER='A36096-050';
      JEDEC_TYPE='SMC0402A';
      ALT_SYMBOLS='(SMX0402,SMX0402A,SMX0402B)';
      VALUE='220pF';
      RATED_VOLTAGE='50V';
      TOL='10%';
      CLASS='DISCRETE';
      DESCRIPTION='CHIP0402';
      HEIGHT='0.024 IN';
      COMPONENT_TYPE='CHIP0402';
      LEAD_LENGTH='';
      LPID='1142';
      SPEED_URL='http://speed.intel.com:8081/speed/module/pdm/item/pdm_item_deta~
il_direct.asp?item_cde=A36096-050&item_rev=01&url_param=unused';
      STATUS='Approved';
      RPL='YES';
      AML='12';
      BUS_UNIT='SMO_BOARDS';
      DAYS='56';
      PARENT_PART_TYPE='CAP';
      PARENT_PPT='CAP';
      PARENT_PPT_PART='CAP_0402LF-220PF,50V,10%,X7R,A36096-050';
  end_body;
end_primitive;
primitive 'CAP_0402LF-270PF,50V,10%,X7R,AA';
  pin
    'A':
      PIN_NUMBER='(1)';
      PINUSE='UNSPEC';
      NO_LOAD_CHECK='BOTH';
      NO_IO_CHECK='BOTH';
      ALLOW_CONNECT='TRUE';
      PIN_GROUP='1';
    'B':
      PIN_NUMBER='(2)';
      PINUSE='UNSPEC';
      NO_LOAD_CHECK='BOTH';
      NO_IO_CHECK='BOTH';
      ALLOW_CONNECT='TRUE';
      PIN_GROUP='1';
  end_pin;
  body
      PART_NAME='CAP';
      PHYS_DES_PREFIX='C';
      ENVCOMP='YES;YES;YES;UNK;ok;VLD';
      PART_NUMBER='A36096-065';
      JEDEC_TYPE='SMC0402A';
      ALT_SYMBOLS='(SMX0402,SMX0402A,SMX0402B)';
      VALUE='270pF';
      RATED_VOLTAGE='50V';
      TOL='10%';
      CLASS='DISCRETE';
      DESCRIPTION='CHIP0402';
      HEIGHT='0.024 IN';
      COMPONENT_TYPE='CHIP0402';
      LEAD_LENGTH='';
      LPID='1142';
      SPEED_URL='http://speed.intel.com:8081/speed/module/pdm/item/pdm_item_deta~
il_direct.asp?item_cde=A36096-065&item_rev=01&url_param=unused';
      STATUS='Approved';
      RPL='NO';
      AML='7';
      BUS_UNIT='SMO_BOARDS';
      DAYS='56';
      PARENT_PART_TYPE='CAP';
      PARENT_PPT='CAP';
      PARENT_PPT_PART='CAP_0402LF-270PF,50V,10%,X7R,A36096-065';
  end_body;
end_primitive;
primitive 'CAP_0402LF-33.0PF,50V,5%,COG,AA';
  pin
    'A':
      PIN_NUMBER='(1)';
      PINUSE='UNSPEC';
      NO_LOAD_CHECK='BOTH';
      NO_IO_CHECK='BOTH';
      ALLOW_CONNECT='TRUE';
      PIN_GROUP='1';
    'B':
      PIN_NUMBER='(2)';
      PINUSE='UNSPEC';
      NO_LOAD_CHECK='BOTH';
      NO_IO_CHECK='BOTH';
      ALLOW_CONNECT='TRUE';
      PIN_GROUP='1';
  end_pin;
  body
      PART_NAME='CAP';
      PHYS_DES_PREFIX='C';
      ENVCOMP='YES;YES;YES;UNK;ok;CIP';
      PART_NUMBER='A36095-031';
      JEDEC_TYPE='SMC0402A';
      ALT_SYMBOLS='(SMX0402,SMX0402A,SMX0402B)';
      VALUE='33.0pF';
      RATED_VOLTAGE='50V';
      TOL='5%';
      CLASS='DISCRETE';
      DESCRIPTION='CHIP0402';
      HEIGHT='0.024 IN';
      COMPONENT_TYPE='CHIP0402';
      LEAD_LENGTH='';
      LPID='1142';
      SPEED_URL='http://speed.intel.com:8081/speed/module/pdm/item/pdm_item_deta~
il_direct.asp?item_cde=A36095-031&item_rev=01&url_param=unused';
      STATUS='Approved';
      RPL='YES';
      AML='11';
      BUS_UNIT='SMO_BOARDS';
      DAYS='56';
      PARENT_PART_TYPE='CAP';
      PARENT_PPT='CAP';
      PARENT_PPT_PART='CAP_0402LF-33.0PF,50V,5%,COG,A36095-031';
  end_body;
end_primitive;
primitive 'CAP_0402LF-3300PF,50V,10%,EMPTA';
  pin
    'A':
      PIN_NUMBER='(1)';
      PINUSE='UNSPEC';
      NO_LOAD_CHECK='BOTH';
      NO_IO_CHECK='BOTH';
      ALLOW_CONNECT='TRUE';
      PIN_GROUP='1';
    'B':
      PIN_NUMBER='(2)';
      PINUSE='UNSPEC';
      NO_LOAD_CHECK='BOTH';
      NO_IO_CHECK='BOTH';
      ALLOW_CONNECT='TRUE';
      PIN_GROUP='1';
  end_pin;
  body
      PART_NAME='CAP';
      PHYS_DES_PREFIX='C';
      ENVCOMP='YES;YES;YES;UNK;ok;YTC';
      PART_NUMBER='A36096-091';
      JEDEC_TYPE='SMC0402A';
      ALT_SYMBOLS='(SMX0402,SMX0402A,SMX0402B)';
      VALUE='NA';
      RATED_VOLTAGE='50V';
      TOL='10%';
      CLASS='DISCRETE';
      DESCRIPTION='CHIP0402';
      HEIGHT='0.022 IN';
      COMPONENT_TYPE='CHIP0402';
      LEAD_LENGTH='';
      LPID='1142';
      SPEED_URL='http://speed.intel.com:8081/speed/module/pdm/item/pdm_item_deta~
il_direct.asp?item_cde=A36096-091&item_rev=01&url_param=unused';
      STATUS='Approved';
      RPL='YES';
      AML='8';
      BUS_UNIT='SMO_BOARDS';
      DAYS='56';
      PARENT_PART_TYPE='CAP';
      PARENT_PPT='CAP';
      PARENT_PPT_PART='CAP_0402LF-3300PF,50V,10%,EMPTY,A36096-091';
  end_body;
end_primitive;
primitive 'CAP_0402LF-47.0PF,50V,5%,COG,AA';
  pin
    'A':
      PIN_NUMBER='(1)';
      PINUSE='UNSPEC';
      NO_LOAD_CHECK='BOTH';
      NO_IO_CHECK='BOTH';
      ALLOW_CONNECT='TRUE';
      PIN_GROUP='1';
    'B':
      PIN_NUMBER='(2)';
      PINUSE='UNSPEC';
      NO_LOAD_CHECK='BOTH';
      NO_IO_CHECK='BOTH';
      ALLOW_CONNECT='TRUE';
      PIN_GROUP='1';
  end_pin;
  body
      PART_NAME='CAP';
      PHYS_DES_PREFIX='C';
      ENVCOMP='YES;YES;YES;UNK;ok;VLD';
      PART_NUMBER='A36095-025';
      JEDEC_TYPE='SMC0402A';
      ALT_SYMBOLS='(SMX0402,SMX0402A,SMX0402B)';
      VALUE='47.0pF';
      RATED_VOLTAGE='50V';
      TOL='5%';
      CLASS='DISCRETE';
      DESCRIPTION='CHIP0402';
      HEIGHT='0.034 IN';
      COMPONENT_TYPE='CHIP0402';
      LEAD_LENGTH='';
      LPID='1142';
      SPEED_URL='http://speed.intel.com:8081/speed/module/pdm/item/pdm_item_deta~
il_direct.asp?item_cde=A36095-025&item_rev=01&url_param=unused';
      STATUS='Approved';
      RPL='YES';
      AML='10';
      BUS_UNIT='SMO_BOARDS';
      DAYS='56';
      PARENT_PART_TYPE='CAP';
      PARENT_PPT='CAP';
      PARENT_PPT_PART='CAP_0402LF-47.0PF,50V,5%,COG,A36095-025';
  end_body;
end_primitive;
primitive 'CAP_0402LF-47.0PF,50V,5%,EMPTYA';
  pin
    'A':
      PIN_NUMBER='(1)';
      PINUSE='UNSPEC';
      NO_LOAD_CHECK='BOTH';
      NO_IO_CHECK='BOTH';
      ALLOW_CONNECT='TRUE';
      PIN_GROUP='1';
    'B':
      PIN_NUMBER='(2)';
      PINUSE='UNSPEC';
      NO_LOAD_CHECK='BOTH';
      NO_IO_CHECK='BOTH';
      ALLOW_CONNECT='TRUE';
      PIN_GROUP='1';
  end_pin;
  body
      PART_NAME='CAP';
      PHYS_DES_PREFIX='C';
      ENVCOMP='YES;YES;YES;UNK;ok;VLD';
      PART_NUMBER='A36095-025';
      JEDEC_TYPE='SMC0402A';
      ALT_SYMBOLS='(SMX0402,SMX0402A,SMX0402B)';
      VALUE='NA';
      RATED_VOLTAGE='50V';
      TOL='5%';
      CLASS='DISCRETE';
      DESCRIPTION='CHIP0402';
      HEIGHT='0.034 IN';
      COMPONENT_TYPE='CHIP0402';
      LEAD_LENGTH='';
      LPID='1142';
      SPEED_URL='http://speed.intel.com:8081/speed/module/pdm/item/pdm_item_deta~
il_direct.asp?item_cde=A36095-025&item_rev=01&url_param=unused';
      STATUS='Approved';
      RPL='YES';
      AML='10';
      BUS_UNIT='SMO_BOARDS';
      DAYS='56';
      PARENT_PART_TYPE='CAP';
      PARENT_PPT='CAP';
      PARENT_PPT_PART='CAP_0402LF-47.0PF,50V,5%,EMPTY,A36095-025';
  end_body;
end_primitive;
primitive 'CAP_0402LF-4700PF,50V,10%,EMPTA';
  pin
    'A':
      PIN_NUMBER='(1)';
      PINUSE='UNSPEC';
      NO_LOAD_CHECK='BOTH';
      NO_IO_CHECK='BOTH';
      ALLOW_CONNECT='TRUE';
      PIN_GROUP='1';
    'B':
      PIN_NUMBER='(2)';
      PINUSE='UNSPEC';
      NO_LOAD_CHECK='BOTH';
      NO_IO_CHECK='BOTH';
      ALLOW_CONNECT='TRUE';
      PIN_GROUP='1';
  end_pin;
  body
      PART_NAME='CAP';
      PHYS_DES_PREFIX='C';
      ENVCOMP='YES;YES;YES;UNK;ok;CIP';
      PART_NUMBER='A36096-066';
      JEDEC_TYPE='SMC0402A';
      ALT_SYMBOLS='(SMX0402,SMX0402A,SMX0402B)';
      VALUE='NA';
      RATED_VOLTAGE='50V';
      TOL='10%';
      CLASS='DISCRETE';
      DESCRIPTION='CHIP0402';
      HEIGHT='0.024 IN';
      COMPONENT_TYPE='CHIP0402';
      LEAD_LENGTH='';
      LPID='1142';
      SPEED_URL='http://speed.intel.com:8081/speed/module/pdm/item/pdm_item_deta~
il_direct.asp?item_cde=A36096-066&item_rev=01&url_param=unused';
      STATUS='Approved';
      RPL='NO';
      AML='7';
      BUS_UNIT='SMO_BOARDS';
      DAYS='56';
      PARENT_PART_TYPE='CAP';
      PARENT_PPT='CAP';
      PARENT_PPT_PART='CAP_0402LF-4700PF,50V,10%,EMPTY,A36096-066';
  end_body;
end_primitive;
primitive 'CAP_0402LF-470PF,50V,10%,EMPTYA';
  pin
    'A':
      PIN_NUMBER='(1)';
      PINUSE='UNSPEC';
      NO_LOAD_CHECK='BOTH';
      NO_IO_CHECK='BOTH';
      ALLOW_CONNECT='TRUE';
      PIN_GROUP='1';
    'B':
      PIN_NUMBER='(2)';
      PINUSE='UNSPEC';
      NO_LOAD_CHECK='BOTH';
      NO_IO_CHECK='BOTH';
      ALLOW_CONNECT='TRUE';
      PIN_GROUP='1';
  end_pin;
  body
      PART_NAME='CAP';
      PHYS_DES_PREFIX='C';
      ENVCOMP='YES;YES;YES;UNK;ok;VLD';
      PART_NUMBER='A36096-049';
      JEDEC_TYPE='SMC0402A';
      ALT_SYMBOLS='(SMX0402,SMX0402A,SMX0402B)';
      VALUE='NA';
      RATED_VOLTAGE='50V';
      TOL='10%';
      CLASS='DISCRETE';
      DESCRIPTION='CHIP0402';
      HEIGHT='0.024 IN';
      COMPONENT_TYPE='CHIP0402';
      LEAD_LENGTH='';
      LPID='1142';
      SPEED_URL='http://speed.intel.com:8081/speed/module/pdm/item/pdm_item_deta~
il_direct.asp?item_cde=A36096-049&item_rev=01&url_param=unused';
      STATUS='Approved';
      RPL='YES';
      AML='13';
      BUS_UNIT='SMO_BOARDS';
      DAYS='56';
      PARENT_PART_TYPE='CAP';
      PARENT_PPT='CAP';
      PARENT_PPT_PART='CAP_0402LF-470PF,50V,10%,EMPTY,A36096-049';
  end_body;
end_primitive;
primitive 'CAP_0402LF-470PF,50V,10%,X7R,AA';
  pin
    'A':
      PIN_NUMBER='(1)';
      PINUSE='UNSPEC';
      NO_LOAD_CHECK='BOTH';
      NO_IO_CHECK='BOTH';
      ALLOW_CONNECT='TRUE';
      PIN_GROUP='1';
    'B':
      PIN_NUMBER='(2)';
      PINUSE='UNSPEC';
      NO_LOAD_CHECK='BOTH';
      NO_IO_CHECK='BOTH';
      ALLOW_CONNECT='TRUE';
      PIN_GROUP='1';
  end_pin;
  body
      PART_NAME='CAP';
      PHYS_DES_PREFIX='C';
      ENVCOMP='YES;YES;YES;UNK;ok;VLD';
      PART_NUMBER='A36096-049';
      JEDEC_TYPE='SMC0402A';
      ALT_SYMBOLS='(SMX0402,SMX0402A,SMX0402B)';
      VALUE='470pF';
      RATED_VOLTAGE='50V';
      TOL='10%';
      CLASS='DISCRETE';
      DESCRIPTION='CHIP0402';
      HEIGHT='0.024 IN';
      COMPONENT_TYPE='CHIP0402';
      LEAD_LENGTH='';
      LPID='1142';
      SPEED_URL='http://speed.intel.com:8081/speed/module/pdm/item/pdm_item_deta~
il_direct.asp?item_cde=A36096-049&item_rev=01&url_param=unused';
      STATUS='Approved';
      RPL='YES';
      AML='13';
      BUS_UNIT='SMO_BOARDS';
      DAYS='56';
      PARENT_PART_TYPE='CAP';
      PARENT_PPT='CAP';
      PARENT_PPT_PART='CAP_0402LF-470PF,50V,10%,X7R,A36096-049';
  end_body;
end_primitive;
primitive 'CAP_0603-10UF,6.3V,20%,X6S,E15A';
  pin
    'A':
      PIN_NUMBER='(1)';
      PINUSE='UNSPEC';
      NO_LOAD_CHECK='BOTH';
      NO_IO_CHECK='BOTH';
      ALLOW_CONNECT='TRUE';
      PIN_GROUP='1';
    'B':
      PIN_NUMBER='(2)';
      PINUSE='UNSPEC';
      NO_LOAD_CHECK='BOTH';
      NO_IO_CHECK='BOTH';
      ALLOW_CONNECT='TRUE';
      PIN_GROUP='1';
  end_pin;
  body
      PART_NAME='CAP';
      PHYS_DES_PREFIX='C';
      ENVCOMP='YES;YES;YES;UNK;ok;VLD';
      PART_NUMBER='E15431-002';
      JEDEC_TYPE='SMC0603A';
      ALT_SYMBOLS='(SMX0603)';
      VALUE='10uF';
      RATED_VOLTAGE='6.3V';
      TOL='20%';
      CLASS='DISCRETE';
      DESCRIPTION='CHIP0603';
      HEIGHT='0.039 IN';
      COMPONENT_TYPE='CHIP0603';
      LEAD_LENGTH='';
      LPID='443';
      SPEED_URL='http://speed.intel.com:8081/speed/module/pdm/item/pdm_item_deta~
il_direct.asp?item_cde=E15431-002&item_rev=01&url_param=unused';
      STATUS='Conditional';
      RPL='NO';
      AML='2';
      BUS_UNIT='SMO_BOARDS';
      DAYS='56';
      PARENT_PART_TYPE='CAP';
      PARENT_PPT='CAP';
      PARENT_PPT_PART='CAP_0603-10UF,6.3V,20%,X6S,E15431-002';
  end_body;
end_primitive;
primitive 'CAP_0603-4.7UF,6.3V,10%,X6S,E1A';
  pin
    'A':
      PIN_NUMBER='(1)';
      PINUSE='UNSPEC';
      NO_LOAD_CHECK='BOTH';
      NO_IO_CHECK='BOTH';
      ALLOW_CONNECT='TRUE';
      PIN_GROUP='1';
    'B':
      PIN_NUMBER='(2)';
      PINUSE='UNSPEC';
      NO_LOAD_CHECK='BOTH';
      NO_IO_CHECK='BOTH';
      ALLOW_CONNECT='TRUE';
      PIN_GROUP='1';
  end_pin;
  body
      PART_NAME='CAP';
      PHYS_DES_PREFIX='C';
      ENVCOMP='YES;YES;YES;UNK;ok;VLD';
      PART_NUMBER='E15431-003';
      JEDEC_TYPE='SMC0603A';
      ALT_SYMBOLS='(SMX0603)';
      VALUE='4.7uF';
      RATED_VOLTAGE='6.3V';
      TOL='10%';
      CLASS='DISCRETE';
      DESCRIPTION='CHIP0603';
      HEIGHT='0.035 IN';
      COMPONENT_TYPE='CHIP0603';
      LEAD_LENGTH='';
      LPID='443';
      SPEED_URL='http://speed.intel.com:8081/speed/module/pdm/item/pdm_item_deta~
il_direct.asp?item_cde=E15431-003&item_rev=01&url_param=unused';
      STATUS='Conditional';
      RPL='NO';
      AML='5';
      BUS_UNIT='SMO_BOARDS';
      DAYS='???';
      PARENT_PART_TYPE='CAP';
      PARENT_PPT='CAP';
      PARENT_PPT_PART='CAP_0603-4.7UF,6.3V,10%,X6S,E15431-003';
  end_body;
end_primitive;
primitive 'CAP_0603LF-0.033UF,50V,10%,X7RA';
  pin
    'A':
      PIN_NUMBER='(1)';
      PINUSE='UNSPEC';
      NO_LOAD_CHECK='BOTH';
      NO_IO_CHECK='BOTH';
      ALLOW_CONNECT='TRUE';
      PIN_GROUP='1';
    'B':
      PIN_NUMBER='(2)';
      PINUSE='UNSPEC';
      NO_LOAD_CHECK='BOTH';
      NO_IO_CHECK='BOTH';
      ALLOW_CONNECT='TRUE';
      PIN_GROUP='1';
  end_pin;
  body
      PART_NAME='CAP';
      PHYS_DES_PREFIX='C';
      ENVCOMP='YES;YES;UNK;UNK;ok;VLD';
      PART_NUMBER='603269-064';
      JEDEC_TYPE='SMC0603A';
      ALT_SYMBOLS='(SMX0603)';
      VALUE='0.033uF';
      RATED_VOLTAGE='50V';
      TOL='10%';
      CLASS='DISCRETE';
      DESCRIPTION='CHIP0603';
      HEIGHT='0.035 IN';
      COMPONENT_TYPE='CHIP0603';
      LEAD_LENGTH='';
      LPID='443';
      SPEED_URL='http://speed.intel.com:8081/speed/module/pdm/item/pdm_item_deta~
il_direct.asp?item_cde=603269-064&item_rev=01&url_param=unused';
      STATUS='Approved';
      RPL='YES';
      AML='8';
      BUS_UNIT='SMO_BOARDS';
      DAYS='56';
      PARENT_PART_TYPE='CAP';
      PARENT_PPT='CAP';
      PARENT_PPT_PART='CAP_0603LF-0.033UF,50V,10%,X7R,603269-064';
  end_body;
end_primitive;
primitive 'CAP_0603LF-0.1UF,25V,10%,X7R,6A';
  pin
    'A':
      PIN_NUMBER='(1)';
      PINUSE='UNSPEC';
      NO_LOAD_CHECK='BOTH';
      NO_IO_CHECK='BOTH';
      ALLOW_CONNECT='TRUE';
      PIN_GROUP='1';
    'B':
      PIN_NUMBER='(2)';
      PINUSE='UNSPEC';
      NO_LOAD_CHECK='BOTH';
      NO_IO_CHECK='BOTH';
      ALLOW_CONNECT='TRUE';
      PIN_GROUP='1';
  end_pin;
  body
      PART_NAME='CAP';
      PHYS_DES_PREFIX='C';
      ENVCOMP='YES;YES;YES;UNK;ok;VLD';
      PART_NUMBER='602433-020';
      JEDEC_TYPE='SMC0603A';
      ALT_SYMBOLS='(SMX0603)';
      VALUE='0.1uF';
      RATED_VOLTAGE='25V';
      TOL='10%';
      CLASS='DISCRETE';
      DESCRIPTION='CHIP0603';
      HEIGHT='0.035 IN';
      COMPONENT_TYPE='CHIP0603';
      LEAD_LENGTH='';
      LPID='443';
      SPEED_URL='http://speed.intel.com:8081/speed/module/pdm/item/pdm_item_deta~
il_direct.asp?item_cde=602433-020&item_rev=01&url_param=unused';
      STATUS='Conditional';
      RPL='YES';
      AML='9';
      BUS_UNIT='SMO_BOARDS';
      DAYS='56';
      PARENT_PART_TYPE='CAP';
      PARENT_PPT='CAP';
      PARENT_PPT_PART='CAP_0603LF-0.1UF,25V,10%,X7R,602433-020';
  end_body;
end_primitive;
primitive 'CAP_0603LF-10UF,4V,20%,X6S,E15A';
  pin
    'A':
      PIN_NUMBER='(1)';
      PINUSE='UNSPEC';
      NO_LOAD_CHECK='BOTH';
      NO_IO_CHECK='BOTH';
      ALLOW_CONNECT='TRUE';
      PIN_GROUP='1';
    'B':
      PIN_NUMBER='(2)';
      PINUSE='UNSPEC';
      NO_LOAD_CHECK='BOTH';
      NO_IO_CHECK='BOTH';
      ALLOW_CONNECT='TRUE';
      PIN_GROUP='1';
  end_pin;
  body
      PART_NAME='CAP';
      PHYS_DES_PREFIX='C';
      ENVCOMP='YES;YES;YES;UNK;ok;VLD';
      PART_NUMBER='E15431-001';
      JEDEC_TYPE='SMC0603A';
      ALT_SYMBOLS='(SMX0603)';
      VALUE='10uF';
      RATED_VOLTAGE='4V';
      TOL='20%';
      CLASS='DISCRETE';
      DESCRIPTION='CHIP0603';
      HEIGHT='0.027 IN';
      COMPONENT_TYPE='CHIP0603';
      LEAD_LENGTH='';
      LPID='443';
      SPEED_URL='http://speed.intel.com:8081/speed/module/pdm/item/pdm_item_deta~
il_direct.asp?item_cde=E15431-001&item_rev=01&url_param=unused';
      STATUS='Conditional';
      RPL='NO';
      AML='3';
      BUS_UNIT='SMO_BOARDS';
      DAYS='???';
      PARENT_PART_TYPE='CAP';
      PARENT_PPT='CAP';
      PARENT_PPT_PART='CAP_0603LF-10UF,4V,20%,X6S,E15431-001';
  end_body;
end_primitive;
primitive 'CAP_0805-100UF,4V,20%,X5R,6024A';
  pin
    'A':
      PIN_NUMBER='(1)';
      PINUSE='UNSPEC';
      NO_LOAD_CHECK='BOTH';
      NO_IO_CHECK='BOTH';
      ALLOW_CONNECT='TRUE';
      PIN_GROUP='1';
    'B':
      PIN_NUMBER='(2)';
      PINUSE='UNSPEC';
      NO_LOAD_CHECK='BOTH';
      NO_IO_CHECK='BOTH';
      ALLOW_CONNECT='TRUE';
      PIN_GROUP='1';
  end_pin;
  body
      PART_NAME='CAP';
      PHYS_DES_PREFIX='C';
      ENVCOMP='';
      PART_NUMBER='602433-112';
      JEDEC_TYPE='SMC0805A';
      ALT_SYMBOLS='(SMX0805)';
      VALUE='100uF';
      RATED_VOLTAGE='4V';
      TOL='20%';
      CLASS='DISCRETE';
      DESCRIPTION='CAPC,X5R,0805,100.00UF,4.00V,+/- 20%';
      HEIGHT='0.057 IN';
      COMPONENT_TYPE='CHIP0805';
      LEAD_LENGTH='';
      LPID='445';
      SPEED_URL='http://speed.intel.com:8081/speed/module/pdm/item/pdm_item_deta~
il_direct.asp?item_cde=602433-112&item_rev=01&url_param=unused';
      STATUS='';
      RPL='';
      AML='';
      BUS_UNIT='';
      DAYS='';
      PARENT_PART_TYPE='CAP';
      PARENT_PPT='CAP';
      PARENT_PPT_PART='CAP_0805-100UF,4V,20%,X5R,602433-112';
  end_body;
end_primitive;
primitive 'CAP_0805-10UF,16V,10%,EMPTY,C9A';
  pin
    'A':
      PIN_NUMBER='(1)';
      PINUSE='UNSPEC';
      NO_LOAD_CHECK='BOTH';
      NO_IO_CHECK='BOTH';
      ALLOW_CONNECT='TRUE';
      PIN_GROUP='1';
    'B':
      PIN_NUMBER='(2)';
      PINUSE='UNSPEC';
      NO_LOAD_CHECK='BOTH';
      NO_IO_CHECK='BOTH';
      ALLOW_CONNECT='TRUE';
      PIN_GROUP='1';
  end_pin;
  body
      PART_NAME='CAP';
      PHYS_DES_PREFIX='C';
      ENVCOMP='YES;YES;YES;UNK;ok;VLD';
      PART_NUMBER='C95333-007';
      JEDEC_TYPE='SMC0805A';
      ALT_SYMBOLS='(SMX0805)';
      VALUE='NA';
      RATED_VOLTAGE='16V';
      TOL='10%';
      CLASS='DISCRETE';
      DESCRIPTION='CHIP0805';
      HEIGHT='0.049 IN';
      COMPONENT_TYPE='CHIP0805';
      LEAD_LENGTH='';
      LPID='445';
      SPEED_URL='http://speed.intel.com:8081/speed/module/pdm/item/pdm_item_deta~
il_direct.asp?item_cde=C95333-007&item_rev=01&url_param=unused';
      STATUS='Conditional';
      RPL='NO';
      AML='3';
      BUS_UNIT='SMO_BOARDS';
      DAYS='???';
      PARENT_PART_TYPE='CAP';
      PARENT_PPT='CAP';
      PARENT_PPT_PART='CAP_0805-10UF,16V,10%,EMPTY,C95333-007';
  end_body;
end_primitive;
primitive 'CAP_0805-10UF,16V,10%,X6S,C953A';
  pin
    'A':
      PIN_NUMBER='(1)';
      PINUSE='UNSPEC';
      NO_LOAD_CHECK='BOTH';
      NO_IO_CHECK='BOTH';
      ALLOW_CONNECT='TRUE';
      PIN_GROUP='1';
    'B':
      PIN_NUMBER='(2)';
      PINUSE='UNSPEC';
      NO_LOAD_CHECK='BOTH';
      NO_IO_CHECK='BOTH';
      ALLOW_CONNECT='TRUE';
      PIN_GROUP='1';
  end_pin;
  body
      PART_NAME='CAP';
      PHYS_DES_PREFIX='C';
      ENVCOMP='YES;YES;YES;UNK;ok;VLD';
      PART_NUMBER='C95333-007';
      JEDEC_TYPE='SMC0805A';
      ALT_SYMBOLS='(SMX0805)';
      VALUE='10uF';
      RATED_VOLTAGE='16V';
      TOL='10%';
      CLASS='DISCRETE';
      DESCRIPTION='CHIP0805';
      HEIGHT='0.049 IN';
      COMPONENT_TYPE='CHIP0805';
      LEAD_LENGTH='';
      LPID='445';
      SPEED_URL='http://speed.intel.com:8081/speed/module/pdm/item/pdm_item_deta~
il_direct.asp?item_cde=C95333-007&item_rev=01&url_param=unused';
      STATUS='Conditional';
      RPL='NO';
      AML='3';
      BUS_UNIT='SMO_BOARDS';
      DAYS='???';
      PARENT_PART_TYPE='CAP';
      PARENT_PPT='CAP';
      PARENT_PPT_PART='CAP_0805-10UF,16V,10%,X6S,C95333-007';
  end_body;
end_primitive;
primitive 'CAP_0805-10UF,16V,10%,X7R,G106A';
  pin
    'A':
      PIN_NUMBER='(1)';
      PINUSE='UNSPEC';
      NO_LOAD_CHECK='BOTH';
      NO_IO_CHECK='BOTH';
      ALLOW_CONNECT='TRUE';
      PIN_GROUP='1';
    'B':
      PIN_NUMBER='(2)';
      PINUSE='UNSPEC';
      NO_LOAD_CHECK='BOTH';
      NO_IO_CHECK='BOTH';
      ALLOW_CONNECT='TRUE';
      PIN_GROUP='1';
  end_pin;
  body
      PART_NAME='CAP';
      PHYS_DES_PREFIX='C';
      ENVCOMP='YES;YES;YES;UNK;ok;VLD';
      PART_NUMBER='G10601-001';
      JEDEC_TYPE='SMC0805A';
      ALT_SYMBOLS='(SMX0805)';
      VALUE='10uF';
      RATED_VOLTAGE='16V';
      TOL='10%';
      CLASS='DISCRETE';
      DESCRIPTION='CHIP0805';
      HEIGHT='0.049 IN';
      COMPONENT_TYPE='CHIP0805';
      LEAD_LENGTH='';
      LPID='445';
      SPEED_URL='http://speed.intel.com:8081/speed/module/pdm/item/pdm_item_deta~
il_direct.asp?item_cde=G10601-001&item_rev=01&url_param=unused';
      STATUS='Design';
      RPL='NO';
      AML='2';
      BUS_UNIT='SMO_BOARDS';
      DAYS='???';
      PARENT_PART_TYPE='CAP';
      PARENT_PPT='CAP';
      PARENT_PPT_PART='CAP_0805-10UF,16V,10%,X7R,G10601-001';
  end_body;
end_primitive;
primitive 'CAP_0805-22UF,6.3V,20%,X6S,C95A';
  pin
    'A':
      PIN_NUMBER='(1)';
      PINUSE='UNSPEC';
      NO_LOAD_CHECK='BOTH';
      NO_IO_CHECK='BOTH';
      ALLOW_CONNECT='TRUE';
      PIN_GROUP='1';
    'B':
      PIN_NUMBER='(2)';
      PINUSE='UNSPEC';
      NO_LOAD_CHECK='BOTH';
      NO_IO_CHECK='BOTH';
      ALLOW_CONNECT='TRUE';
      PIN_GROUP='1';
  end_pin;
  body
      PART_NAME='CAP';
      PHYS_DES_PREFIX='C';
      ENVCOMP='YES;YES;YES;UNK;ok;VLD';
      PART_NUMBER='C95333-008';
      JEDEC_TYPE='SMC0805A';
      ALT_SYMBOLS='(SMX0805)';
      VALUE='22uF';
      RATED_VOLTAGE='6.3V';
      TOL='20%';
      CLASS='DISCRETE';
      DESCRIPTION='CHIP0805';
      HEIGHT='0.055 IN';
      COMPONENT_TYPE='CHIP0805';
      LEAD_LENGTH='';
      LPID='445';
      SPEED_URL='http://speed.intel.com:8081/speed/module/pdm/item/pdm_item_deta~
il_direct.asp?item_cde=C95333-008&item_rev=01&url_param=unused';
      STATUS='Conditional';
      RPL='YES';
      AML='5';
      BUS_UNIT='SMO_BOARDS';
      DAYS='???';
      PARENT_PART_TYPE='CAP';
      PARENT_PPT='CAP';
      PARENT_PPT_PART='CAP_0805-22UF,6.3V,20%,X6S,C95333-008';
  end_body;
end_primitive;
primitive 'CAP_0805-47UF,4V,20%,X6S,C9533A';
  pin
    'A':
      PIN_NUMBER='(1)';
      PINUSE='UNSPEC';
      NO_LOAD_CHECK='BOTH';
      NO_IO_CHECK='BOTH';
      ALLOW_CONNECT='TRUE';
      PIN_GROUP='1';
    'B':
      PIN_NUMBER='(2)';
      PINUSE='UNSPEC';
      NO_LOAD_CHECK='BOTH';
      NO_IO_CHECK='BOTH';
      ALLOW_CONNECT='TRUE';
      PIN_GROUP='1';
  end_pin;
  body
      PART_NAME='CAP';
      PHYS_DES_PREFIX='C';
      ENVCOMP='YES;YES;YES;UNK;ok;VLD';
      PART_NUMBER='C95333-006';
      JEDEC_TYPE='SMC0805A';
      ALT_SYMBOLS='(SMX0805)';
      VALUE='47uF';
      RATED_VOLTAGE='4V';
      TOL='20%';
      CLASS='DISCRETE';
      DESCRIPTION='CHIP0805';
      HEIGHT='0.060 IN';
      COMPONENT_TYPE='CHIP0805';
      LEAD_LENGTH='';
      LPID='445';
      SPEED_URL='http://speed.intel.com:8081/speed/module/pdm/item/pdm_item_deta~
il_direct.asp?item_cde=C95333-006&item_rev=01&url_param=unused';
      STATUS='Conditional';
      RPL='NO';
      AML='7';
      BUS_UNIT='SMO_BOARDS';
      DAYS='???';
      PARENT_PART_TYPE='CAP';
      PARENT_PPT='CAP';
      PARENT_PPT_PART='CAP_0805-47UF,4V,20%,X6S,C95333-006';
  end_body;
end_primitive;
primitive 'CAP_0805LF-22UF,4V,20%,X6S,C95A';
  pin
    'A':
      PIN_NUMBER='(1)';
      PINUSE='UNSPEC';
      NO_LOAD_CHECK='BOTH';
      NO_IO_CHECK='BOTH';
      ALLOW_CONNECT='TRUE';
      PIN_GROUP='1';
    'B':
      PIN_NUMBER='(2)';
      PINUSE='UNSPEC';
      NO_LOAD_CHECK='BOTH';
      NO_IO_CHECK='BOTH';
      ALLOW_CONNECT='TRUE';
      PIN_GROUP='1';
  end_pin;
  body
      PART_NAME='CAP';
      PHYS_DES_PREFIX='C';
      ENVCOMP='YES;YES;YES;UNK;ok;VLD';
      PART_NUMBER='C95333-002';
      JEDEC_TYPE='SMC0805A';
      ALT_SYMBOLS='(SMX0805)';
      VALUE='22uF';
      RATED_VOLTAGE='4V';
      TOL='20%';
      CLASS='DISCRETE';
      DESCRIPTION='CHIP0805';
      HEIGHT='0.055 IN';
      COMPONENT_TYPE='CHIP0805';
      LEAD_LENGTH='';
      LPID='445';
      SPEED_URL='http://speed.intel.com:8081/speed/module/pdm/item/pdm_item_deta~
il_direct.asp?item_cde=C95333-002&item_rev=01&url_param=unused';
      STATUS='Conditional';
      RPL='NO';
      AML='4';
      BUS_UNIT='SMO_BOARDS';
      DAYS='56';
      PARENT_PART_TYPE='CAP';
      PARENT_PPT='CAP';
      PARENT_PPT_PART='CAP_0805LF-22UF,4V,20%,X6S,C95333-002';
  end_body;
end_primitive;
primitive 'CAP_1206-0.068UF,50V,20%,X7R,1A';
  pin
    'A':
      PIN_NUMBER='(1)';
      PINUSE='UNSPEC';
      NO_LOAD_CHECK='BOTH';
      NO_IO_CHECK='BOTH';
      ALLOW_CONNECT='TRUE';
      PIN_GROUP='1';
    'B':
      PIN_NUMBER='(2)';
      PINUSE='UNSPEC';
      NO_LOAD_CHECK='BOTH';
      NO_IO_CHECK='BOTH';
      ALLOW_CONNECT='TRUE';
      PIN_GROUP='1';
  end_pin;
  body
      PART_NAME='CAP';
      PHYS_DES_PREFIX='C';
      ENVCOMP='YES;YES;UNK;UNK;ok;VLD';
      PART_NUMBER='108427-047';
      JEDEC_TYPE='SMC1206A';
      ALT_SYMBOLS='(SMC1206AW)';
      VALUE='.068uF';
      RATED_VOLTAGE='50V';
      TOL='20%';
      CLASS='DISCRETE';
      DESCRIPTION='CHIP1206';
      HEIGHT='0.038 IN';
      COMPONENT_TYPE='CHIP';
      LEAD_LENGTH='';
      LPID='447';
      SPEED_URL='http://speed.intel.com:8081/speed/module/pdm/item/pdm_item_deta~
il_direct.asp?item_cde=108427-047&item_rev=01&url_param=unused';
      STATUS='Archive';
      RPL='NO';
      AML='11';
      BUS_UNIT='SMO_BOARDS';
      DAYS='56';
      PARENT_PART_TYPE='CAP';
      PARENT_PPT='CAP';
      PARENT_PPT_PART='CAP_1206-0.068UF,50V,20%,X7R,108427-047';
  end_body;
end_primitive;
primitive 'CAP_1206LF-22UF,16V,10%,X6S,D3A';
  pin
    'A':
      PIN_NUMBER='(1)';
      PINUSE='UNSPEC';
      NO_LOAD_CHECK='BOTH';
      NO_IO_CHECK='BOTH';
      ALLOW_CONNECT='TRUE';
      PIN_GROUP='1';
    'B':
      PIN_NUMBER='(2)';
      PINUSE='UNSPEC';
      NO_LOAD_CHECK='BOTH';
      NO_IO_CHECK='BOTH';
      ALLOW_CONNECT='TRUE';
      PIN_GROUP='1';
  end_pin;
  body
      PART_NAME='CAP';
      PHYS_DES_PREFIX='C';
      ENVCOMP='YES;YES;YES;UNK;ok;VLD';
      PART_NUMBER='D38464-005';
      JEDEC_TYPE='SMC1206A';
      ALT_SYMBOLS='(SMC1206AW)';
      VALUE='22uF';
      RATED_VOLTAGE='16V';
      TOL='10%';
      CLASS='DISCRETE';
      DESCRIPTION='CHIP1206';
      HEIGHT='0.071 IN';
      COMPONENT_TYPE='CHIP';
      LEAD_LENGTH='';
      LPID='447';
      SPEED_URL='http://speed.intel.com:8081/speed/module/pdm/item/pdm_item_deta~
il_direct.asp?item_cde=D38464-005&item_rev=01&url_param=unused';
      STATUS='Conditional';
      RPL='NO';
      AML='1';
      BUS_UNIT='SMO_BOARDS';
      DAYS='???';
      PARENT_PART_TYPE='CAP';
      PARENT_PPT='CAP';
      PARENT_PPT_PART='CAP_1206LF-22UF,16V,10%,X6S,D38464-005';
  end_body;
end_primitive;
primitive 'CAP_A_0402V-0.01UF,25V,10%,X7RA';
  pin
    'A':
      PIN_NUMBER='(1)';
      PINUSE='UNSPEC';
      NO_LOAD_CHECK='BOTH';
      NO_IO_CHECK='BOTH';
      ALLOW_CONNECT='TRUE';
      PIN_GROUP='1';
    'B':
      PIN_NUMBER='(2)';
      PINUSE='UNSPEC';
      NO_LOAD_CHECK='BOTH';
      NO_IO_CHECK='BOTH';
      ALLOW_CONNECT='TRUE';
      PIN_GROUP='1';
  end_pin;
  body
      PART_NAME='CAP_A';
      PHYS_DES_PREFIX='C';
      ENVCOMP='YES;YES;YES;UNK;ok;CIP';
      PART_NUMBER='A36096-045';
      JEDEC_TYPE='SMC0402A';
      ALT_SYMBOLS='(SMX0402V,SMX0402AV,SMX0402BV)';
      VALUE='0.01uF';
      RATED_VOLTAGE='25V';
      TOL='10%';
      CLASS='DISCRETE';
      DESCRIPTION='CHIP0402';
      HEIGHT='0.024 IN';
      COMPONENT_TYPE='CHIP0402';
      LEAD_LENGTH='';
      LPID='1142';
      SPEED_URL='http://speed.intel.com:8081/speed/module/pdm/item/pdm_item_deta~
il_direct.asp?item_cde=A36096-045&item_rev=01&url_param=unused';
      STATUS='Approved';
      RPL='YES';
      AML='13';
      BUS_UNIT='SMO_BOARDS';
      DAYS='56';
      PARENT_PART_TYPE='CAP_A';
      PARENT_PPT='CAP_A';
      PARENT_PPT_PART='CAP_A_0402V-0.01UF,25V,10%,X7R,A36096-045';
  end_body;
end_primitive;
primitive 'CAP_A_0402V-0.1UF,16V,10%,EMPTA';
  pin
    'A':
      PIN_NUMBER='(1)';
      PINUSE='UNSPEC';
      NO_LOAD_CHECK='BOTH';
      NO_IO_CHECK='BOTH';
      ALLOW_CONNECT='TRUE';
      PIN_GROUP='1';
    'B':
      PIN_NUMBER='(2)';
      PINUSE='UNSPEC';
      NO_LOAD_CHECK='BOTH';
      NO_IO_CHECK='BOTH';
      ALLOW_CONNECT='TRUE';
      PIN_GROUP='1';
  end_pin;
  body
      PART_NAME='CAP_A';
      PHYS_DES_PREFIX='C';
      ENVCOMP='YES;YES;YES;UNK;ok;VLD';
      PART_NUMBER='A36096-030';
      JEDEC_TYPE='SMC0402A';
      ALT_SYMBOLS='(SMX0402V,SMX0402AV,SMX0402BV)';
      VALUE='NA';
      RATED_VOLTAGE='16V';
      TOL='10%';
      CLASS='DISCRETE';
      DESCRIPTION='CHIP0402';
      HEIGHT='0.024 IN';
      COMPONENT_TYPE='CHIP0402';
      LEAD_LENGTH='';
      LPID='1142';
      SPEED_URL='http://speed.intel.com:8081/speed/module/pdm/item/pdm_item_deta~
il_direct.asp?item_cde=A36096-030&item_rev=01&url_param=unused';
      STATUS='Approved';
      RPL='YES';
      AML='12';
      BUS_UNIT='SMO_BOARDS';
      DAYS='56';
      PARENT_PART_TYPE='CAP_A';
      PARENT_PPT='CAP_A';
      PARENT_PPT_PART='CAP_A_0402V-0.1UF,16V,10%,EMPTY,A36096-030';
  end_body;
end_primitive;
primitive 'CAP_A_0402V-0.1UF,16V,10%,X7R,A';
  pin
    'A':
      PIN_NUMBER='(1)';
      PINUSE='UNSPEC';
      NO_LOAD_CHECK='BOTH';
      NO_IO_CHECK='BOTH';
      ALLOW_CONNECT='TRUE';
      PIN_GROUP='1';
    'B':
      PIN_NUMBER='(2)';
      PINUSE='UNSPEC';
      NO_LOAD_CHECK='BOTH';
      NO_IO_CHECK='BOTH';
      ALLOW_CONNECT='TRUE';
      PIN_GROUP='1';
  end_pin;
  body
      PART_NAME='CAP_A';
      PHYS_DES_PREFIX='C';
      ENVCOMP='YES;YES;YES;UNK;ok;VLD';
      PART_NUMBER='A36096-030';
      JEDEC_TYPE='SMC0402A';
      ALT_SYMBOLS='(SMX0402V,SMX0402AV,SMX0402BV)';
      VALUE='0.1uF';
      RATED_VOLTAGE='16V';
      TOL='10%';
      CLASS='DISCRETE';
      DESCRIPTION='CHIP0402';
      HEIGHT='0.024 IN';
      COMPONENT_TYPE='CHIP0402';
      LEAD_LENGTH='';
      LPID='1142';
      SPEED_URL='http://speed.intel.com:8081/speed/module/pdm/item/pdm_item_deta~
il_direct.asp?item_cde=A36096-030&item_rev=01&url_param=unused';
      STATUS='Approved';
      RPL='YES';
      AML='12';
      BUS_UNIT='SMO_BOARDS';
      DAYS='56';
      PARENT_PART_TYPE='CAP_A';
      PARENT_PPT='CAP_A';
      PARENT_PPT_PART='CAP_A_0402V-0.1UF,16V,10%,X7R,A36096-030';
  end_body;
end_primitive;
primitive 'CAP_A_0402V-1.0UF,6.3V,10%,X6SA';
  pin
    'A':
      PIN_NUMBER='(1)';
      PINUSE='UNSPEC';
      NO_LOAD_CHECK='BOTH';
      NO_IO_CHECK='BOTH';
      ALLOW_CONNECT='TRUE';
      PIN_GROUP='1';
    'B':
      PIN_NUMBER='(2)';
      PINUSE='UNSPEC';
      NO_LOAD_CHECK='BOTH';
      NO_IO_CHECK='BOTH';
      ALLOW_CONNECT='TRUE';
      PIN_GROUP='1';
  end_pin;
  body
      PART_NAME='CAP_A';
      PHYS_DES_PREFIX='C';
      ENVCOMP='YES;YES;YES;UNK;ok;VLD';
      PART_NUMBER='D97712-004';
      JEDEC_TYPE='SMC0402A';
      ALT_SYMBOLS='(SMX0402V,SMX0402AV,SMX0402BV)';
      VALUE='1.0uF';
      RATED_VOLTAGE='6.3V';
      TOL='10%';
      CLASS='DISCRETE';
      DESCRIPTION='CHIP0402';
      HEIGHT='0.022 IN';
      COMPONENT_TYPE='CHIP0402';
      LEAD_LENGTH='';
      LPID='1142';
      SPEED_URL='http://speed.intel.com:8081/speed/module/pdm/item/pdm_item_deta~
il_direct.asp?item_cde=D97712-004&item_rev=01&url_param=unused';
      STATUS='Conditional';
      RPL='NO';
      AML='4';
      BUS_UNIT='SMO_BOARDS';
      DAYS='???';
      PARENT_PART_TYPE='CAP_A';
      PARENT_PPT='CAP_A';
      PARENT_PPT_PART='CAP_A_0402V-1.0UF,6.3V,10%,X6S,D97712-004';
  end_body;
end_primitive;
primitive 'CAP_A_0603V-22.0UF,4V,20%,EMPTA';
  pin
    'A':
      PIN_NUMBER='(1)';
      PINUSE='UNSPEC';
      NO_LOAD_CHECK='BOTH';
      NO_IO_CHECK='BOTH';
      ALLOW_CONNECT='TRUE';
      PIN_GROUP='1';
    'B':
      PIN_NUMBER='(2)';
      PINUSE='UNSPEC';
      NO_LOAD_CHECK='BOTH';
      NO_IO_CHECK='BOTH';
      ALLOW_CONNECT='TRUE';
      PIN_GROUP='1';
  end_pin;
  body
      PART_NAME='CAP_A';
      PHYS_DES_PREFIX='C';
      ENVCOMP='YES;YES;YES;UNK;ok;VLD';
      PART_NUMBER='E15431-004';
      JEDEC_TYPE='SMC0603A';
      ALT_SYMBOLS='(SMX0603V)';
      VALUE='NA';
      RATED_VOLTAGE='4V';
      TOL='20%';
      CLASS='DISCRETE';
      DESCRIPTION='CAPC,X6S,0603,22.00UF,4.00V, 20%';
      HEIGHT='0.035 IN';
      COMPONENT_TYPE='CHIP0603';
      LEAD_LENGTH='';
      LPID='443';
      SPEED_URL='http://speed.intel.com:8081/speed/module/pdm/item/pdm_item_deta~
il_direct.asp?item_cde=E15431-004&item_rev=01&url_param=unused';
      STATUS='Design';
      RPL='NO';
      AML='2';
      BUS_UNIT='SMO_BOARDS';
      DAYS='???';
      PARENT_PART_TYPE='CAP_A';
      PARENT_PPT='CAP_A';
      PARENT_PPT_PART='CAP_A_0603V-22.0UF,4V,20%,EMPTY,E15431-004';
  end_body;
end_primitive;
primitive 'CAP_A_0603V-22.0UF,4V,20%,X6S,A';
  pin
    'A':
      PIN_NUMBER='(1)';
      PINUSE='UNSPEC';
      NO_LOAD_CHECK='BOTH';
      NO_IO_CHECK='BOTH';
      ALLOW_CONNECT='TRUE';
      PIN_GROUP='1';
    'B':
      PIN_NUMBER='(2)';
      PINUSE='UNSPEC';
      NO_LOAD_CHECK='BOTH';
      NO_IO_CHECK='BOTH';
      ALLOW_CONNECT='TRUE';
      PIN_GROUP='1';
  end_pin;
  body
      PART_NAME='CAP_A';
      PHYS_DES_PREFIX='C';
      ENVCOMP='YES;YES;YES;UNK;ok;VLD';
      PART_NUMBER='E15431-004';
      JEDEC_TYPE='SMC0603A';
      ALT_SYMBOLS='(SMX0603V)';
      VALUE='22.0uF';
      RATED_VOLTAGE='4V';
      TOL='20%';
      CLASS='DISCRETE';
      DESCRIPTION='CAPC,X6S,0603,22.00UF,4.00V, 20%';
      HEIGHT='0.035 IN';
      COMPONENT_TYPE='CHIP0603';
      LEAD_LENGTH='';
      LPID='443';
      SPEED_URL='http://speed.intel.com:8081/speed/module/pdm/item/pdm_item_deta~
il_direct.asp?item_cde=E15431-004&item_rev=01&url_param=unused';
      STATUS='Design';
      RPL='NO';
      AML='2';
      BUS_UNIT='SMO_BOARDS';
      DAYS='???';
      PARENT_PART_TYPE='CAP_A';
      PARENT_PPT='CAP_A';
      PARENT_PPT_PART='CAP_A_0603V-22.0UF,4V,20%,X6S,E15431-004';
  end_body;
end_primitive;
primitive 'CAP_A_0603V-47UF,4V,20%,X5R,60A';
  pin
    'A':
      PIN_NUMBER='(1)';
      PINUSE='UNSPEC';
      NO_LOAD_CHECK='BOTH';
      NO_IO_CHECK='BOTH';
      ALLOW_CONNECT='TRUE';
      PIN_GROUP='1';
    'B':
      PIN_NUMBER='(2)';
      PINUSE='UNSPEC';
      NO_LOAD_CHECK='BOTH';
      NO_IO_CHECK='BOTH';
      ALLOW_CONNECT='TRUE';
      PIN_GROUP='1';
  end_pin;
  body
      PART_NAME='CAP_A';
      PHYS_DES_PREFIX='C';
      ENVCOMP='';
      PART_NUMBER='602433-106';
      JEDEC_TYPE='SMC0603CV';
      ALT_SYMBOLS='';
      VALUE='47uF';
      RATED_VOLTAGE='4V';
      TOL='20%';
      CLASS='DISCRETE';
      DESCRIPTION='CAPC,X5R,0603,47.00UF,4.00V, 20%';
      HEIGHT='0.039 IN';
      COMPONENT_TYPE='CHIP0603';
      LEAD_LENGTH='';
      LPID='3802';
      SPEED_URL='http://speed.intel.com:8081/speed/module/pdm/item/pdm_item_deta~
il_direct.asp?item_cde=602433-106&item_rev=01&url_param=unused';
      STATUS='';
      RPL='';
      AML='';
      BUS_UNIT='';
      DAYS='';
      PARENT_PART_TYPE='CAP_A';
      PARENT_PPT='CAP_A';
      PARENT_PPT_PART='CAP_A_0603V-47UF,4V,20%,X5R,602433-106';
  end_body;
end_primitive;
primitive 'CHOKE_4PIN_SMLF-90 OHM,IND,752A';
  pin
    'A1':
      PIN_NUMBER='(1)';
      PIN_TYPE='ANALOG';
      NO_LOAD_CHECK='BOTH';
      NO_IO_CHECK='BOTH';
      ALLOW_CONNECT='TRUE';
      PINUSE='UNSPEC';
    'A2':
      PIN_NUMBER='(2)';
      PIN_TYPE='ANALOG';
      NO_LOAD_CHECK='BOTH';
      NO_IO_CHECK='BOTH';
      ALLOW_CONNECT='TRUE';
      PINUSE='UNSPEC';
    'B1':
      PIN_NUMBER='(3)';
      PIN_TYPE='ANALOG';
      NO_LOAD_CHECK='BOTH';
      NO_IO_CHECK='BOTH';
      ALLOW_CONNECT='TRUE';
      PINUSE='UNSPEC';
    'B2':
      PIN_NUMBER='(4)';
      PIN_TYPE='ANALOG';
      NO_LOAD_CHECK='BOTH';
      NO_IO_CHECK='BOTH';
      ALLOW_CONNECT='TRUE';
      PINUSE='UNSPEC';
  end_pin;
  body
      PART_NAME='CHOKE_4PIN';
      PHYS_DES_PREFIX='L';
      ENVCOMP='YES;YES;YES;UNK;ok;VLD';
      PART_NUMBER='752402-015';
      JEDEC_TYPE='SMI0805B';
      VALUE='90 OHM';
      CLASS='DISCRETE';
      DESCRIPTION='(VERIFY PINOUT BEFORE USING)COMMON MODE CHOKE 90 OHM';
      HEIGHT='0.055 IN';
      COMPONENT_TYPE='SMALLSMT';
      LEAD_LENGTH='';
      LPID='';
      SPEED_URL='http://speed.intel.com:8081/speed/module/pdm/item/pdm_item_deta~
il_direct.asp?item_cde=752402-015&item_rev=01&url_param=unused';
      STATUS='Approved';
      RPL='YES';
      AML='4';
      BUS_UNIT='SMO_BOARDS';
      DAYS='70';
      PARENT_PART_TYPE='CHOKE_4PIN';
      PARENT_PPT='CHOKE_4PIN';
      PARENT_PPT_PART='CHOKE_4PIN_SMLF-90 OHM,IND,752402-015';
  end_body;
end_primitive;
primitive 'CHOKE_4PIN_SM_B-67 OHM,EMPTY,7A';
  pin
    '1':
      PIN_NUMBER='(1)';
      PIN_TYPE='ANALOG';
      NO_LOAD_CHECK='BOTH';
      NO_IO_CHECK='BOTH';
      ALLOW_CONNECT='TRUE';
      PINUSE='UNSPEC';
    '2':
      PIN_NUMBER='(2)';
      PIN_TYPE='ANALOG';
      NO_LOAD_CHECK='BOTH';
      NO_IO_CHECK='BOTH';
      ALLOW_CONNECT='TRUE';
      PINUSE='UNSPEC';
    '3':
      PIN_NUMBER='(3)';
      PIN_TYPE='ANALOG';
      NO_LOAD_CHECK='BOTH';
      NO_IO_CHECK='BOTH';
      ALLOW_CONNECT='TRUE';
      PINUSE='UNSPEC';
    '4':
      PIN_NUMBER='(4)';
      PIN_TYPE='ANALOG';
      NO_LOAD_CHECK='BOTH';
      NO_IO_CHECK='BOTH';
      ALLOW_CONNECT='TRUE';
      PINUSE='UNSPEC';
  end_pin;
  body
      PART_NAME='CHOKE_4PIN';
      PHYS_DES_PREFIX='L';
      ENVCOMP='UNK;UNK;UNK;UNK;ok;CIP';
      PART_NUMBER='752402-028';
      JEDEC_TYPE='SMI0805C';
      VALUE='NA';
      CLASS='DISCRETE';
      DESCRIPTION='USE SYM 2 - COMMON MODE CHOKE 67 OHM';
      HEIGHT='0.055 IN';
      COMPONENT_TYPE='SMALLSMT';
      LEAD_LENGTH='';
      LPID='270';
      SPEED_URL='http://speed.intel.com:8081/speed/module/pdm/item/pdm_item_deta~
il_direct.asp?item_cde=752402-028&item_rev=01&url_param=unused';
      STATUS='Design';
      RPL='YES';
      AML='1';
      BUS_UNIT='SMO_BOARDS';
      DAYS='???';
      PARENT_PART_TYPE='CHOKE_4PIN_SM_B';
      PARENT_PPT='CHOKE_4PIN';
      PARENT_PPT_PART='CHOKE_4PIN_SM_B-67 OHM,EMPTY,752402-028';
  end_body;
end_primitive;
primitive 'CLX-CONN3A-1-GP_CONN-G3-CLX-COA';
  pin
    '1':
      PIN_NUMBER='(1)';
      PIN_TYPE='ANALOG';
      NO_LOAD_CHECK='Both';
      NO_IO_CHECK='Both';
      NO_ASSERT_CHECK='TRUE';
      NO_DIR_CHECK='TRUE';
      ALLOW_CONNECT='TRUE';
      PINUSE='UNSPEC';
    '2':
      PIN_NUMBER='(2)';
      PIN_TYPE='ANALOG';
      NO_LOAD_CHECK='Both';
      NO_IO_CHECK='Both';
      NO_ASSERT_CHECK='TRUE';
      NO_DIR_CHECK='TRUE';
      ALLOW_CONNECT='TRUE';
      PINUSE='UNSPEC';
    '3':
      PIN_NUMBER='(3)';
      PIN_TYPE='ANALOG';
      NO_LOAD_CHECK='Both';
      NO_IO_CHECK='Both';
      NO_ASSERT_CHECK='TRUE';
      NO_DIR_CHECK='TRUE';
      ALLOW_CONNECT='TRUE';
      PINUSE='UNSPEC';
  end_pin;
  body
      PART_NAME='CLX-CONN3A-1-GP';
      BODY_NAME='CLX-CONN3A-1-GP';
      PHYS_DES_PREFIX='CN';
      CLASS='IO';
      DESCRIPTION='HEAD ML 1R3P CH11032M100-0P-NH SMD';
      JEDEC_TYPE='CH11032M100-0P-NH';
      PARENT_PART_TYPE='CLX-CONN3A-1-GP';
      PARENT_PPT='CLX-CONN3A-1-GP';
      PARENT_PPT_PART='CLX-CONN3A-1-GP_CONN-G3-CLX-CONN3A-1-GP,021.D0139.0103';
  end_body;
end_primitive;
primitive 'CONN12_C73564003_PIP-CONN,C735A';
  pin
    'IO1':
      PIN_NUMBER='(1)';
      BIDIRECTIONAL='TRUE';
      INPUT_LOAD='(-0.01,0.01)';
      OUTPUT_LOAD='(1.0,-1.0)';
      PINUSE='BI';
    'IO10':
      PIN_NUMBER='(10)';
      BIDIRECTIONAL='TRUE';
      INPUT_LOAD='(-0.01,0.01)';
      OUTPUT_LOAD='(1.0,-1.0)';
      PINUSE='BI';
    'IO11':
      PIN_NUMBER='(11)';
      BIDIRECTIONAL='TRUE';
      INPUT_LOAD='(-0.01,0.01)';
      OUTPUT_LOAD='(1.0,-1.0)';
      PINUSE='BI';
    'IO12':
      PIN_NUMBER='(12)';
      BIDIRECTIONAL='TRUE';
      INPUT_LOAD='(-0.01,0.01)';
      OUTPUT_LOAD='(1.0,-1.0)';
      PINUSE='BI';
    'IO2':
      PIN_NUMBER='(2)';
      BIDIRECTIONAL='TRUE';
      INPUT_LOAD='(-0.01,0.01)';
      OUTPUT_LOAD='(1.0,-1.0)';
      PINUSE='BI';
    'IO3':
      PIN_NUMBER='(3)';
      BIDIRECTIONAL='TRUE';
      INPUT_LOAD='(-0.01,0.01)';
      OUTPUT_LOAD='(1.0,-1.0)';
      PINUSE='BI';
    'IO4':
      PIN_NUMBER='(4)';
      BIDIRECTIONAL='TRUE';
      INPUT_LOAD='(-0.01,0.01)';
      OUTPUT_LOAD='(1.0,-1.0)';
      PINUSE='BI';
    'IO5':
      PIN_NUMBER='(5)';
      BIDIRECTIONAL='TRUE';
      INPUT_LOAD='(-0.01,0.01)';
      OUTPUT_LOAD='(1.0,-1.0)';
      PINUSE='BI';
    'IO6':
      PIN_NUMBER='(6)';
      BIDIRECTIONAL='TRUE';
      INPUT_LOAD='(-0.01,0.01)';
      OUTPUT_LOAD='(1.0,-1.0)';
      PINUSE='BI';
    'IO7':
      PIN_NUMBER='(7)';
      BIDIRECTIONAL='TRUE';
      INPUT_LOAD='(-0.01,0.01)';
      OUTPUT_LOAD='(1.0,-1.0)';
      PINUSE='BI';
    'IO8':
      PIN_NUMBER='(8)';
      BIDIRECTIONAL='TRUE';
      INPUT_LOAD='(-0.01,0.01)';
      OUTPUT_LOAD='(1.0,-1.0)';
      PINUSE='BI';
    'IO9':
      PIN_NUMBER='(9)';
      BIDIRECTIONAL='TRUE';
      INPUT_LOAD='(-0.01,0.01)';
      OUTPUT_LOAD='(1.0,-1.0)';
      PINUSE='BI';
  end_pin;
  body
      PART_NAME='CONN12_C73564003';
      PHYS_DES_PREFIX='J';
      ENVCOMP='';
      PART_NUMBER='C73564-003';
      JEDEC_TYPE='CONN12_C73564003_PIP';
      DESCRIPTION='CONN,HDR,2 X 6,PLG,VT,0.1,062ST,KP';
      CLASS='IO';
      COMPONENT_TYPE='THMT';
      HEIGHT='0.343 IN';
      LEAD_LENGTH='0.085';
      SPEED_URL='http://speed.intel.com:8081/speed/module/pdm/item/pdm_item_deta~
il_direct.asp?item_cde=C73564-003&item_rev=01&url_param=unused';
      STATUS='';
      RPL='';
      AML='';
      BUS_UNIT='';
      DAYS='';
      PARENT_PART_TYPE='CONN12_C73564003';
      PARENT_PPT='CONN12_C73564003';
      PARENT_PPT_PART='CONN12_C73564003_PIP-CONN,C73564-003';
  end_body;
end_primitive;
primitive 'CONN14_H54902001_PIP-CONN,H549A';
  pin
    'IO1':
      PIN_NUMBER='(1)';
      BIDIRECTIONAL='TRUE';
      INPUT_LOAD='(-0.01,0.01)';
      OUTPUT_LOAD='(1.0,-1.0)';
      PINUSE='BI';
    'IO10':
      PIN_NUMBER='(10)';
      BIDIRECTIONAL='TRUE';
      INPUT_LOAD='(-0.01,0.01)';
      OUTPUT_LOAD='(1.0,-1.0)';
      PINUSE='BI';
    'IO11':
      PIN_NUMBER='(11)';
      BIDIRECTIONAL='TRUE';
      INPUT_LOAD='(-0.01,0.01)';
      OUTPUT_LOAD='(1.0,-1.0)';
      PINUSE='BI';
    'IO12':
      PIN_NUMBER='(12)';
      BIDIRECTIONAL='TRUE';
      INPUT_LOAD='(-0.01,0.01)';
      OUTPUT_LOAD='(1.0,-1.0)';
      PINUSE='BI';
    'IO13':
      PIN_NUMBER='(13)';
      BIDIRECTIONAL='TRUE';
      INPUT_LOAD='(-0.01,0.01)';
      OUTPUT_LOAD='(1.0,-1.0)';
      PINUSE='BI';
    'IO14':
      PIN_NUMBER='(14)';
      BIDIRECTIONAL='TRUE';
      INPUT_LOAD='(-0.01,0.01)';
      OUTPUT_LOAD='(1.0,-1.0)';
      PINUSE='BI';
    'IO2':
      PIN_NUMBER='(2)';
      BIDIRECTIONAL='TRUE';
      INPUT_LOAD='(-0.01,0.01)';
      OUTPUT_LOAD='(1.0,-1.0)';
      PINUSE='BI';
    'IO3':
      PIN_NUMBER='(3)';
      BIDIRECTIONAL='TRUE';
      INPUT_LOAD='(-0.01,0.01)';
      OUTPUT_LOAD='(1.0,-1.0)';
      PINUSE='BI';
    'IO4':
      PIN_NUMBER='(4)';
      BIDIRECTIONAL='TRUE';
      INPUT_LOAD='(-0.01,0.01)';
      OUTPUT_LOAD='(1.0,-1.0)';
      PINUSE='BI';
    'IO5':
      PIN_NUMBER='(5)';
      BIDIRECTIONAL='TRUE';
      INPUT_LOAD='(-0.01,0.01)';
      OUTPUT_LOAD='(1.0,-1.0)';
      PINUSE='BI';
    'IO6':
      PIN_NUMBER='(6)';
      BIDIRECTIONAL='TRUE';
      INPUT_LOAD='(-0.01,0.01)';
      OUTPUT_LOAD='(1.0,-1.0)';
      PINUSE='BI';
    'IO7':
      PIN_NUMBER='(7)';
      BIDIRECTIONAL='TRUE';
      INPUT_LOAD='(-0.01,0.01)';
      OUTPUT_LOAD='(1.0,-1.0)';
      PINUSE='BI';
    'IO8':
      PIN_NUMBER='(8)';
      BIDIRECTIONAL='TRUE';
      INPUT_LOAD='(-0.01,0.01)';
      OUTPUT_LOAD='(1.0,-1.0)';
      PINUSE='BI';
    'IO9':
      PIN_NUMBER='(9)';
      BIDIRECTIONAL='TRUE';
      INPUT_LOAD='(-0.01,0.01)';
      OUTPUT_LOAD='(1.0,-1.0)';
      PINUSE='BI';
  end_pin;
  body
      PART_NAME='CONN14_H54902001';
      PHYS_DES_PREFIX='J';
      ENVCOMP='';
      PART_NUMBER='H54902-001';
      JEDEC_TYPE='CONN14_H54902001_PIP';
      DESCRIPTION='CONN_HDR,2X7,RCP,VT,2.00mm,9ST,NT';
      CLASS='IO';
      COMPONENT_TYPE='THMT';
      HEIGHT='0.195 IN';
      LEAD_LENGTH='0.117';
      SPEED_URL='http://speed.intel.com:8081/speed/module/pdm/item/pdm_item_deta~
il_direct.asp?item_cde=H54902-001&item_rev=01&url_param=unused';
      STATUS='';
      RPL='';
      AML='';
      BUS_UNIT='';
      DAYS='';
      PARENT_PART_TYPE='CONN14_H54902001_PIP';
      PARENT_PPT='CONN14_H54902001';
      PARENT_PPT_PART='CONN14_H54902001_PIP-CONN,H54902-001';
  end_body;
end_primitive;
primitive 'CONN3_C95678002_PIP-CONN,C9567A';
  pin
    'IO1':
      PIN_NUMBER='(1)';
      PINUSE='UNSPEC';
      NO_LOAD_CHECK='BOTH';
      NO_IO_CHECK='BOTH';
      ALLOW_CONNECT='TRUE';
    'IO2':
      PIN_NUMBER='(2)';
      PINUSE='UNSPEC';
      NO_LOAD_CHECK='BOTH';
      NO_IO_CHECK='BOTH';
      ALLOW_CONNECT='TRUE';
    'IO3':
      PIN_NUMBER='(3)';
      PINUSE='UNSPEC';
      NO_LOAD_CHECK='BOTH';
      NO_IO_CHECK='BOTH';
      ALLOW_CONNECT='TRUE';
  end_pin;
  body
      PART_NAME='CONN3_C95678002';
      PHYS_DES_PREFIX='J';
      ENVCOMP='';
      PART_NUMBER='C95678-002';
      JEDEC_TYPE='CONN3_C95678002_PIP';
      CLASS='IO';
      DESCRIPTION='CONN,HDR,1 X 3,PLG,VT,0.1,093ST,KP';
      HEIGHT='0.346 IN';
      COMPONENT_TYPE='THMT';
      LEAD_LENGTH='0.118';
      SPEED_URL='http://speed.intel.com:8081/speed/module/pdm/item/pdm_item_deta~
il_direct.asp?item_cde=C95678-002&item_rev=01&url_param=unused';
      STATUS='';
      RPL='';
      AML='';
      BUS_UNIT='';
      DAYS='';
      PARENT_PART_TYPE='CONN3_C95678002_PIP';
      PARENT_PPT='CONN3_C95678002';
      PARENT_PPT_PART='CONN3_C95678002_PIP-CONN,C95678-002';
  end_body;
end_primitive;
primitive 'CONN3_G98259001_PIP-CONN,G9825A';
  pin
    'IO1':
      PIN_NUMBER='(1)';
      BIDIRECTIONAL='TRUE';
      INPUT_LOAD='(-0.01,0.01)';
      OUTPUT_LOAD='(1.0,-1.0)';
      PINUSE='BI';
    'IO2':
      PIN_NUMBER='(2)';
      BIDIRECTIONAL='TRUE';
      INPUT_LOAD='(-0.01,0.01)';
      OUTPUT_LOAD='(1.0,-1.0)';
      PINUSE='BI';
    'IO3':
      PIN_NUMBER='(3)';
      BIDIRECTIONAL='TRUE';
      INPUT_LOAD='(-0.01,0.01)';
      OUTPUT_LOAD='(1.0,-1.0)';
      PINUSE='BI';
  end_pin;
  body
      PART_NAME='CONN3_G98259001';
      PHYS_DES_PREFIX='J';
      ENVCOMP='YES;YES;YES;UNK;ok;VLD';
      PART_NUMBER='G98259-001';
      JEDEC_TYPE='CONN3_G98259001_PIP';
      CLASS='IO';
      DESCRIPTION='CONN_HDR,3X1,PLG,RA,11.75mm,6ST,MT';
      HEIGHT='0.396 IN';
      COMPONENT_TYPE='THMT';
      LEAD_LENGTH='0.157';
      SPEED_URL='http://speed.intel.com:8081/speed/module/pdm/item/pdm_item_deta~
il_direct.asp?item_cde=G98259-001&item_rev=01&url_param=unused';
      STATUS='Design';
      RPL='NO';
      AML='1';
      BUS_UNIT='SMO_BOARDS';
      DAYS='???';
      PARENT_PART_TYPE='CONN3_G98259001_PIP';
      PARENT_PPT='CONN3_G98259001';
      PARENT_PPT_PART='CONN3_G98259001_PIP-CONN,G98259-001';
  end_body;
end_primitive;
primitive 'CONN4_D42317002_PIP-CONN,D4231A';
  pin
    'IO1':
      PIN_NUMBER='(1)';
      BIDIRECTIONAL='TRUE';
      INPUT_LOAD='(-0.01,0.01)';
      OUTPUT_LOAD='(1.0,-1.0)';
      PINUSE='BI';
    'IO2':
      PIN_NUMBER='(2)';
      BIDIRECTIONAL='TRUE';
      INPUT_LOAD='(-0.01,0.01)';
      OUTPUT_LOAD='(1.0,-1.0)';
      PINUSE='BI';
    'IO3':
      PIN_NUMBER='(3)';
      BIDIRECTIONAL='TRUE';
      INPUT_LOAD='(-0.01,0.01)';
      OUTPUT_LOAD='(1.0,-1.0)';
      PINUSE='BI';
    'IO4':
      PIN_NUMBER='(4)';
      BIDIRECTIONAL='TRUE';
      INPUT_LOAD='(-0.01,0.01)';
      OUTPUT_LOAD='(1.0,-1.0)';
      PINUSE='BI';
  end_pin;
  body
      PART_NAME='CONN4_D42317002';
      PHYS_DES_PREFIX='J';
      ENVCOMP='';
      PART_NUMBER='D42317-002';
      JEDEC_TYPE='CONN4_D42317002_PIP';
      CLASS='IO';
      DESCRIPTION='CONN,HDR,1X4,PLG,VT,2MM,093ST,KP';
      HEIGHT='0.244 IN';
      COMPONENT_TYPE='THMT';
      LEAD_LENGTH='0.126';
      SPEED_URL='http://speed.intel.com:8081/speed/module/pdm/item/pdm_item_deta~
il_direct.asp?item_cde=D42317-002&item_rev=01&url_param=unused';
      STATUS='';
      RPL='';
      AML='';
      BUS_UNIT='';
      DAYS='';
      PARENT_PART_TYPE='CONN4_D42317002_PIP';
      PARENT_PPT='CONN4_D42317002';
      PARENT_PPT_PART='CONN4_D42317002_PIP-CONN,D42317-002';
  end_body;
end_primitive;
primitive 'CONN6_C74770005_PIP-HDR,C74770A';
  pin
    'IO1':
      PIN_NUMBER='(1)';
      PIN_TYPE='UNSPEC';
      NO_LOAD_CHECK='BOTH';
      NO_IO_CHECK='BOTH';
      ALLOW_CONNECT='TRUE';
      PINUSE='UNSPEC';
    'IO2':
      PIN_NUMBER='(2)';
      PIN_TYPE='UNSPEC';
      NO_LOAD_CHECK='BOTH';
      NO_IO_CHECK='BOTH';
      ALLOW_CONNECT='TRUE';
      PINUSE='UNSPEC';
    'IO3':
      PIN_NUMBER='(3)';
      PIN_TYPE='UNSPEC';
      NO_LOAD_CHECK='BOTH';
      NO_IO_CHECK='BOTH';
      ALLOW_CONNECT='TRUE';
      PINUSE='UNSPEC';
    'IO4':
      PIN_NUMBER='(4)';
      PIN_TYPE='UNSPEC';
      NO_LOAD_CHECK='BOTH';
      NO_IO_CHECK='BOTH';
      ALLOW_CONNECT='TRUE';
      PINUSE='UNSPEC';
    'IO5':
      PIN_NUMBER='(5)';
      PIN_TYPE='UNSPEC';
      NO_LOAD_CHECK='BOTH';
      NO_IO_CHECK='BOTH';
      ALLOW_CONNECT='TRUE';
      PINUSE='UNSPEC';
    'IO6':
      PIN_NUMBER='(6)';
      PIN_TYPE='UNSPEC';
      NO_LOAD_CHECK='BOTH';
      NO_IO_CHECK='BOTH';
      ALLOW_CONNECT='TRUE';
      PINUSE='UNSPEC';
  end_pin;
  body
      PART_NAME='CONN6_C74770005';
      PHYS_DES_PREFIX='J';
      ENVCOMP='';
      PART_NUMBER='C74770-005';
      JEDEC_TYPE='CONN6_C74770005_PIP';
      CLASS='IO';
      DESCRIPTION='CONN,HDR,1 X 6,PLG,VT,0.1,093ST,KP SHR';
      HEIGHT='0.421 IN';
      COMPONENT_TYPE='THMT';
      LEAD_LENGTH='0.138';
      SPEED_URL='http://speed.intel.com:8081/speed/module/pdm/item/pdm_item_deta~
il_direct.asp?item_cde=C74770-005&item_rev=01&url_param=unused';
      STATUS='';
      RPL='';
      AML='';
      BUS_UNIT='';
      DAYS='';
      PARENT_PART_TYPE='CONN6_C74770005';
      PARENT_PPT='CONN6_C74770005';
      PARENT_PPT_PART='CONN6_C74770005_PIP-HDR,C74770-005';
  end_body;
end_primitive;
primitive 'CONN72_G97614002_A_CP-CONN,G97A';
  pin
    'GND'<23>:
      PIN_NUMBER='(1A3)';
      PINUSE='GROUND';
      NO_LOAD_CHECK='Both';
      NO_IO_CHECK='Both';
      NO_ASSERT_CHECK='TRUE';
      NO_DIR_CHECK='TRUE';
      ALLOW_CONNECT='TRUE';
    'GND'<22>:
      PIN_NUMBER='(1A6)';
      PINUSE='GROUND';
      NO_LOAD_CHECK='Both';
      NO_IO_CHECK='Both';
      NO_ASSERT_CHECK='TRUE';
      NO_DIR_CHECK='TRUE';
      ALLOW_CONNECT='TRUE';
    'GND'<21>:
      PIN_NUMBER='(1A9)';
      PINUSE='GROUND';
      NO_LOAD_CHECK='Both';
      NO_IO_CHECK='Both';
      NO_ASSERT_CHECK='TRUE';
      NO_DIR_CHECK='TRUE';
      ALLOW_CONNECT='TRUE';
    'GND'<20>:
      PIN_NUMBER='(1B3)';
      PINUSE='GROUND';
      NO_LOAD_CHECK='Both';
      NO_IO_CHECK='Both';
      NO_ASSERT_CHECK='TRUE';
      NO_DIR_CHECK='TRUE';
      ALLOW_CONNECT='TRUE';
    'GND'<19>:
      PIN_NUMBER='(1B6)';
      PINUSE='GROUND';
      NO_LOAD_CHECK='Both';
      NO_IO_CHECK='Both';
      NO_ASSERT_CHECK='TRUE';
      NO_DIR_CHECK='TRUE';
      ALLOW_CONNECT='TRUE';
    'GND'<18>:
      PIN_NUMBER='(1B9)';
      PINUSE='GROUND';
      NO_LOAD_CHECK='Both';
      NO_IO_CHECK='Both';
      NO_ASSERT_CHECK='TRUE';
      NO_DIR_CHECK='TRUE';
      ALLOW_CONNECT='TRUE';
    'GND'<17>:
      PIN_NUMBER='(1C3)';
      PINUSE='GROUND';
      NO_LOAD_CHECK='Both';
      NO_IO_CHECK='Both';
      NO_ASSERT_CHECK='TRUE';
      NO_DIR_CHECK='TRUE';
      ALLOW_CONNECT='TRUE';
    'GND'<16>:
      PIN_NUMBER='(1C6)';
      PINUSE='GROUND';
      NO_LOAD_CHECK='Both';
      NO_IO_CHECK='Both';
      NO_ASSERT_CHECK='TRUE';
      NO_DIR_CHECK='TRUE';
      ALLOW_CONNECT='TRUE';
    'GND'<15>:
      PIN_NUMBER='(1C9)';
      PINUSE='GROUND';
      NO_LOAD_CHECK='Both';
      NO_IO_CHECK='Both';
      NO_ASSERT_CHECK='TRUE';
      NO_DIR_CHECK='TRUE';
      ALLOW_CONNECT='TRUE';
    'GND'<14>:
      PIN_NUMBER='(1D3)';
      PINUSE='GROUND';
      NO_LOAD_CHECK='Both';
      NO_IO_CHECK='Both';
      NO_ASSERT_CHECK='TRUE';
      NO_DIR_CHECK='TRUE';
      ALLOW_CONNECT='TRUE';
    'GND'<13>:
      PIN_NUMBER='(1D6)';
      BIDIRECTIONAL='TRUE';
      INPUT_LOAD='(-0.01,0.01)';
      OUTPUT_LOAD='(1.0,-1.0)';
      PINUSE='BI';
    'GND'<12>:
      PIN_NUMBER='(1D9)';
      PINUSE='GROUND';
      NO_LOAD_CHECK='Both';
      NO_IO_CHECK='Both';
      NO_ASSERT_CHECK='TRUE';
      NO_DIR_CHECK='TRUE';
      ALLOW_CONNECT='TRUE';
    'GND'<11>:
      PIN_NUMBER='(2A3)';
      PINUSE='GROUND';
      NO_LOAD_CHECK='Both';
      NO_IO_CHECK='Both';
      NO_ASSERT_CHECK='TRUE';
      NO_DIR_CHECK='TRUE';
      ALLOW_CONNECT='TRUE';
    'GND'<10>:
      PIN_NUMBER='(2A6)';
      PINUSE='GROUND';
      NO_LOAD_CHECK='Both';
      NO_IO_CHECK='Both';
      NO_ASSERT_CHECK='TRUE';
      NO_DIR_CHECK='TRUE';
      ALLOW_CONNECT='TRUE';
    'GND'<9>:
      PIN_NUMBER='(2A9)';
      PINUSE='GROUND';
      NO_LOAD_CHECK='Both';
      NO_IO_CHECK='Both';
      NO_ASSERT_CHECK='TRUE';
      NO_DIR_CHECK='TRUE';
      ALLOW_CONNECT='TRUE';
    'GND'<8>:
      PIN_NUMBER='(2B3)';
      PINUSE='GROUND';
      NO_LOAD_CHECK='Both';
      NO_IO_CHECK='Both';
      NO_ASSERT_CHECK='TRUE';
      NO_DIR_CHECK='TRUE';
      ALLOW_CONNECT='TRUE';
    'GND'<7>:
      PIN_NUMBER='(2B6)';
      PINUSE='GROUND';
      NO_LOAD_CHECK='Both';
      NO_IO_CHECK='Both';
      NO_ASSERT_CHECK='TRUE';
      NO_DIR_CHECK='TRUE';
      ALLOW_CONNECT='TRUE';
    'GND'<6>:
      PIN_NUMBER='(2B9)';
      PINUSE='GROUND';
      NO_LOAD_CHECK='Both';
      NO_IO_CHECK='Both';
      NO_ASSERT_CHECK='TRUE';
      NO_DIR_CHECK='TRUE';
      ALLOW_CONNECT='TRUE';
    'GND'<5>:
      PIN_NUMBER='(2C3)';
      PINUSE='GROUND';
      NO_LOAD_CHECK='Both';
      NO_IO_CHECK='Both';
      NO_ASSERT_CHECK='TRUE';
      NO_DIR_CHECK='TRUE';
      ALLOW_CONNECT='TRUE';
    'GND'<4>:
      PIN_NUMBER='(2C6)';
      PINUSE='GROUND';
      NO_LOAD_CHECK='Both';
      NO_IO_CHECK='Both';
      NO_ASSERT_CHECK='TRUE';
      NO_DIR_CHECK='TRUE';
      ALLOW_CONNECT='TRUE';
    'GND'<3>:
      PIN_NUMBER='(2C9)';
      PINUSE='GROUND';
      NO_LOAD_CHECK='Both';
      NO_IO_CHECK='Both';
      NO_ASSERT_CHECK='TRUE';
      NO_DIR_CHECK='TRUE';
      ALLOW_CONNECT='TRUE';
    'GND'<2>:
      PIN_NUMBER='(2D3)';
      PINUSE='GROUND';
      NO_LOAD_CHECK='Both';
      NO_IO_CHECK='Both';
      NO_ASSERT_CHECK='TRUE';
      NO_DIR_CHECK='TRUE';
      ALLOW_CONNECT='TRUE';
    'GND'<1>:
      PIN_NUMBER='(2D6)';
      BIDIRECTIONAL='TRUE';
      INPUT_LOAD='(-0.01,0.01)';
      OUTPUT_LOAD='(1.0,-1.0)';
      PINUSE='BI';
    'GND'<0>:
      PIN_NUMBER='(2D9)';
      PINUSE='GROUND';
      NO_LOAD_CHECK='Both';
      NO_IO_CHECK='Both';
      NO_ASSERT_CHECK='TRUE';
      NO_DIR_CHECK='TRUE';
      ALLOW_CONNECT='TRUE';
    'RXA0_DN':
      PIN_NUMBER='(1B5)';
      BIDIRECTIONAL='TRUE';
      INPUT_LOAD='(-0.01,0.01)';
      OUTPUT_LOAD='(1.0,-1.0)';
      PINUSE='BI';
    'RXA0_DP':
      PIN_NUMBER='(1B4)';
      BIDIRECTIONAL='TRUE';
      INPUT_LOAD='(-0.01,0.01)';
      OUTPUT_LOAD='(1.0,-1.0)';
      PINUSE='BI';
    'RXA1_DN':
      PIN_NUMBER='(1A5)';
      BIDIRECTIONAL='TRUE';
      INPUT_LOAD='(-0.01,0.01)';
      OUTPUT_LOAD='(1.0,-1.0)';
      PINUSE='BI';
    'RXA1_DP':
      PIN_NUMBER='(1A4)';
      BIDIRECTIONAL='TRUE';
      INPUT_LOAD='(-0.01,0.01)';
      OUTPUT_LOAD='(1.0,-1.0)';
      PINUSE='BI';
    'RXA2_DN':
      PIN_NUMBER='(1B8)';
      BIDIRECTIONAL='TRUE';
      INPUT_LOAD='(-0.01,0.01)';
      OUTPUT_LOAD='(1.0,-1.0)';
      PINUSE='BI';
    'RXA2_DP':
      PIN_NUMBER='(1B7)';
      BIDIRECTIONAL='TRUE';
      INPUT_LOAD='(-0.01,0.01)';
      OUTPUT_LOAD='(1.0,-1.0)';
      PINUSE='BI';
    'RXA3_DN':
      PIN_NUMBER='(1A8)';
      BIDIRECTIONAL='TRUE';
      INPUT_LOAD='(-0.01,0.01)';
      OUTPUT_LOAD='(1.0,-1.0)';
      PINUSE='BI';
    'RXA3_DP':
      PIN_NUMBER='(1A7)';
      BIDIRECTIONAL='TRUE';
      INPUT_LOAD='(-0.01,0.01)';
      OUTPUT_LOAD='(1.0,-1.0)';
      PINUSE='BI';
    'RXB0_DN':
      PIN_NUMBER='(2B5)';
      BIDIRECTIONAL='TRUE';
      INPUT_LOAD='(-0.01,0.01)';
      OUTPUT_LOAD='(1.0,-1.0)';
      PINUSE='BI';
    'RXB0_DP':
      PIN_NUMBER='(2B4)';
      BIDIRECTIONAL='TRUE';
      INPUT_LOAD='(-0.01,0.01)';
      OUTPUT_LOAD='(1.0,-1.0)';
      PINUSE='BI';
    'RXB1_DN':
      PIN_NUMBER='(2A5)';
      BIDIRECTIONAL='TRUE';
      INPUT_LOAD='(-0.01,0.01)';
      OUTPUT_LOAD='(1.0,-1.0)';
      PINUSE='BI';
    'RXB1_DP':
      PIN_NUMBER='(2A4)';
      BIDIRECTIONAL='TRUE';
      INPUT_LOAD='(-0.01,0.01)';
      OUTPUT_LOAD='(1.0,-1.0)';
      PINUSE='BI';
    'RXB2_DN':
      PIN_NUMBER='(2B8)';
      BIDIRECTIONAL='TRUE';
      INPUT_LOAD='(-0.01,0.01)';
      OUTPUT_LOAD='(1.0,-1.0)';
      PINUSE='BI';
    'RXB2_DP':
      PIN_NUMBER='(2B7)';
      BIDIRECTIONAL='TRUE';
      INPUT_LOAD='(-0.01,0.01)';
      OUTPUT_LOAD='(1.0,-1.0)';
      PINUSE='BI';
    'RXB3_DN':
      PIN_NUMBER='(2A8)';
      BIDIRECTIONAL='TRUE';
      INPUT_LOAD='(-0.01,0.01)';
      OUTPUT_LOAD='(1.0,-1.0)';
      PINUSE='BI';
    'RXB3_DP':
      PIN_NUMBER='(2A7)';
      BIDIRECTIONAL='TRUE';
      INPUT_LOAD='(-0.01,0.01)';
      OUTPUT_LOAD='(1.0,-1.0)';
      PINUSE='BI';
    'SIDEBANDA_0':
      PIN_NUMBER='(1A2)';
      BIDIRECTIONAL='TRUE';
      INPUT_LOAD='(-0.01,0.01)';
      OUTPUT_LOAD='(1.0,-1.0)';
      PINUSE='BI';
    'SIDEBANDA_1':
      PIN_NUMBER='(1B2)';
      BIDIRECTIONAL='TRUE';
      INPUT_LOAD='(-0.01,0.01)';
      OUTPUT_LOAD='(1.0,-1.0)';
      PINUSE='BI';
    'SIDEBANDA_2':
      PIN_NUMBER='(1C2)';
      BIDIRECTIONAL='TRUE';
      INPUT_LOAD='(-0.01,0.01)';
      OUTPUT_LOAD='(1.0,-1.0)';
      PINUSE='BI';
    'SIDEBANDA_3':
      PIN_NUMBER='(1B1)';
      BIDIRECTIONAL='TRUE';
      INPUT_LOAD='(-0.01,0.01)';
      OUTPUT_LOAD='(1.0,-1.0)';
      PINUSE='BI';
    'SIDEBANDA_4':
      PIN_NUMBER='(1C1)';
      BIDIRECTIONAL='TRUE';
      INPUT_LOAD='(-0.01,0.01)';
      OUTPUT_LOAD='(1.0,-1.0)';
      PINUSE='BI';
    'SIDEBANDA_5':
      PIN_NUMBER='(1D1)';
      BIDIRECTIONAL='TRUE';
      INPUT_LOAD='(-0.01,0.01)';
      OUTPUT_LOAD='(1.0,-1.0)';
      PINUSE='BI';
    'SIDEBANDA_6':
      PIN_NUMBER='(1D2)';
      BIDIRECTIONAL='TRUE';
      INPUT_LOAD='(-0.01,0.01)';
      OUTPUT_LOAD='(1.0,-1.0)';
      PINUSE='BI';
    'SIDEBANDA_7':
      PIN_NUMBER='(1A1)';
      BIDIRECTIONAL='TRUE';
      INPUT_LOAD='(-0.01,0.01)';
      OUTPUT_LOAD='(1.0,-1.0)';
      PINUSE='BI';
    'SIDEBANDB_0':
      PIN_NUMBER='(2A2)';
      BIDIRECTIONAL='TRUE';
      INPUT_LOAD='(-0.01,0.01)';
      OUTPUT_LOAD='(1.0,-1.0)';
      PINUSE='BI';
    'SIDEBANDB_1':
      PIN_NUMBER='(2B2)';
      BIDIRECTIONAL='TRUE';
      INPUT_LOAD='(-0.01,0.01)';
      OUTPUT_LOAD='(1.0,-1.0)';
      PINUSE='BI';
    'SIDEBANDB_2':
      PIN_NUMBER='(2C2)';
      BIDIRECTIONAL='TRUE';
      INPUT_LOAD='(-0.01,0.01)';
      OUTPUT_LOAD='(1.0,-1.0)';
      PINUSE='BI';
    'SIDEBANDB_3':
      PIN_NUMBER='(2B1)';
      BIDIRECTIONAL='TRUE';
      INPUT_LOAD='(-0.01,0.01)';
      OUTPUT_LOAD='(1.0,-1.0)';
      PINUSE='BI';
    'SIDEBANDB_4':
      PIN_NUMBER='(2C1)';
      BIDIRECTIONAL='TRUE';
      INPUT_LOAD='(-0.01,0.01)';
      OUTPUT_LOAD='(1.0,-1.0)';
      PINUSE='BI';
    'SIDEBANDB_5':
      PIN_NUMBER='(2D1)';
      BIDIRECTIONAL='TRUE';
      INPUT_LOAD='(-0.01,0.01)';
      OUTPUT_LOAD='(1.0,-1.0)';
      PINUSE='BI';
    'SIDEBANDB_6':
      PIN_NUMBER='(2D2)';
      BIDIRECTIONAL='TRUE';
      INPUT_LOAD='(-0.01,0.01)';
      OUTPUT_LOAD='(1.0,-1.0)';
      PINUSE='BI';
    'SIDEBANDB_7':
      PIN_NUMBER='(2A1)';
      BIDIRECTIONAL='TRUE';
      INPUT_LOAD='(-0.01,0.01)';
      OUTPUT_LOAD='(1.0,-1.0)';
      PINUSE='BI';
    'TXA0_DN':
      PIN_NUMBER='(1D5)';
      BIDIRECTIONAL='TRUE';
      INPUT_LOAD='(-0.01,0.01)';
      OUTPUT_LOAD='(1.0,-1.0)';
      PINUSE='BI';
    'TXA0_DP':
      PIN_NUMBER='(1D4)';
      BIDIRECTIONAL='TRUE';
      INPUT_LOAD='(-0.01,0.01)';
      OUTPUT_LOAD='(1.0,-1.0)';
      PINUSE='BI';
    'TXA1_DN':
      PIN_NUMBER='(1C5)';
      BIDIRECTIONAL='TRUE';
      INPUT_LOAD='(-0.01,0.01)';
      OUTPUT_LOAD='(1.0,-1.0)';
      PINUSE='BI';
    'TXA1_DP':
      PIN_NUMBER='(1C4)';
      BIDIRECTIONAL='TRUE';
      INPUT_LOAD='(-0.01,0.01)';
      OUTPUT_LOAD='(1.0,-1.0)';
      PINUSE='BI';
    'TXA2_DN':
      PIN_NUMBER='(1D8)';
      BIDIRECTIONAL='TRUE';
      INPUT_LOAD='(-0.01,0.01)';
      OUTPUT_LOAD='(1.0,-1.0)';
      PINUSE='BI';
    'TXA2_DP':
      PIN_NUMBER='(1D7)';
      BIDIRECTIONAL='TRUE';
      INPUT_LOAD='(-0.01,0.01)';
      OUTPUT_LOAD='(1.0,-1.0)';
      PINUSE='BI';
    'TXA3_DN':
      PIN_NUMBER='(1C8)';
      BIDIRECTIONAL='TRUE';
      INPUT_LOAD='(-0.01,0.01)';
      OUTPUT_LOAD='(1.0,-1.0)';
      PINUSE='BI';
    'TXA3_DP':
      PIN_NUMBER='(1C7)';
      BIDIRECTIONAL='TRUE';
      INPUT_LOAD='(-0.01,0.01)';
      OUTPUT_LOAD='(1.0,-1.0)';
      PINUSE='BI';
    'TXB0_DN':
      PIN_NUMBER='(2D5)';
      BIDIRECTIONAL='TRUE';
      INPUT_LOAD='(-0.01,0.01)';
      OUTPUT_LOAD='(1.0,-1.0)';
      PINUSE='BI';
    'TXB0_DP':
      PIN_NUMBER='(2D4)';
      BIDIRECTIONAL='TRUE';
      INPUT_LOAD='(-0.01,0.01)';
      OUTPUT_LOAD='(1.0,-1.0)';
      PINUSE='BI';
    'TXB1_DN':
      PIN_NUMBER='(2C5)';
      BIDIRECTIONAL='TRUE';
      INPUT_LOAD='(-0.01,0.01)';
      OUTPUT_LOAD='(1.0,-1.0)';
      PINUSE='BI';
    'TXB1_DP':
      PIN_NUMBER='(2C4)';
      BIDIRECTIONAL='TRUE';
      INPUT_LOAD='(-0.01,0.01)';
      OUTPUT_LOAD='(1.0,-1.0)';
      PINUSE='BI';
    'TXB2_DN':
      PIN_NUMBER='(2D8)';
      BIDIRECTIONAL='TRUE';
      INPUT_LOAD='(-0.01,0.01)';
      OUTPUT_LOAD='(1.0,-1.0)';
      PINUSE='BI';
    'TXB2_DP':
      PIN_NUMBER='(2D7)';
      BIDIRECTIONAL='TRUE';
      INPUT_LOAD='(-0.01,0.01)';
      OUTPUT_LOAD='(1.0,-1.0)';
      PINUSE='BI';
    'TXB3_DN':
      PIN_NUMBER='(2C8)';
      BIDIRECTIONAL='TRUE';
      INPUT_LOAD='(-0.01,0.01)';
      OUTPUT_LOAD='(1.0,-1.0)';
      PINUSE='BI';
    'TXB3_DP':
      PIN_NUMBER='(2C7)';
      BIDIRECTIONAL='TRUE';
      INPUT_LOAD='(-0.01,0.01)';
      OUTPUT_LOAD='(1.0,-1.0)';
      PINUSE='BI';
  end_pin;
  body
      PART_NAME='CONN72_G97614002_A';
      PHYS_DES_PREFIX='J';
      ENVCOMP='YES;YES;CNC;CNC;ok;VLD';
      PART_NUMBER='G97614-002';
      JEDEC_TYPE='CONN72_G97614002';
      DESCRIPTION='(SYM_1)CONN,MISC,72P,CONNECTOR,MINISAS HD';
      CLASS='IO';
      HEIGHT='0.550 IN';
      COMPONENT_TYPE='PRESSFIT';
      LEAD_LENGTH='0.061';
      SPEED_URL='http://speed.intel.com:8081/speed/module/pdm/item/pdm_item_deta~
il_direct.asp?item_cde=G97614-002&item_rev=01&url_param=unused';
      STATUS='Design';
      RPL='NO';
      AML='1';
      BUS_UNIT='SMO_BOARDS';
      DAYS='???';
      PARENT_PART_TYPE='CONN72_G97614002_A_CP';
      PARENT_PPT='CONN72_G97614002_A';
      PARENT_PPT_PART='CONN72_G97614002_A_CP-CONN,G97614-002';
  end_body;
end_primitive;
primitive 'CONN8_C77962004_PIP-CONN,C7796A';
  pin
    'IO1':
      PIN_NUMBER='(1)';
      INPUT_LOAD='(-0.01,0.01)';
      OUTPUT_LOAD='(1.0,-1.0)';
      OUTPUT_TYPE='(TS,TS)';
      BIDIRECTIONAL='TRUE';
      PINUSE='BI';
    'IO2':
      PIN_NUMBER='(2)';
      INPUT_LOAD='(-0.01,0.01)';
      OUTPUT_LOAD='(1.0,-1.0)';
      OUTPUT_TYPE='(TS,TS)';
      BIDIRECTIONAL='TRUE';
      PINUSE='BI';
    'IO3':
      PIN_NUMBER='(3)';
      INPUT_LOAD='(-0.01,0.01)';
      OUTPUT_LOAD='(1.0,-1.0)';
      OUTPUT_TYPE='(TS,TS)';
      BIDIRECTIONAL='TRUE';
      PINUSE='BI';
    'IO4':
      PIN_NUMBER='(4)';
      INPUT_LOAD='(-0.01,0.01)';
      OUTPUT_LOAD='(1.0,-1.0)';
      OUTPUT_TYPE='(TS,TS)';
      BIDIRECTIONAL='TRUE';
      PINUSE='BI';
    'IO5':
      PIN_NUMBER='(5)';
      INPUT_LOAD='(-0.01,0.01)';
      OUTPUT_LOAD='(1.0,-1.0)';
      OUTPUT_TYPE='(TS,TS)';
      BIDIRECTIONAL='TRUE';
      PINUSE='BI';
    'IO6':
      PIN_NUMBER='(6)';
      INPUT_LOAD='(-0.01,0.01)';
      OUTPUT_LOAD='(1.0,-1.0)';
      OUTPUT_TYPE='(TS,TS)';
      BIDIRECTIONAL='TRUE';
      PINUSE='BI';
    'IO7':
      PIN_NUMBER='(7)';
      INPUT_LOAD='(-0.01,0.01)';
      OUTPUT_LOAD='(1.0,-1.0)';
      OUTPUT_TYPE='(TS,TS)';
      BIDIRECTIONAL='TRUE';
      PINUSE='BI';
    'IO8':
      PIN_NUMBER='(8)';
      INPUT_LOAD='(-0.01,0.01)';
      OUTPUT_LOAD='(1.0,-1.0)';
      OUTPUT_TYPE='(TS,TS)';
      BIDIRECTIONAL='TRUE';
      PINUSE='BI';
  end_pin;
  body
      PART_NAME='CONN8_C77962004';
      CLASS='IO';
      PHYS_DES_PREFIX='J';
      ENVCOMP='';
      PART_NUMBER='C77962-004';
      JEDEC_TYPE='CONN8_C77962004_PIP';
      DESCRIPTION='PIP PHYSICAL HEADER - 8PIN .100 PITCH';
      COMPONENT_TYPE='THMT';
      HEIGHT='0.343 IN';
      LEAD_LENGTH='0.085';
      SPEED_URL='http://speed.intel.com:8081/speed/module/pdm/item/pdm_item_deta~
il_direct.asp?item_cde=C77962-004&item_rev=01&url_param=unused';
      STATUS='';
      RPL='';
      AML='';
      BUS_UNIT='';
      DAYS='';
      PARENT_PART_TYPE='CONN8_C77962004';
      PARENT_PPT='CONN8_C77962004';
      PARENT_PPT_PART='CONN8_C77962004_PIP-CONN,C77962-004';
  end_body;
end_primitive;
primitive 'CONN8_H62179001_PIP-CONN,H6217A';
  pin
    'IO1':
      PIN_NUMBER='(1)';
      BIDIRECTIONAL='TRUE';
      INPUT_LOAD='(-0.01,0.01)';
      OUTPUT_LOAD='(1.0,-1.0)';
      PINUSE='BI';
    'IO2':
      PIN_NUMBER='(2)';
      BIDIRECTIONAL='TRUE';
      INPUT_LOAD='(-0.01,0.01)';
      OUTPUT_LOAD='(1.0,-1.0)';
      PINUSE='BI';
    'IO3':
      PIN_NUMBER='(3)';
      BIDIRECTIONAL='TRUE';
      INPUT_LOAD='(-0.01,0.01)';
      OUTPUT_LOAD='(1.0,-1.0)';
      PINUSE='BI';
    'IO4':
      PIN_NUMBER='(4)';
      BIDIRECTIONAL='TRUE';
      INPUT_LOAD='(-0.01,0.01)';
      OUTPUT_LOAD='(1.0,-1.0)';
      PINUSE='BI';
    'IO5':
      PIN_NUMBER='(5)';
      BIDIRECTIONAL='TRUE';
      INPUT_LOAD='(-0.01,0.01)';
      OUTPUT_LOAD='(1.0,-1.0)';
      PINUSE='BI';
    'IO6':
      PIN_NUMBER='(6)';
      BIDIRECTIONAL='TRUE';
      INPUT_LOAD='(-0.01,0.01)';
      OUTPUT_LOAD='(1.0,-1.0)';
      PINUSE='BI';
    'IO7':
      PIN_NUMBER='(7)';
      BIDIRECTIONAL='TRUE';
      INPUT_LOAD='(-0.01,0.01)';
      OUTPUT_LOAD='(1.0,-1.0)';
      PINUSE='BI';
    'IO8':
      PIN_NUMBER='(8)';
      BIDIRECTIONAL='TRUE';
      INPUT_LOAD='(-0.01,0.01)';
      OUTPUT_LOAD='(1.0,-1.0)';
      PINUSE='BI';
  end_pin;
  body
      PART_NAME='CONN8_H62179001';
      PHYS_DES_PREFIX='J';
      ENVCOMP='';
      PART_NUMBER='H62179-001';
      JEDEC_TYPE='CONN8_H62179001_PIP';
      DESCRIPTION='CONN,HDR,1X8,PLG,VT,1.25MM,093ST,KPSHR';
      CLASS='IO';
      COMPONENT_TYPE='THMT';
      HEIGHT='0.193 IN';
      LEAD_LENGTH='0.091';
      SPEED_URL='http://speed.intel.com:8081/speed/module/pdm/item/pdm_item_deta~
il_direct.asp?item_cde=H62179-001&item_rev=01&url_param=unused';
      STATUS='';
      RPL='';
      AML='';
      BUS_UNIT='';
      DAYS='';
      PARENT_PART_TYPE='CONN8_H62179001_PIP';
      PARENT_PPT='CONN8_H62179001';
      PARENT_PPT_PART='CONN8_H62179001_PIP-CONN,H62179-001';
  end_body;
end_primitive;
primitive 'CONN9_H51826001_PIP2-CONN,H518A';
  pin
    'DN':
      PIN_NUMBER='(2)';
      BIDIRECTIONAL='TRUE';
      INPUT_LOAD='(-0.01,0.01)';
      OUTPUT_LOAD='(1.0,-1.0)';
      PINUSE='BI';
    'DP':
      PIN_NUMBER='(3)';
      BIDIRECTIONAL='TRUE';
      INPUT_LOAD='(-0.01,0.01)';
      OUTPUT_LOAD='(1.0,-1.0)';
      PINUSE='BI';
    'GND':
      PIN_NUMBER='(4)';
      PINUSE='GROUND';
      NO_LOAD_CHECK='Both';
      NO_IO_CHECK='Both';
      NO_ASSERT_CHECK='TRUE';
      NO_DIR_CHECK='TRUE';
      ALLOW_CONNECT='TRUE';
    'GND_DRAIN':
      PIN_NUMBER='(7)';
      PINUSE='GROUND';
      NO_LOAD_CHECK='Both';
      NO_IO_CHECK='Both';
      NO_ASSERT_CHECK='TRUE';
      NO_DIR_CHECK='TRUE';
      ALLOW_CONNECT='TRUE';
    'MH1':
      PIN_NUMBER='(MH1)';
      PINUSE='GROUND';
      NO_LOAD_CHECK='Both';
      NO_IO_CHECK='Both';
      NO_ASSERT_CHECK='TRUE';
      NO_DIR_CHECK='TRUE';
      ALLOW_CONNECT='TRUE';
    'MH2':
      PIN_NUMBER='(MH2)';
      PINUSE='GROUND';
      NO_LOAD_CHECK='Both';
      NO_IO_CHECK='Both';
      NO_ASSERT_CHECK='TRUE';
      NO_DIR_CHECK='TRUE';
      ALLOW_CONNECT='TRUE';
    'MH3':
      PIN_NUMBER='(MH3)';
      PINUSE='GROUND';
      NO_LOAD_CHECK='Both';
      NO_IO_CHECK='Both';
      NO_ASSERT_CHECK='TRUE';
      NO_DIR_CHECK='TRUE';
      ALLOW_CONNECT='TRUE';
    'MH4':
      PIN_NUMBER='(MH4)';
      PINUSE='GROUND';
      NO_LOAD_CHECK='Both';
      NO_IO_CHECK='Both';
      NO_ASSERT_CHECK='TRUE';
      NO_DIR_CHECK='TRUE';
      ALLOW_CONNECT='TRUE';
    'STDA_SSRXN':
      PIN_NUMBER='(5)';
      BIDIRECTIONAL='TRUE';
      INPUT_LOAD='(-0.01,0.01)';
      OUTPUT_LOAD='(1.0,-1.0)';
      PINUSE='BI';
    'STDA_SSRXP':
      PIN_NUMBER='(6)';
      BIDIRECTIONAL='TRUE';
      INPUT_LOAD='(-0.01,0.01)';
      OUTPUT_LOAD='(1.0,-1.0)';
      PINUSE='BI';
    'STDA_SSTXN':
      PIN_NUMBER='(8)';
      BIDIRECTIONAL='TRUE';
      INPUT_LOAD='(-0.01,0.01)';
      OUTPUT_LOAD='(1.0,-1.0)';
      PINUSE='BI';
    'STDA_SSTXP':
      PIN_NUMBER='(9)';
      BIDIRECTIONAL='TRUE';
      INPUT_LOAD='(-0.01,0.01)';
      OUTPUT_LOAD='(1.0,-1.0)';
      PINUSE='BI';
    'VBUS':
      PIN_NUMBER='(1)';
      BIDIRECTIONAL='TRUE';
      INPUT_LOAD='(-0.01,0.01)';
      OUTPUT_LOAD='(1.0,-1.0)';
      PINUSE='BI';
  end_pin;
  body
      PART_NAME='CONN9_H51826001';
      PHYS_DES_PREFIX='J';
      ENVCOMP='';
      PART_NUMBER='H51826-001';
      JEDEC_TYPE='CONN9_H51826001_PIP';
      CLASS='IO';
      DESCRIPTION='(USB 3.0 USE SYM_2)   CONN,I/O,9P,USB,FLG,MIXED,062ST';
      COMPONENT_TYPE='THMT';
      HEIGHT='0.553 IN';
      LEAD_LENGTH='0.096';
      SPEED_URL='http://speed.intel.com:8081/speed/module/pdm/item/pdm_item_deta~
il_direct.asp?item_cde=H51826-001&item_rev=01&url_param=unused';
      STATUS='';
      RPL='';
      AML='';
      BUS_UNIT='';
      DAYS='';
      PARENT_PART_TYPE='CONN9_H51826001_PIP2';
      PARENT_PPT='CONN9_H51826001';
      PARENT_PPT_PART='CONN9_H51826001_PIP2-CONN,H51826-001';
  end_body;
end_primitive;
primitive 'CRYSTAL_2013-25.000MHZ,IC,D717A';
  pin
    'A':
      PIN_NUMBER='(1)';
      PINUSE='UNSPEC';
      NO_LOAD_CHECK='BOTH';
      NO_IO_CHECK='BOTH';
      ALLOW_CONNECT='TRUE';
      PIN_GROUP='1';
    'B':
      PIN_NUMBER='(3)';
      PINUSE='UNSPEC';
      NO_LOAD_CHECK='BOTH';
      NO_IO_CHECK='BOTH';
      ALLOW_CONNECT='TRUE';
      PIN_GROUP='1';
  end_pin;
  body
      POWER_PINS='(GND:2,4)';
      PART_NAME='CRYSTAL';
      PHYS_DES_PREFIX='Y';
      ENVCOMP='';
      PART_NUMBER='D71700-057';
      JEDEC_TYPE='SMY1310A';
      CLASS='IC';
      DESCRIPTION='(USE SYM 3 OR 4)XTAL,CER3.2X2.5,25.00,MHZ,18.0,PF,0.003%,SM';
      HEIGHT='0.031 IN';
      COMPONENT_TYPE='SMTOTHER';
      LEAD_LENGTH='';
      LPID='1719';
      SPEED_URL='http://speed.intel.com:8081/speed/module/pdm/item/pdm_item_deta~
il_direct.asp?item_cde=D71700-057&item_rev=01&url_param=unused';
      STATUS='';
      RPL='';
      AML='';
      BUS_UNIT='';
      DAYS='';
      PARENT_PART_TYPE='CRYSTAL_2013';
      PARENT_PPT='CRYSTAL';
      PARENT_PPT_PART='CRYSTAL_2013-25.000MHZ,IC,D71700-057';
  end_body;
end_primitive;
primitive 'CRYSTAL_2013-25.000MHZ,IC,H196A';
  pin
    'A':
      PIN_NUMBER='(1)';
      PINUSE='UNSPEC';
      NO_LOAD_CHECK='BOTH';
      NO_IO_CHECK='BOTH';
      ALLOW_CONNECT='TRUE';
      PIN_GROUP='1';
    'B':
      PIN_NUMBER='(3)';
      PINUSE='UNSPEC';
      NO_LOAD_CHECK='BOTH';
      NO_IO_CHECK='BOTH';
      ALLOW_CONNECT='TRUE';
      PIN_GROUP='1';
  end_pin;
  body
      POWER_PINS='(GND:2,4)';
      PART_NAME='CRYSTAL';
      PHYS_DES_PREFIX='Y';
      ENVCOMP='YES;YES;YES;UNK;ok;VLD';
      PART_NUMBER='H19611-001';
      JEDEC_TYPE='SMY1310A';
      CLASS='IC';
      DESCRIPTION='XTAL,25.000MHZ,20PF,SM,7M25020008';
      HEIGHT='0.031 IN';
      COMPONENT_TYPE='SMTOTHER';
      LEAD_LENGTH='';
      LPID='1719';
      SPEED_URL='http://speed.intel.com:8081/speed/module/pdm/item/pdm_item_deta~
il_direct.asp?item_cde=H19611-001&item_rev=01&url_param=unused';
      STATUS='Design';
      RPL='NO';
      AML='1';
      BUS_UNIT='SG';
      DAYS='???';
      PARENT_PART_TYPE='CRYSTAL_2013';
      PARENT_PPT='CRYSTAL';
      PARENT_PPT_PART='CRYSTAL_2013-25.000MHZ,IC,H19611-001';
  end_body;
end_primitive;
primitive 'CRYSTAL_2013-48.000MHZ,IC,D717A';
  pin
    'A':
      PIN_NUMBER='(1)';
      PINUSE='UNSPEC';
      NO_LOAD_CHECK='BOTH';
      NO_IO_CHECK='BOTH';
      ALLOW_CONNECT='TRUE';
      PIN_GROUP='1';
    'B':
      PIN_NUMBER='(3)';
      PINUSE='UNSPEC';
      NO_LOAD_CHECK='BOTH';
      NO_IO_CHECK='BOTH';
      ALLOW_CONNECT='TRUE';
      PIN_GROUP='1';
  end_pin;
  body
      POWER_PINS='(GND:2,4)';
      PART_NAME='CRYSTAL';
      PHYS_DES_PREFIX='Y';
      ENVCOMP='YES;YES;YES;UNK;ok;VLD';
      PART_NUMBER='D71700-058';
      JEDEC_TYPE='SMY1310A';
      CLASS='IC';
      DESCRIPTION='XTAL,CER3.2X2.5,48.00,MHZ,10.0,PF,0.003%,SM';
      HEIGHT='0.031 IN';
      COMPONENT_TYPE='SMTOTHER';
      LEAD_LENGTH='';
      LPID='1719';
      SPEED_URL='http://speed.intel.com:8081/speed/module/pdm/item/pdm_item_deta~
il_direct.asp?item_cde=D71700-058&item_rev=01&url_param=unused';
      STATUS='Design';
      RPL='YES';
      AML='2';
      BUS_UNIT='SMO_BOARDS';
      DAYS='???';
      PARENT_PART_TYPE='CRYSTAL_2013';
      PARENT_PPT='CRYSTAL';
      PARENT_PPT_PART='CRYSTAL_2013-48.000MHZ,IC,D71700-058';
  end_body;
end_primitive;
primitive 'CRYSTAL_2013LF-25.000MHZ,IC,D7B';
  pin
    'A':
      PIN_NUMBER='(1)';
      PINUSE='UNSPEC';
      NO_LOAD_CHECK='BOTH';
      NO_IO_CHECK='BOTH';
      ALLOW_CONNECT='TRUE';
      PIN_GROUP='1';
    'B':
      PIN_NUMBER='(3)';
      PINUSE='UNSPEC';
      NO_LOAD_CHECK='BOTH';
      NO_IO_CHECK='BOTH';
      ALLOW_CONNECT='TRUE';
      PIN_GROUP='1';
  end_pin;
  body
      PART_NAME='CRYSTAL';
      PHYS_DES_PREFIX='Y';
      ENVCOMP='YES;YES;YES;UNK;ok;YTC';
      PART_NUMBER='D71700-033';
      JEDEC_TYPE='SMY1310A';
      CLASS='IC';
      DESCRIPTION='XTAL,CER3.2X2.5,25,20PF,0-85DEG';
      HEIGHT='0.031 IN';
      COMPONENT_TYPE='SMTOTHER';
      LEAD_LENGTH='';
      LPID='1719';
      SPEED_URL='http://speed.intel.com:8081/speed/module/pdm/item/pdm_item_deta~
il_direct.asp?item_cde=D71700-033&item_rev=01&url_param=unused';
      STATUS='Design';
      RPL='YES';
      AML='2';
      BUS_UNIT='SMO_BOARDS';
      DAYS='???';
      POWER_PINS='(GND:2,4)';
      PARENT_PART_TYPE='CRYSTAL_2013LF';
      SCH_MODIFIED_PART='TRUE';
      PARENT_PPT='CRYSTAL';
      PARENT_PPT_PART='CRYSTAL_2013LF-25.000MHZ,IC,D71700-033';
  end_body;
end_primitive;
primitive 'CRYSTAL_SM-32.768KHZ,IC,C13544A';
  pin
    'A':
      PIN_NUMBER='(1)';
      PINUSE='UNSPEC';
      NO_LOAD_CHECK='BOTH';
      NO_IO_CHECK='BOTH';
      ALLOW_CONNECT='TRUE';
      PIN_GROUP='1';
    'B':
      PIN_NUMBER='(2)';
      PINUSE='UNSPEC';
      NO_LOAD_CHECK='BOTH';
      NO_IO_CHECK='BOTH';
      ALLOW_CONNECT='TRUE';
      PIN_GROUP='1';
  end_pin;
  body
      PART_NAME='CRYSTAL';
      PHYS_DES_PREFIX='Y';
      ENVCOMP='';
      PART_NUMBER='C13544-023';
      JEDEC_TYPE='SMY1306A';
      CLASS='IC';
      DESCRIPTION='XTAL,CER3.2X1.5,32.768,KHZ,12.5,PF,0.002%,SM';
      HEIGHT='0.035 IN';
      COMPONENT_TYPE='SMTOTHER';
      LEAD_LENGTH='';
      LPID='1776';
      SPEED_URL='http://speed.intel.com:8081/speed/module/pdm/item/pdm_item_deta~
il_direct.asp?item_cde=C13544-023&item_rev=01&url_param=unused';
      STATUS='';
      RPL='';
      AML='';
      BUS_UNIT='';
      DAYS='';
      PARENT_PART_TYPE='CRYSTAL_SM';
      PARENT_PPT='CRYSTAL';
      PARENT_PPT_PART='CRYSTAL_SM-32.768KHZ,IC,C13544-023';
  end_body;
end_primitive;
primitive 'CSD87384M_SM-IC,H66258-001';
  pin
    'BG':
      PIN_NUMBER='(4)';
      INPUT_LOAD='(-0.01,0.01)';
      PINUSE='IN';
    'PGND':
      PIN_NUMBER='(3)';
      PIN_TYPE='GROUND';
      NO_LOAD_CHECK='BOTH';
      NO_IO_CHECK='BOTH';
      ALLOW_CONNECT='TRUE';
      PINUSE='UNSPEC';
    'TG':
      PIN_NUMBER='(1)';
      INPUT_LOAD='(-0.01,0.01)';
      PINUSE='IN';
    'VIN':
      PIN_NUMBER='(2)';
      INPUT_LOAD='(-0.01,0.01)';
      PINUSE='IN';
    'VSW':
      PIN_NUMBER='(5)';
      OUTPUT_LOAD='(1.0,-1.0)';
      PINUSE='OUT';
  end_pin;
  body
      PART_NAME='CSD87384M';
      PHYS_DES_PREFIX='EU';
      ENVCOMP='';
      PART_NUMBER='H66258-001';
      JEDEC_TYPE='LCC5_14_20_1MA';
      DESCRIPTION='IC,DS,FET N,PPAK,CSD87384M';
      CLASS='IC';
      COMPONENT_TYPE='LCC';
      HEIGHT='0.018 IN';
      LPID='3811';
      SPEED_URL='http://speed.intel.com:8081/speed/module/pdm/item/pdm_item_deta~
il_direct.asp?item_cde=H66258-001&item_rev=01&url_param=unused';
      STATUS='';
      RPL='';
      AML='';
      BUS_UNIT='';
      DAYS='';
      PARENT_PART_TYPE='CSD87384M_SM';
      PARENT_PPT='CSD87384M';
      PARENT_PPT_PART='CSD87384M_SM-IC,H66258-001';
  end_body;
end_primitive;
primitive 'DIODE2A_DUAL_SMLF-BAS70-05,DIOA';
  pin
    'C':
      PIN_NUMBER='(3)';
      PINUSE='UNSPEC';
      NO_LOAD_CHECK='BOTH';
      NO_IO_CHECK='BOTH';
      ALLOW_CONNECT='TRUE';
    'A1':
      PIN_NUMBER='(1)';
      PINUSE='UNSPEC';
      NO_LOAD_CHECK='BOTH';
      NO_IO_CHECK='BOTH';
      ALLOW_CONNECT='TRUE';
    'A2':
      PIN_NUMBER='(2)';
      PINUSE='UNSPEC';
      NO_LOAD_CHECK='BOTH';
      NO_IO_CHECK='BOTH';
      ALLOW_CONNECT='TRUE';
  end_pin;
  body
      PART_NAME='DIODE2A_DUAL';
      PHYS_DES_PREFIX='CR';
      ENVCOMP='YES;YES;CNC;CNC;ok;VLD';
      PART_NUMBER='C90169-001';
      JEDEC_TYPE='SOT23A';
      CLASS='IC';
      DESCRIPTION='IC,DS,DIO,SOT-23,BAS70-05,SHTKY';
      HEIGHT='0.044 IN';
      COMPONENT_TYPE='SMALLSMT';
      LEAD_LENGTH='';
      LPID='513';
      SPEED_URL='http://speed.intel.com:8081/speed/module/pdm/item/pdm_item_deta~
il_direct.asp?item_cde=C90169-001&item_rev=01&url_param=unused';
      STATUS='Conditional';
      RPL='YES';
      AML='5';
      BUS_UNIT='SMO_IC';
      DAYS='84';
      PARENT_PART_TYPE='DIODE2A_DUAL';
      PARENT_PPT='DIODE2A_DUAL';
      PARENT_PPT_PART='DIODE2A_DUAL_SMLF-BAS70-05,DIO,C90169-001';
  end_body;
end_primitive;
primitive 'DIODEAC_DUAL_ARRAY_SM9-ESD3V3UA';
  pin
    'AC0':
      PIN_NUMBER='(1)';
      BIDIRECTIONAL='TRUE';
      INPUT_LOAD='(-0.01,0.01)';
      OUTPUT_LOAD='(1.0,-1.0)';
      PINUSE='BI';
    'AC1':
      PIN_NUMBER='(2)';
      BIDIRECTIONAL='TRUE';
      INPUT_LOAD='(-0.01,0.01)';
      OUTPUT_LOAD='(1.0,-1.0)';
      PINUSE='BI';
    'AC2':
      PIN_NUMBER='(4)';
      BIDIRECTIONAL='TRUE';
      INPUT_LOAD='(-0.01,0.01)';
      OUTPUT_LOAD='(1.0,-1.0)';
      PINUSE='BI';
    'AC3':
      PIN_NUMBER='(5)';
      BIDIRECTIONAL='TRUE';
      INPUT_LOAD='(-0.01,0.01)';
      OUTPUT_LOAD='(1.0,-1.0)';
      PINUSE='BI';
    'GND'<0>:
      PIN_NUMBER='(3)';
      PINUSE='GROUND';
      NO_LOAD_CHECK='Both';
      NO_IO_CHECK='Both';
      NO_ASSERT_CHECK='TRUE';
      NO_DIR_CHECK='TRUE';
      ALLOW_CONNECT='TRUE';
    'OUT0':
      PIN_NUMBER='(9)';
      OUTPUT_LOAD='(1.0,-1.0)';
      PINUSE='OUT';
    'OUT1':
      PIN_NUMBER='(8)';
      OUTPUT_LOAD='(1.0,-1.0)';
      PINUSE='OUT';
    'OUT2':
      PIN_NUMBER='(7)';
      OUTPUT_LOAD='(1.0,-1.0)';
      PINUSE='OUT';
    'OUT3':
      PIN_NUMBER='(6)';
      OUTPUT_LOAD='(1.0,-1.0)';
      PINUSE='OUT';
  end_pin;
  body
      PART_NAME='DIODEAC_DUAL_ARRAY';
      PHYS_DES_PREFIX='CR';
      ENVCOMP='YES;YES;YES;UNK;ok;VLD';
      PART_NUMBER='G18435-001';
      JEDEC_TYPE='LCC9_04_09_5MA';
      DESCRIPTION='(USE SYM 7) IC,DS,DIO,SOP,ESDPROTECT,TVS';
      CLASS='IC';
      HEIGHT='0.013 IN';
      COMPONENT_TYPE='LCC';
      LEAD_LENGTH='';
      LPID='2169';
      SPEED_URL='http://speed.intel.com:8081/speed/module/pdm/item/pdm_item_deta~
il_direct.asp?item_cde=G18435-001&item_rev=01&url_param=unused';
      STATUS='Conditional';
      RPL='YES';
      AML='2';
      BUS_UNIT='SMO_IC';
      DAYS='???';
      PARENT_PART_TYPE='DIODEAC_DUAL_ARRAY_SM9';
      PARENT_PPT='DIODEAC_DUAL_ARRAY';
      PARENT_PPT_PART='DIODEAC_DUAL_ARRAY_SM9-ESD3V3U4ULC,IC,G18435-001';
  end_body;
end_primitive;
primitive 'DIODE_SM-1N4148W,IC,D89194-001';
  pin
    'C':
      PIN_NUMBER='(1)';
      PINUSE='UNSPEC';
      NO_LOAD_CHECK='BOTH';
      NO_IO_CHECK='BOTH';
      ALLOW_CONNECT='TRUE';
    'A':
      PIN_NUMBER='(2)';
      PINUSE='UNSPEC';
      NO_LOAD_CHECK='BOTH';
      NO_IO_CHECK='BOTH';
      ALLOW_CONNECT='TRUE';
  end_pin;
  body
      PART_NAME='DIODE';
      PHYS_DES_PREFIX='CR';
      ENVCOMP='YES;YES;UNK;UNK;ok;VLD';
      PART_NUMBER='D89194-001';
      JEDEC_TYPE='SOD123A';
      CLASS='IC';
      DESCRIPTION='1N4148W';
      HEIGHT='0.053 IN';
      COMPONENT_TYPE='SMALLSMT';
      LEAD_LENGTH='';
      LPID='';
      SPEED_URL='http://speed.intel.com:8081/speed/module/pdm/item/pdm_item_deta~
il_direct.asp?item_cde=D89194-001&item_rev=01&url_param=unused';
      STATUS='Design';
      RPL='NO';
      AML='1';
      BUS_UNIT='SMO_IC';
      DAYS='???';
      PARENT_PART_TYPE='DIODE_SM';
      PARENT_PPT='DIODE';
      PARENT_PPT_PART='DIODE_SM-1N4148W,IC,D89194-001';
  end_body;
end_primitive;
primitive 'DIODE_SM-MBRS340T3G,EMPTY,C819A';
  pin
    'C':
      PIN_NUMBER='(1)';
      PINUSE='UNSPEC';
      NO_LOAD_CHECK='BOTH';
      NO_IO_CHECK='BOTH';
      ALLOW_CONNECT='TRUE';
    'A':
      PIN_NUMBER='(2)';
      PINUSE='UNSPEC';
      NO_LOAD_CHECK='BOTH';
      NO_IO_CHECK='BOTH';
      ALLOW_CONNECT='TRUE';
  end_pin;
  body
      PART_NAME='DIODE';
      PHYS_DES_PREFIX='CR';
      ENVCOMP='Y/E;Y/E;YES;UNK;ok;VLD';
      PART_NUMBER='C81983-002';
      JEDEC_TYPE='SCR3125A';
      CLASS='IO';
      DESCRIPTION='DIO,3.0A,40V,403-03,SHTKY';
      HEIGHT='0.101 IN';
      COMPONENT_TYPE='SMTOTHER';
      LEAD_LENGTH='';
      LPID='472';
      SPEED_URL='http://speed.intel.com:8081/speed/module/pdm/item/pdm_item_deta~
il_direct.asp?item_cde=C81983-002&item_rev=01&url_param=unused';
      STATUS='Design';
      RPL='YES';
      AML='2';
      BUS_UNIT='SMO_IC';
      DAYS='???';
      PARENT_PART_TYPE='DIODE_SM';
      PARENT_PPT='DIODE';
      PARENT_PPT_PART='DIODE_SM-MBRS340T3G,EMPTY,C81983-002';
  end_body;
end_primitive;
primitive 'DIODE_SM-SDMK0340L,EMPTY,H7179A';
  pin
    'C':
      PIN_NUMBER='(1)';
      PINUSE='UNSPEC';
      NO_LOAD_CHECK='BOTH';
      NO_IO_CHECK='BOTH';
      ALLOW_CONNECT='TRUE';
    'A':
      PIN_NUMBER='(2)';
      PINUSE='UNSPEC';
      NO_LOAD_CHECK='BOTH';
      NO_IO_CHECK='BOTH';
      ALLOW_CONNECT='TRUE';
  end_pin;
  body
      PART_NAME='DIODE';
      PHYS_DES_PREFIX='CR';
      ENVCOMP='';
      PART_NUMBER='H71799-001';
      JEDEC_TYPE='SOD323A';
      CLASS='IO';
      DESCRIPTION='IC,DS,DIO,SOD323,SDMK0340,SCHTKY';
      HEIGHT='0.047 IN';
      COMPONENT_TYPE='SMALLSMT';
      LEAD_LENGTH='';
      LPID='789';
      SPEED_URL='http://speed.intel.com:8081/speed/module/pdm/item/pdm_item_deta~
il_direct.asp?item_cde=H71799-001&item_rev=01&url_param=unused';
      STATUS='';
      RPL='';
      AML='';
      BUS_UNIT='';
      DAYS='';
      PARENT_PART_TYPE='DIODE_SM';
      PARENT_PPT='DIODE';
      PARENT_PPT_PART='DIODE_SM-SDMK0340L,EMPTY,H71799-001';
  end_body;
end_primitive;
primitive 'DIODE_SM-SDMK0340L,IC,H71799-0A';
  pin
    'C':
      PIN_NUMBER='(1)';
      PINUSE='UNSPEC';
      NO_LOAD_CHECK='BOTH';
      NO_IO_CHECK='BOTH';
      ALLOW_CONNECT='TRUE';
    'A':
      PIN_NUMBER='(2)';
      PINUSE='UNSPEC';
      NO_LOAD_CHECK='BOTH';
      NO_IO_CHECK='BOTH';
      ALLOW_CONNECT='TRUE';
  end_pin;
  body
      PART_NAME='DIODE';
      PHYS_DES_PREFIX='CR';
      ENVCOMP='';
      PART_NUMBER='H71799-001';
      JEDEC_TYPE='SOD323A';
      CLASS='IC';
      DESCRIPTION='IC,DS,DIO,SOD323,SDMK0340,SCHTKY';
      HEIGHT='0.047 IN';
      COMPONENT_TYPE='SMALLSMT';
      LEAD_LENGTH='';
      LPID='789';
      SPEED_URL='http://speed.intel.com:8081/speed/module/pdm/item/pdm_item_deta~
il_direct.asp?item_cde=H71799-001&item_rev=01&url_param=unused';
      STATUS='';
      RPL='';
      AML='';
      BUS_UNIT='';
      DAYS='';
      PARENT_PART_TYPE='DIODE_SM';
      PARENT_PPT='DIODE';
      PARENT_PPT_PART='DIODE_SM-SDMK0340L,IC,H71799-001';
  end_body;
end_primitive;
primitive 'DIODE_SMLF-1N5819HW,IC,D55839-A';
  pin
    'C':
      PIN_NUMBER='(1)';
      PINUSE='UNSPEC';
      NO_LOAD_CHECK='BOTH';
      NO_IO_CHECK='BOTH';
      ALLOW_CONNECT='TRUE';
    'A':
      PIN_NUMBER='(2)';
      PINUSE='UNSPEC';
      NO_LOAD_CHECK='BOTH';
      NO_IO_CHECK='BOTH';
      ALLOW_CONNECT='TRUE';
  end_pin;
  body
      PART_NAME='DIODE';
      PHYS_DES_PREFIX='CR';
      ENVCOMP='YES;YES;YES;UNK;ok;VLD';
      PART_NUMBER='D55839-001';
      JEDEC_TYPE='SOD123A';
      CLASS='IC';
      DESCRIPTION='1N5819HW';
      HEIGHT='0.053 IN';
      COMPONENT_TYPE='SMALLSMT';
      LEAD_LENGTH='';
      LPID='';
      SPEED_URL='http://speed.intel.com:8081/speed/module/pdm/item/pdm_item_deta~
il_direct.asp?item_cde=D55839-001&item_rev=01&url_param=unused';
      STATUS='Conditional';
      RPL='YES';
      AML='1';
      BUS_UNIT='SMO_IC';
      DAYS='48';
      PARENT_PART_TYPE='DIODE_SMLF';
      PARENT_PPT='DIODE';
      PARENT_PPT_PART='DIODE_SMLF-1N5819HW,IC,D55839-001';
  end_body;
end_primitive;
primitive 'DIODE_SMLF-BAT54WS,IC,C73510-0A';
  pin
    'C':
      PIN_NUMBER='(1)';
      PINUSE='UNSPEC';
      NO_LOAD_CHECK='BOTH';
      NO_IO_CHECK='BOTH';
      ALLOW_CONNECT='TRUE';
    'A':
      PIN_NUMBER='(2)';
      PINUSE='UNSPEC';
      NO_LOAD_CHECK='BOTH';
      NO_IO_CHECK='BOTH';
      ALLOW_CONNECT='TRUE';
  end_pin;
  body
      PART_NAME='DIODE';
      PHYS_DES_PREFIX='CR';
      ENVCOMP='YES;YES;YES;UNK;ok;VLD';
      PART_NUMBER='C73510-001';
      JEDEC_TYPE='SOD323A';
      CLASS='IC';
      DESCRIPTION='BAT54WS';
      HEIGHT='0.042 IN';
      COMPONENT_TYPE='SMALLSMT';
      LEAD_LENGTH='';
      LPID='';
      SPEED_URL='http://speed.intel.com:8081/speed/module/pdm/item/pdm_item_deta~
il_direct.asp?item_cde=C73510-001&item_rev=01&url_param=unused';
      STATUS='Conditional';
      RPL='YES';
      AML='1';
      BUS_UNIT='SMO_IC';
      DAYS='49';
      PARENT_PART_TYPE='DIODE_SMLF';
      PARENT_PPT='DIODE';
      PARENT_PPT_PART='DIODE_SMLF-BAT54WS,IC,C73510-001';
  end_body;
end_primitive;
primitive 'DM-FCI-CONN76-8R-GP-U-01_CONN-A';
  pin
    'PCIE_RX_DP0':
      PIN_NUMBER='(A1)';
      PIN_TYPE='ANALOG';
      NO_LOAD_CHECK='Both';
      NO_IO_CHECK='Both';
      NO_ASSERT_CHECK='TRUE';
      NO_DIR_CHECK='TRUE';
      ALLOW_CONNECT='TRUE';
      PINUSE='UNSPEC';
    'GND1':
      PIN_NUMBER='(A2)';
      PINUSE='POWER';
      NO_LOAD_CHECK='Both';
      NO_IO_CHECK='Both';
      NO_ASSERT_CHECK='TRUE';
      NO_DIR_CHECK='TRUE';
      ALLOW_CONNECT='TRUE';
    'PCIE_RX_DP6':
      PIN_NUMBER='(A3)';
      PIN_TYPE='ANALOG';
      NO_LOAD_CHECK='Both';
      NO_IO_CHECK='Both';
      NO_ASSERT_CHECK='TRUE';
      NO_DIR_CHECK='TRUE';
      ALLOW_CONNECT='TRUE';
      PINUSE='UNSPEC';
    'FAN_TACH3':
      PIN_NUMBER='(A4)';
      PIN_TYPE='ANALOG';
      NO_LOAD_CHECK='Both';
      NO_IO_CHECK='Both';
      NO_ASSERT_CHECK='TRUE';
      NO_DIR_CHECK='TRUE';
      ALLOW_CONNECT='TRUE';
      PINUSE='UNSPEC';
    'MNG_TX_DP':
      PIN_NUMBER='(A5)';
      PIN_TYPE='ANALOG';
      NO_LOAD_CHECK='Both';
      NO_IO_CHECK='Both';
      NO_ASSERT_CHECK='TRUE';
      NO_DIR_CHECK='TRUE';
      ALLOW_CONNECT='TRUE';
      PINUSE='UNSPEC';
    'PMBUS_ALERT#':
      PIN_NUMBER='(A6)';
      PIN_TYPE='ANALOG';
      NO_LOAD_CHECK='Both';
      NO_IO_CHECK='Both';
      NO_ASSERT_CHECK='TRUE';
      NO_DIR_CHECK='TRUE';
      ALLOW_CONNECT='TRUE';
      PINUSE='UNSPEC';
    'PCIE_TX_DP3':
      PIN_NUMBER='(A7)';
      PIN_TYPE='ANALOG';
      NO_LOAD_CHECK='Both';
      NO_IO_CHECK='Both';
      NO_ASSERT_CHECK='TRUE';
      NO_DIR_CHECK='TRUE';
      ALLOW_CONNECT='TRUE';
      PINUSE='UNSPEC';
    'GND2':
      PIN_NUMBER='(A8)';
      PINUSE='POWER';
      NO_LOAD_CHECK='Both';
      NO_IO_CHECK='Both';
      NO_ASSERT_CHECK='TRUE';
      NO_DIR_CHECK='TRUE';
      ALLOW_CONNECT='TRUE';
    'PCIE_RX_DN0':
      PIN_NUMBER='(B1)';
      PIN_TYPE='ANALOG';
      NO_LOAD_CHECK='Both';
      NO_IO_CHECK='Both';
      NO_ASSERT_CHECK='TRUE';
      NO_DIR_CHECK='TRUE';
      ALLOW_CONNECT='TRUE';
      PINUSE='UNSPEC';
    'PCIE_RX_DP3':
      PIN_NUMBER='(B2)';
      PIN_TYPE='ANALOG';
      NO_LOAD_CHECK='Both';
      NO_IO_CHECK='Both';
      NO_ASSERT_CHECK='TRUE';
      NO_DIR_CHECK='TRUE';
      ALLOW_CONNECT='TRUE';
      PINUSE='UNSPEC';
    'PCIE_RX_DN6':
      PIN_NUMBER='(B3)';
      PIN_TYPE='ANALOG';
      NO_LOAD_CHECK='Both';
      NO_IO_CHECK='Both';
      NO_ASSERT_CHECK='TRUE';
      NO_DIR_CHECK='TRUE';
      ALLOW_CONNECT='TRUE';
      PINUSE='UNSPEC';
    'FAN_TACH2':
      PIN_NUMBER='(B4)';
      PIN_TYPE='ANALOG';
      NO_LOAD_CHECK='Both';
      NO_IO_CHECK='Both';
      NO_ASSERT_CHECK='TRUE';
      NO_DIR_CHECK='TRUE';
      ALLOW_CONNECT='TRUE';
      PINUSE='UNSPEC';
    'MNG_TX_DN':
      PIN_NUMBER='(B5)';
      PIN_TYPE='ANALOG';
      NO_LOAD_CHECK='Both';
      NO_IO_CHECK='Both';
      NO_ASSERT_CHECK='TRUE';
      NO_DIR_CHECK='TRUE';
      ALLOW_CONNECT='TRUE';
      PINUSE='UNSPEC';
    'PMBUS_DATA':
      PIN_NUMBER='(B6)';
      PIN_TYPE='ANALOG';
      NO_LOAD_CHECK='Both';
      NO_IO_CHECK='Both';
      NO_ASSERT_CHECK='TRUE';
      NO_DIR_CHECK='TRUE';
      ALLOW_CONNECT='TRUE';
      PINUSE='UNSPEC';
    'PCIE_TX_DN3':
      PIN_NUMBER='(B7)';
      PIN_TYPE='ANALOG';
      NO_LOAD_CHECK='Both';
      NO_IO_CHECK='Both';
      NO_ASSERT_CHECK='TRUE';
      NO_DIR_CHECK='TRUE';
      ALLOW_CONNECT='TRUE';
      PINUSE='UNSPEC';
    'PCIE_TX_DP0':
      PIN_NUMBER='(B8)';
      PIN_TYPE='ANALOG';
      NO_LOAD_CHECK='Both';
      NO_IO_CHECK='Both';
      NO_ASSERT_CHECK='TRUE';
      NO_DIR_CHECK='TRUE';
      ALLOW_CONNECT='TRUE';
      PINUSE='UNSPEC';
    'GND3':
      PIN_NUMBER='(C1)';
      PINUSE='POWER';
      NO_LOAD_CHECK='Both';
      NO_IO_CHECK='Both';
      NO_ASSERT_CHECK='TRUE';
      NO_DIR_CHECK='TRUE';
      ALLOW_CONNECT='TRUE';
    'PCIE_RX_DN3':
      PIN_NUMBER='(C2)';
      PIN_TYPE='ANALOG';
      NO_LOAD_CHECK='Both';
      NO_IO_CHECK='Both';
      NO_ASSERT_CHECK='TRUE';
      NO_DIR_CHECK='TRUE';
      ALLOW_CONNECT='TRUE';
      PINUSE='UNSPEC';
    'GND4':
      PIN_NUMBER='(C3)';
      PINUSE='POWER';
      NO_LOAD_CHECK='Both';
      NO_IO_CHECK='Both';
      NO_ASSERT_CHECK='TRUE';
      NO_DIR_CHECK='TRUE';
      ALLOW_CONNECT='TRUE';
    'FAN_TACH1':
      PIN_NUMBER='(C4)';
      PIN_TYPE='ANALOG';
      NO_LOAD_CHECK='Both';
      NO_IO_CHECK='Both';
      NO_ASSERT_CHECK='TRUE';
      NO_DIR_CHECK='TRUE';
      ALLOW_CONNECT='TRUE';
      PINUSE='UNSPEC';
    'GND5':
      PIN_NUMBER='(C5)';
      PINUSE='POWER';
      NO_LOAD_CHECK='Both';
      NO_IO_CHECK='Both';
      NO_ASSERT_CHECK='TRUE';
      NO_DIR_CHECK='TRUE';
      ALLOW_CONNECT='TRUE';
    'PMBUS_CLK':
      PIN_NUMBER='(C6)';
      PIN_TYPE='ANALOG';
      NO_LOAD_CHECK='Both';
      NO_IO_CHECK='Both';
      NO_ASSERT_CHECK='TRUE';
      NO_DIR_CHECK='TRUE';
      ALLOW_CONNECT='TRUE';
      PINUSE='UNSPEC';
    'GND6':
      PIN_NUMBER='(C7)';
      PINUSE='POWER';
      NO_LOAD_CHECK='Both';
      NO_IO_CHECK='Both';
      NO_ASSERT_CHECK='TRUE';
      NO_DIR_CHECK='TRUE';
      ALLOW_CONNECT='TRUE';
    'PCIE_TX_DN0':
      PIN_NUMBER='(C8)';
      PIN_TYPE='ANALOG';
      NO_LOAD_CHECK='Both';
      NO_IO_CHECK='Both';
      NO_ASSERT_CHECK='TRUE';
      NO_DIR_CHECK='TRUE';
      ALLOW_CONNECT='TRUE';
      PINUSE='UNSPEC';
    'PCIE_RX_DP1':
      PIN_NUMBER='(D1)';
      PIN_TYPE='ANALOG';
      NO_LOAD_CHECK='Both';
      NO_IO_CHECK='Both';
      NO_ASSERT_CHECK='TRUE';
      NO_DIR_CHECK='TRUE';
      ALLOW_CONNECT='TRUE';
      PINUSE='UNSPEC';
    'GND7':
      PIN_NUMBER='(D2)';
      PINUSE='POWER';
      NO_LOAD_CHECK='Both';
      NO_IO_CHECK='Both';
      NO_ASSERT_CHECK='TRUE';
      NO_DIR_CHECK='TRUE';
      ALLOW_CONNECT='TRUE';
    'PCIE_RX_DP7':
      PIN_NUMBER='(D3)';
      PIN_TYPE='ANALOG';
      NO_LOAD_CHECK='Both';
      NO_IO_CHECK='Both';
      NO_ASSERT_CHECK='TRUE';
      NO_DIR_CHECK='TRUE';
      ALLOW_CONNECT='TRUE';
      PINUSE='UNSPEC';
    'FAN_TACH0':
      PIN_NUMBER='(D4)';
      PIN_TYPE='ANALOG';
      NO_LOAD_CHECK='Both';
      NO_IO_CHECK='Both';
      NO_ASSERT_CHECK='TRUE';
      NO_DIR_CHECK='TRUE';
      ALLOW_CONNECT='TRUE';
      PINUSE='UNSPEC';
    'MNG_RX_DP':
      PIN_NUMBER='(D5)';
      PIN_TYPE='ANALOG';
      NO_LOAD_CHECK='Both';
      NO_IO_CHECK='Both';
      NO_ASSERT_CHECK='TRUE';
      NO_DIR_CHECK='TRUE';
      ALLOW_CONNECT='TRUE';
      PINUSE='UNSPEC';
    'GND8':
      PIN_NUMBER='(D6)';
      PINUSE='POWER';
      NO_LOAD_CHECK='Both';
      NO_IO_CHECK='Both';
      NO_ASSERT_CHECK='TRUE';
      NO_DIR_CHECK='TRUE';
      ALLOW_CONNECT='TRUE';
    'PCIE_TX_DP4':
      PIN_NUMBER='(D7)';
      PIN_TYPE='ANALOG';
      NO_LOAD_CHECK='Both';
      NO_IO_CHECK='Both';
      NO_ASSERT_CHECK='TRUE';
      NO_DIR_CHECK='TRUE';
      ALLOW_CONNECT='TRUE';
      PINUSE='UNSPEC';
    'GND9':
      PIN_NUMBER='(D8)';
      PINUSE='POWER';
      NO_LOAD_CHECK='Both';
      NO_IO_CHECK='Both';
      NO_ASSERT_CHECK='TRUE';
      NO_DIR_CHECK='TRUE';
      ALLOW_CONNECT='TRUE';
    'PCIE_RX_DN1':
      PIN_NUMBER='(E1)';
      PIN_TYPE='ANALOG';
      NO_LOAD_CHECK='Both';
      NO_IO_CHECK='Both';
      NO_ASSERT_CHECK='TRUE';
      NO_DIR_CHECK='TRUE';
      ALLOW_CONNECT='TRUE';
      PINUSE='UNSPEC';
    'PCIE_RX_DP4':
      PIN_NUMBER='(E2)';
      PIN_TYPE='ANALOG';
      NO_LOAD_CHECK='Both';
      NO_IO_CHECK='Both';
      NO_ASSERT_CHECK='TRUE';
      NO_DIR_CHECK='TRUE';
      ALLOW_CONNECT='TRUE';
      PINUSE='UNSPEC';
    'PCIE_RX_DN7':
      PIN_NUMBER='(E3)';
      PIN_TYPE='ANALOG';
      NO_LOAD_CHECK='Both';
      NO_IO_CHECK='Both';
      NO_ASSERT_CHECK='TRUE';
      NO_DIR_CHECK='TRUE';
      ALLOW_CONNECT='TRUE';
      PINUSE='UNSPEC';
    'MATED_IN#':
      PIN_NUMBER='(E4)';
      PIN_TYPE='ANALOG';
      NO_LOAD_CHECK='Both';
      NO_IO_CHECK='Both';
      NO_ASSERT_CHECK='TRUE';
      NO_DIR_CHECK='TRUE';
      ALLOW_CONNECT='TRUE';
      PINUSE='UNSPEC';
    'MNG_RX_DN':
      PIN_NUMBER='(E5)';
      PIN_TYPE='ANALOG';
      NO_LOAD_CHECK='Both';
      NO_IO_CHECK='Both';
      NO_ASSERT_CHECK='TRUE';
      NO_DIR_CHECK='TRUE';
      ALLOW_CONNECT='TRUE';
      PINUSE='UNSPEC';
    'PCIE_TX_DP6':
      PIN_NUMBER='(E6)';
      PIN_TYPE='ANALOG';
      NO_LOAD_CHECK='Both';
      NO_IO_CHECK='Both';
      NO_ASSERT_CHECK='TRUE';
      NO_DIR_CHECK='TRUE';
      ALLOW_CONNECT='TRUE';
      PINUSE='UNSPEC';
    'PCIE_TX_DN4':
      PIN_NUMBER='(E7)';
      PIN_TYPE='ANALOG';
      NO_LOAD_CHECK='Both';
      NO_IO_CHECK='Both';
      NO_ASSERT_CHECK='TRUE';
      NO_DIR_CHECK='TRUE';
      ALLOW_CONNECT='TRUE';
      PINUSE='UNSPEC';
    'PCIE_TX_DP1':
      PIN_NUMBER='(E8)';
      PIN_TYPE='ANALOG';
      NO_LOAD_CHECK='Both';
      NO_IO_CHECK='Both';
      NO_ASSERT_CHECK='TRUE';
      NO_DIR_CHECK='TRUE';
      ALLOW_CONNECT='TRUE';
      PINUSE='UNSPEC';
    'GND10':
      PIN_NUMBER='(F1)';
      PINUSE='POWER';
      NO_LOAD_CHECK='Both';
      NO_IO_CHECK='Both';
      NO_ASSERT_CHECK='TRUE';
      NO_DIR_CHECK='TRUE';
      ALLOW_CONNECT='TRUE';
    'PCIE_RX_DN4':
      PIN_NUMBER='(F2)';
      PIN_TYPE='ANALOG';
      NO_LOAD_CHECK='Both';
      NO_IO_CHECK='Both';
      NO_ASSERT_CHECK='TRUE';
      NO_DIR_CHECK='TRUE';
      ALLOW_CONNECT='TRUE';
      PINUSE='UNSPEC';
    'GND11':
      PIN_NUMBER='(F3)';
      PINUSE='POWER';
      NO_LOAD_CHECK='Both';
      NO_IO_CHECK='Both';
      NO_ASSERT_CHECK='TRUE';
      NO_DIR_CHECK='TRUE';
      ALLOW_CONNECT='TRUE';
    'FAN_PWM0':
      PIN_NUMBER='(F4)';
      PIN_TYPE='ANALOG';
      NO_LOAD_CHECK='Both';
      NO_IO_CHECK='Both';
      NO_ASSERT_CHECK='TRUE';
      NO_DIR_CHECK='TRUE';
      ALLOW_CONNECT='TRUE';
      PINUSE='UNSPEC';
    'MB_SLOT_ID0':
      PIN_NUMBER='(F5)';
      PIN_TYPE='ANALOG';
      NO_LOAD_CHECK='Both';
      NO_IO_CHECK='Both';
      NO_ASSERT_CHECK='TRUE';
      NO_DIR_CHECK='TRUE';
      ALLOW_CONNECT='TRUE';
      PINUSE='UNSPEC';
    'PCIE_TX_DN6':
      PIN_NUMBER='(F6)';
      PIN_TYPE='ANALOG';
      NO_LOAD_CHECK='Both';
      NO_IO_CHECK='Both';
      NO_ASSERT_CHECK='TRUE';
      NO_DIR_CHECK='TRUE';
      ALLOW_CONNECT='TRUE';
      PINUSE='UNSPEC';
    'GND12':
      PIN_NUMBER='(F7)';
      PINUSE='POWER';
      NO_LOAD_CHECK='Both';
      NO_IO_CHECK='Both';
      NO_ASSERT_CHECK='TRUE';
      NO_DIR_CHECK='TRUE';
      ALLOW_CONNECT='TRUE';
    'PCIE_TX_DN1':
      PIN_NUMBER='(F8)';
      PIN_TYPE='ANALOG';
      NO_LOAD_CHECK='Both';
      NO_IO_CHECK='Both';
      NO_ASSERT_CHECK='TRUE';
      NO_DIR_CHECK='TRUE';
      ALLOW_CONNECT='TRUE';
      PINUSE='UNSPEC';
    'PCIE_RX_DP2':
      PIN_NUMBER='(G1)';
      PIN_TYPE='ANALOG';
      NO_LOAD_CHECK='Both';
      NO_IO_CHECK='Both';
      NO_ASSERT_CHECK='TRUE';
      NO_DIR_CHECK='TRUE';
      ALLOW_CONNECT='TRUE';
      PINUSE='UNSPEC';
    'GND13':
      PIN_NUMBER='(G2)';
      PINUSE='POWER';
      NO_LOAD_CHECK='Both';
      NO_IO_CHECK='Both';
      NO_ASSERT_CHECK='TRUE';
      NO_DIR_CHECK='TRUE';
      ALLOW_CONNECT='TRUE';
    'COM_TX':
      PIN_NUMBER='(G3)';
      PIN_TYPE='ANALOG';
      NO_LOAD_CHECK='Both';
      NO_IO_CHECK='Both';
      NO_ASSERT_CHECK='TRUE';
      NO_DIR_CHECK='TRUE';
      ALLOW_CONNECT='TRUE';
      PINUSE='UNSPEC';
    'GND14':
      PIN_NUMBER='(G4)';
      PINUSE='POWER';
      NO_LOAD_CHECK='Both';
      NO_IO_CHECK='Both';
      NO_ASSERT_CHECK='TRUE';
      NO_DIR_CHECK='TRUE';
      ALLOW_CONNECT='TRUE';
    'MB_SLOT_ID1':
      PIN_NUMBER='(G5)';
      PIN_TYPE='ANALOG';
      NO_LOAD_CHECK='Both';
      NO_IO_CHECK='Both';
      NO_ASSERT_CHECK='TRUE';
      NO_DIR_CHECK='TRUE';
      ALLOW_CONNECT='TRUE';
      PINUSE='UNSPEC';
    'GND15':
      PIN_NUMBER='(G6)';
      PINUSE='POWER';
      NO_LOAD_CHECK='Both';
      NO_IO_CHECK='Both';
      NO_ASSERT_CHECK='TRUE';
      NO_DIR_CHECK='TRUE';
      ALLOW_CONNECT='TRUE';
    'PCIE_TX_DP5':
      PIN_NUMBER='(G7)';
      PIN_TYPE='ANALOG';
      NO_LOAD_CHECK='Both';
      NO_IO_CHECK='Both';
      NO_ASSERT_CHECK='TRUE';
      NO_DIR_CHECK='TRUE';
      ALLOW_CONNECT='TRUE';
      PINUSE='UNSPEC';
    'GND16':
      PIN_NUMBER='(G8)';
      PINUSE='POWER';
      NO_LOAD_CHECK='Both';
      NO_IO_CHECK='Both';
      NO_ASSERT_CHECK='TRUE';
      NO_DIR_CHECK='TRUE';
      ALLOW_CONNECT='TRUE';
    'PCIE_RX_DN2':
      PIN_NUMBER='(H1)';
      PIN_TYPE='ANALOG';
      NO_LOAD_CHECK='Both';
      NO_IO_CHECK='Both';
      NO_ASSERT_CHECK='TRUE';
      NO_DIR_CHECK='TRUE';
      ALLOW_CONNECT='TRUE';
      PINUSE='UNSPEC';
    'PCIE_RX_DP5':
      PIN_NUMBER='(H2)';
      PIN_TYPE='ANALOG';
      NO_LOAD_CHECK='Both';
      NO_IO_CHECK='Both';
      NO_ASSERT_CHECK='TRUE';
      NO_DIR_CHECK='TRUE';
      ALLOW_CONNECT='TRUE';
      PINUSE='UNSPEC';
    'COM_RX':
      PIN_NUMBER='(H3)';
      PIN_TYPE='ANALOG';
      NO_LOAD_CHECK='Both';
      NO_IO_CHECK='Both';
      NO_ASSERT_CHECK='TRUE';
      NO_DIR_CHECK='TRUE';
      ALLOW_CONNECT='TRUE';
      PINUSE='UNSPEC';
    'PCIE_CLK_100M_DP':
      PIN_NUMBER='(H4)';
      PIN_TYPE='ANALOG';
      NO_LOAD_CHECK='Both';
      NO_IO_CHECK='Both';
      NO_ASSERT_CHECK='TRUE';
      NO_DIR_CHECK='TRUE';
      ALLOW_CONNECT='TRUE';
      PINUSE='UNSPEC';
    'MB_SLOT_ID2':
      PIN_NUMBER='(H5)';
      PIN_TYPE='ANALOG';
      NO_LOAD_CHECK='Both';
      NO_IO_CHECK='Both';
      NO_ASSERT_CHECK='TRUE';
      NO_DIR_CHECK='TRUE';
      ALLOW_CONNECT='TRUE';
      PINUSE='UNSPEC';
    'PCIE_TX_DP7':
      PIN_NUMBER='(H6)';
      PIN_TYPE='ANALOG';
      NO_LOAD_CHECK='Both';
      NO_IO_CHECK='Both';
      NO_ASSERT_CHECK='TRUE';
      NO_DIR_CHECK='TRUE';
      ALLOW_CONNECT='TRUE';
      PINUSE='UNSPEC';
    'PCIE_TX_DN5':
      PIN_NUMBER='(H7)';
      PIN_TYPE='ANALOG';
      NO_LOAD_CHECK='Both';
      NO_IO_CHECK='Both';
      NO_ASSERT_CHECK='TRUE';
      NO_DIR_CHECK='TRUE';
      ALLOW_CONNECT='TRUE';
      PINUSE='UNSPEC';
    'PCIE_TX_DP2':
      PIN_NUMBER='(H8)';
      PIN_TYPE='ANALOG';
      NO_LOAD_CHECK='Both';
      NO_IO_CHECK='Both';
      NO_ASSERT_CHECK='TRUE';
      NO_DIR_CHECK='TRUE';
      ALLOW_CONNECT='TRUE';
      PINUSE='UNSPEC';
    'GND17':
      PIN_NUMBER='(I1)';
      PINUSE='POWER';
      NO_LOAD_CHECK='Both';
      NO_IO_CHECK='Both';
      NO_ASSERT_CHECK='TRUE';
      NO_DIR_CHECK='TRUE';
      ALLOW_CONNECT='TRUE';
    'PCIE_RX_DN5':
      PIN_NUMBER='(I2)';
      PIN_TYPE='ANALOG';
      NO_LOAD_CHECK='Both';
      NO_IO_CHECK='Both';
      NO_ASSERT_CHECK='TRUE';
      NO_DIR_CHECK='TRUE';
      ALLOW_CONNECT='TRUE';
      PINUSE='UNSPEC';
    'MB_ON#':
      PIN_NUMBER='(I3)';
      PIN_TYPE='ANALOG';
      NO_LOAD_CHECK='Both';
      NO_IO_CHECK='Both';
      NO_ASSERT_CHECK='TRUE';
      NO_DIR_CHECK='TRUE';
      ALLOW_CONNECT='TRUE';
      PINUSE='UNSPEC';
    'PCIE_CLK_100M_DN':
      PIN_NUMBER='(I4)';
      PIN_TYPE='ANALOG';
      NO_LOAD_CHECK='Both';
      NO_IO_CHECK='Both';
      NO_ASSERT_CHECK='TRUE';
      NO_DIR_CHECK='TRUE';
      ALLOW_CONNECT='TRUE';
      PINUSE='UNSPEC';
    'PCIE_PERST#':
      PIN_NUMBER='(I5)';
      PIN_TYPE='ANALOG';
      NO_LOAD_CHECK='Both';
      NO_IO_CHECK='Both';
      NO_ASSERT_CHECK='TRUE';
      NO_DIR_CHECK='TRUE';
      ALLOW_CONNECT='TRUE';
      PINUSE='UNSPEC';
    'PCIE_TX_DN7':
      PIN_NUMBER='(I6)';
      PIN_TYPE='ANALOG';
      NO_LOAD_CHECK='Both';
      NO_IO_CHECK='Both';
      NO_ASSERT_CHECK='TRUE';
      NO_DIR_CHECK='TRUE';
      ALLOW_CONNECT='TRUE';
      PINUSE='UNSPEC';
    'GND18':
      PIN_NUMBER='(I7)';
      PINUSE='POWER';
      NO_LOAD_CHECK='Both';
      NO_IO_CHECK='Both';
      NO_ASSERT_CHECK='TRUE';
      NO_DIR_CHECK='TRUE';
      ALLOW_CONNECT='TRUE';
    'PCIE_TX_DN2':
      PIN_NUMBER='(I8)';
      PIN_TYPE='ANALOG';
      NO_LOAD_CHECK='Both';
      NO_IO_CHECK='Both';
      NO_ASSERT_CHECK='TRUE';
      NO_DIR_CHECK='TRUE';
      ALLOW_CONNECT='TRUE';
      PINUSE='UNSPEC';
    'J2':
      PIN_NUMBER='(J2)';
      PIN_TYPE='ANALOG';
      NO_LOAD_CHECK='Both';
      NO_IO_CHECK='Both';
      NO_ASSERT_CHECK='TRUE';
      NO_DIR_CHECK='TRUE';
      ALLOW_CONNECT='TRUE';
      PINUSE='UNSPEC';
    'J4':
      PIN_NUMBER='(J4)';
      PIN_TYPE='ANALOG';
      NO_LOAD_CHECK='Both';
      NO_IO_CHECK='Both';
      NO_ASSERT_CHECK='TRUE';
      NO_DIR_CHECK='TRUE';
      ALLOW_CONNECT='TRUE';
      PINUSE='UNSPEC';
    'J6':
      PIN_NUMBER='(J6)';
      PIN_TYPE='ANALOG';
      NO_LOAD_CHECK='Both';
      NO_IO_CHECK='Both';
      NO_ASSERT_CHECK='TRUE';
      NO_DIR_CHECK='TRUE';
      ALLOW_CONNECT='TRUE';
      PINUSE='UNSPEC';
    'J8':
      PIN_NUMBER='(J8)';
      PIN_TYPE='ANALOG';
      NO_LOAD_CHECK='Both';
      NO_IO_CHECK='Both';
      NO_ASSERT_CHECK='TRUE';
      NO_DIR_CHECK='TRUE';
      ALLOW_CONNECT='TRUE';
      PINUSE='UNSPEC';
  end_pin;
  body
      PART_NAME='DM-FCI-CONN76-8R-GP-U-01';
      BODY_NAME='DM-FCI-CONN76-8R-GP-U-01';
      PHYS_DES_PREFIX='CN';
      CLASS='DISCRETE';
      DESCRIPTION='CONN CTR 48S+28G 10124755-111LF PRESSFIT';
      JEDEC_TYPE='DM-FIT76P179295UH459-01';
      PARENT_PART_TYPE='DM-FCI-CONN76-8R-GP-U-01';
      PARENT_PPT='DM-FCI-CONN76-8R-GP-U-01';
      PARENT_PPT_PART='DM-FCI-CONN76-8R-GP-U-01_CONN-G4-DM-FCI-CONN76-8R-GP-U-01,ZZ.82092.07601';
  end_body;
end_primitive;
primitive 'FCI-CONN12-2R-GP_CONN-G5-FCI-CA';
  pin
    '2_1':
      PIN_NUMBER='(2_1)';
      PIN_TYPE='ANALOG';
      NO_LOAD_CHECK='Both';
      NO_IO_CHECK='Both';
      NO_ASSERT_CHECK='TRUE';
      NO_DIR_CHECK='TRUE';
      ALLOW_CONNECT='TRUE';
      PINUSE='UNSPEC';
    '2_2':
      PIN_NUMBER='(2_2)';
      PIN_TYPE='ANALOG';
      NO_LOAD_CHECK='Both';
      NO_IO_CHECK='Both';
      NO_ASSERT_CHECK='TRUE';
      NO_DIR_CHECK='TRUE';
      ALLOW_CONNECT='TRUE';
      PINUSE='UNSPEC';
    '2_3':
      PIN_NUMBER='(2_3)';
      PIN_TYPE='ANALOG';
      NO_LOAD_CHECK='Both';
      NO_IO_CHECK='Both';
      NO_ASSERT_CHECK='TRUE';
      NO_DIR_CHECK='TRUE';
      ALLOW_CONNECT='TRUE';
      PINUSE='UNSPEC';
    '3_1':
      PIN_NUMBER='(3_1)';
      PIN_TYPE='ANALOG';
      NO_LOAD_CHECK='Both';
      NO_IO_CHECK='Both';
      NO_ASSERT_CHECK='TRUE';
      NO_DIR_CHECK='TRUE';
      ALLOW_CONNECT='TRUE';
      PINUSE='UNSPEC';
    '3_2':
      PIN_NUMBER='(3_2)';
      PIN_TYPE='ANALOG';
      NO_LOAD_CHECK='Both';
      NO_IO_CHECK='Both';
      NO_ASSERT_CHECK='TRUE';
      NO_DIR_CHECK='TRUE';
      ALLOW_CONNECT='TRUE';
      PINUSE='UNSPEC';
    '3_3':
      PIN_NUMBER='(3_3)';
      PIN_TYPE='ANALOG';
      NO_LOAD_CHECK='Both';
      NO_IO_CHECK='Both';
      NO_ASSERT_CHECK='TRUE';
      NO_DIR_CHECK='TRUE';
      ALLOW_CONNECT='TRUE';
      PINUSE='UNSPEC';
    'NP1':
      PIN_NUMBER='(NP1)';
      PIN_TYPE='ANALOG';
      NO_LOAD_CHECK='Both';
      NO_IO_CHECK='Both';
      NO_ASSERT_CHECK='TRUE';
      NO_DIR_CHECK='TRUE';
      ALLOW_CONNECT='TRUE';
      PINUSE='UNSPEC';
    '1_1':
      PIN_NUMBER='(1_1)';
      PIN_TYPE='ANALOG';
      NO_LOAD_CHECK='Both';
      NO_IO_CHECK='Both';
      NO_ASSERT_CHECK='TRUE';
      NO_DIR_CHECK='TRUE';
      ALLOW_CONNECT='TRUE';
      PINUSE='UNSPEC';
    '1_2':
      PIN_NUMBER='(1_2)';
      PIN_TYPE='ANALOG';
      NO_LOAD_CHECK='Both';
      NO_IO_CHECK='Both';
      NO_ASSERT_CHECK='TRUE';
      NO_DIR_CHECK='TRUE';
      ALLOW_CONNECT='TRUE';
      PINUSE='UNSPEC';
    '1_3':
      PIN_NUMBER='(1_3)';
      PIN_TYPE='ANALOG';
      NO_LOAD_CHECK='Both';
      NO_IO_CHECK='Both';
      NO_ASSERT_CHECK='TRUE';
      NO_DIR_CHECK='TRUE';
      ALLOW_CONNECT='TRUE';
      PINUSE='UNSPEC';
    '4_1':
      PIN_NUMBER='(4_1)';
      PIN_TYPE='ANALOG';
      NO_LOAD_CHECK='Both';
      NO_IO_CHECK='Both';
      NO_ASSERT_CHECK='TRUE';
      NO_DIR_CHECK='TRUE';
      ALLOW_CONNECT='TRUE';
      PINUSE='UNSPEC';
    '4_2':
      PIN_NUMBER='(4_2)';
      PIN_TYPE='ANALOG';
      NO_LOAD_CHECK='Both';
      NO_IO_CHECK='Both';
      NO_ASSERT_CHECK='TRUE';
      NO_DIR_CHECK='TRUE';
      ALLOW_CONNECT='TRUE';
      PINUSE='UNSPEC';
    '4_3':
      PIN_NUMBER='(4_3)';
      PIN_TYPE='ANALOG';
      NO_LOAD_CHECK='Both';
      NO_IO_CHECK='Both';
      NO_ASSERT_CHECK='TRUE';
      NO_DIR_CHECK='TRUE';
      ALLOW_CONNECT='TRUE';
      PINUSE='UNSPEC';
  end_pin;
  body
      PART_NAME='FCI-CONN12-2R-GP';
      BODY_NAME='FCI-CONN12-2R-GP';
      PHYS_DES_PREFIX='CN';
      CLASS='DISCRETE';
      DESCRIPTION='CONN CTR 12P 10124648-001LF PRESSFIT';
      JEDEC_TYPE='PREFIT-12P-119310-UH463';
      PARENT_PART_TYPE='FCI-CONN12-2R-GP';
      PARENT_PPT='FCI-CONN12-2R-GP';
      PARENT_PPT_PART='FCI-CONN12-2R-GP_CONN-G5-FCI-CONN12-2R-GP,20.82093.012';
  end_body;
end_primitive;
primitive 'FERRITE_SM-120,FB,693286-027';
  pin
    'A':
      PIN_NUMBER='(1)';
      PINUSE='UNSPEC';
      NO_LOAD_CHECK='BOTH';
      NO_IO_CHECK='BOTH';
      ALLOW_CONNECT='TRUE';
      PIN_GROUP='0';
    'B':
      PIN_NUMBER='(2)';
      PINUSE='UNSPEC';
      NO_LOAD_CHECK='BOTH';
      NO_IO_CHECK='BOTH';
      ALLOW_CONNECT='TRUE';
      PIN_GROUP='0';
  end_pin;
  body
      PART_NAME='FERRITE';
      PHYS_DES_PREFIX='FB';
      ENVCOMP='YES;YES;YES;UNK;ok;VLD';
      PART_NUMBER='693286-027';
      JEDEC_TYPE='SFB0603B';
      ALT_SYMBOLS='(SMX0603)';
      VALUE='120';
      CLASS='DISCRETE';
      DESCRIPTION='FER-BEAD,0603,120.0 OHM,2.0 A,+/- 25%';
      COMPONENT_TYPE='CHIP0603';
      HEIGHT='0.037 IN';
      LEAD_LENGTH='';
      LPID='2418';
      SPEED_URL='http://speed.intel.com:8081/speed/module/pdm/item/pdm_item_deta~
il_direct.asp?item_cde=693286-027&item_rev=01&url_param=unused';
      STATUS='Conditional';
      RPL='YES';
      AML='4';
      BUS_UNIT='SMO_BOARDS';
      DAYS='56';
      PARENT_PART_TYPE='FERRITE_SM';
      PARENT_PPT='FERRITE';
      PARENT_PPT_PART='FERRITE_SM-120,FB,693286-027';
  end_body;
end_primitive;
primitive 'FERRITE_SM-22,FB,656554-051';
  pin
    'A':
      PIN_NUMBER='(1)';
      PINUSE='UNSPEC';
      NO_LOAD_CHECK='BOTH';
      NO_IO_CHECK='BOTH';
      ALLOW_CONNECT='TRUE';
      PIN_GROUP='0';
    'B':
      PIN_NUMBER='(2)';
      PINUSE='UNSPEC';
      NO_LOAD_CHECK='BOTH';
      NO_IO_CHECK='BOTH';
      ALLOW_CONNECT='TRUE';
      PIN_GROUP='0';
  end_pin;
  body
      PART_NAME='FERRITE';
      PHYS_DES_PREFIX='FB';
      ENVCOMP='YES;YES;YES;UNK;ok;VLD';
      PART_NUMBER='656554-051';
      JEDEC_TYPE='SFB0805A';
      ALT_SYMBOLS='(SMX0805)';
      VALUE='22';
      CLASS='DISCRETE';
      DESCRIPTION='FER-BEAD,0805,22.0OHM,6.0A,+/-25%';
      COMPONENT_TYPE='CHIP0805';
      HEIGHT='0.041 IN';
      LEAD_LENGTH='';
      LPID='458';
      SPEED_URL='http://speed.intel.com:8081/speed/module/pdm/item/pdm_item_deta~
il_direct.asp?item_cde=656554-051&item_rev=01&url_param=unused';
      STATUS='Design';
      RPL='YES';
      AML='1';
      BUS_UNIT='SMO_BOARDS';
      DAYS='???';
      PARENT_PART_TYPE='FERRITE_SM';
      PARENT_PPT='FERRITE';
      PARENT_PPT_PART='FERRITE_SM-22,FB,656554-051';
  end_body;
end_primitive;
primitive 'FERRITE_SMLF-30,FB,693286-021';
  pin
    'A':
      PIN_NUMBER='(1)';
      PINUSE='UNSPEC';
      NO_LOAD_CHECK='BOTH';
      NO_IO_CHECK='BOTH';
      ALLOW_CONNECT='TRUE';
      PIN_GROUP='0';
    'B':
      PIN_NUMBER='(2)';
      PINUSE='UNSPEC';
      NO_LOAD_CHECK='BOTH';
      NO_IO_CHECK='BOTH';
      ALLOW_CONNECT='TRUE';
      PIN_GROUP='0';
  end_pin;
  body
      PART_NAME='FERRITE';
      PHYS_DES_PREFIX='FB';
      ENVCOMP='YES;YES;YES;UNK;ok;VLD';
      PART_NUMBER='693286-021';
      JEDEC_TYPE='SFB0603A';
      ALT_SYMBOLS='(SMX0603)';
      VALUE='30';
      CLASS='DISCRETE';
      DESCRIPTION='FERRITE 30OHM 1A';
      COMPONENT_TYPE='CHIP';
      HEIGHT='0.037 IN';
      LEAD_LENGTH='';
      LPID='';
      SPEED_URL='http://speed.intel.com:8081/speed/module/pdm/item/pdm_item_deta~
il_direct.asp?item_cde=693286-021&item_rev=01&url_param=unused';
      STATUS='Approved';
      RPL='YES';
      AML='6';
      BUS_UNIT='SMO_BOARDS';
      DAYS='56';
      PARENT_PART_TYPE='FERRITE';
      PARENT_PPT='FERRITE';
      PARENT_PPT_PART='FERRITE_SMLF-30,FB,693286-021';
  end_body;
end_primitive;
primitive 'FERRITE_SMLF-600,FB,656554-043';
  pin
    'A':
      PIN_NUMBER='(1)';
      PINUSE='UNSPEC';
      NO_LOAD_CHECK='BOTH';
      NO_IO_CHECK='BOTH';
      ALLOW_CONNECT='TRUE';
      PIN_GROUP='0';
    'B':
      PIN_NUMBER='(2)';
      PINUSE='UNSPEC';
      NO_LOAD_CHECK='BOTH';
      NO_IO_CHECK='BOTH';
      ALLOW_CONNECT='TRUE';
      PIN_GROUP='0';
  end_pin;
  body
      PART_NAME='FERRITE';
      PHYS_DES_PREFIX='FB';
      ENVCOMP='YES;YES;YES;UNK;ok;VLD';
      PART_NUMBER='656554-043';
      JEDEC_TYPE='SFB0805A';
      ALT_SYMBOLS='(SMX0805)';
      VALUE='600';
      CLASS='DISCRETE';
      DESCRIPTION='FERRITE 600OHM';
      COMPONENT_TYPE='CHIP';
      HEIGHT='0.040 IN';
      LEAD_LENGTH='';
      LPID='';
      SPEED_URL='http://speed.intel.com:8081/speed/module/pdm/item/pdm_item_deta~
il_direct.asp?item_cde=656554-043&item_rev=01&url_param=unused';
      STATUS='Conditional';
      RPL='YES';
      AML='3';
      BUS_UNIT='SMO_BOARDS';
      DAYS='56';
      PARENT_PART_TYPE='FERRITE';
      PARENT_PPT='FERRITE';
      PARENT_PPT_PART='FERRITE_SMLF-600,FB,656554-043';
  end_body;
end_primitive;
primitive 'FET_N_DUAL_SMLF-2N7002DW,FET,DA';
  pin
    'GATE'<0>:
      PIN_NUMBER='(2,5)';
      PINUSE='UNSPEC';
      NO_LOAD_CHECK='BOTH';
      NO_IO_CHECK='BOTH';
      ALLOW_CONNECT='TRUE';
    'SOURCE'<0>:
      PIN_NUMBER='(1,4)';
      PINUSE='UNSPEC';
      NO_LOAD_CHECK='BOTH';
      NO_IO_CHECK='BOTH';
      ALLOW_CONNECT='TRUE';
    'DRAIN'<0>:
      PIN_NUMBER='(6,3)';
      PINUSE='UNSPEC';
      NO_LOAD_CHECK='BOTH';
      NO_IO_CHECK='BOTH';
      ALLOW_CONNECT='TRUE';
  end_pin;
  body
      CLASS='IC';
      PART_NAME='FET_N_DUAL';
      PHYS_DES_PREFIX='Q';
      ENVCOMP='YES;YES;YES;UNK;ok;VLD';
      PART_NUMBER='D24280-001';
      JEDEC_TYPE='SSOP6_53_65MA';
      DESCRIPTION='DUAL N CHANNEL FET';
      HEIGHT='.044 IN';
      COMPONENT_TYPE='SMALLSMT';
      LEAD_LENGTH='';
      LPID='374';
      SPEED_URL='http://speed.intel.com:8081/speed/module/pdm/item/pdm_item_deta~
il_direct.asp?item_cde=D24280-001&item_rev=01&url_param=unused';
      STATUS='Approved';
      RPL='YES';
      AML='5';
      BUS_UNIT='SMO_IC';
      DAYS='84';
      PARENT_PART_TYPE='FET_N_DUAL_SMLF';
      PARENT_PPT='FET_N_DUAL';
      PARENT_PPT_PART='FET_N_DUAL_SMLF-2N7002DW,FET,D24280-001';
  end_body;
end_primitive;
primitive 'FET_N_DUAL_SMLF-NTJD4001N,FET,A';
  pin
    'GATE'<0>:
      PIN_NUMBER='(2,5)';
      PINUSE='UNSPEC';
      NO_LOAD_CHECK='BOTH';
      NO_IO_CHECK='BOTH';
      ALLOW_CONNECT='TRUE';
    'SOURCE'<0>:
      PIN_NUMBER='(1,4)';
      PINUSE='UNSPEC';
      NO_LOAD_CHECK='BOTH';
      NO_IO_CHECK='BOTH';
      ALLOW_CONNECT='TRUE';
    'DRAIN'<0>:
      PIN_NUMBER='(6,3)';
      PINUSE='UNSPEC';
      NO_LOAD_CHECK='BOTH';
      NO_IO_CHECK='BOTH';
      ALLOW_CONNECT='TRUE';
  end_pin;
  body
      CLASS='IC';
      PART_NAME='FET_N_DUAL';
      PHYS_DES_PREFIX='Q';
      ENVCOMP='YES;YES;YES;UNK;ok;VLD';
      PART_NUMBER='E40049-001';
      JEDEC_TYPE='SOT363A';
      DESCRIPTION='DUAL N CHANNEL FET';
      HEIGHT='0.043 IN';
      COMPONENT_TYPE='SMALLSMT';
      LEAD_LENGTH='';
      LPID='723';
      SPEED_URL='http://speed.intel.com:8081/speed/module/pdm/item/pdm_item_deta~
il_direct.asp?item_cde=E40049-001&item_rev=01&url_param=unused';
      STATUS='Conditional';
      RPL='YES';
      AML='2';
      BUS_UNIT='SMO_IC';
      DAYS='84';
      PARENT_PART_TYPE='FET_N_DUAL_SMLF';
      PARENT_PPT='FET_N_DUAL';
      PARENT_PPT_PART='FET_N_DUAL_SMLF-NTJD4001N,FET,E40049-001';
  end_body;
end_primitive;
primitive 'FET_N_SOT23LF-2N7002,FET,C7925A';
  pin
    'GATE':
      PIN_NUMBER='(1)';
      PINUSE='UNSPEC';
      NO_LOAD_CHECK='BOTH';
      NO_IO_CHECK='BOTH';
      ALLOW_CONNECT='TRUE';
    'SRC':
      PIN_NUMBER='(2)';
      PINUSE='UNSPEC';
      NO_LOAD_CHECK='BOTH';
      NO_IO_CHECK='BOTH';
      ALLOW_CONNECT='TRUE';
    'DRN':
      PIN_NUMBER='(3)';
      PINUSE='UNSPEC';
      NO_LOAD_CHECK='BOTH';
      NO_IO_CHECK='BOTH';
      ALLOW_CONNECT='TRUE';
  end_pin;
  body
      PART_NAME='FET_N';
      PHYS_DES_PREFIX='Q';
      ENVCOMP='YES;YES;YES;UNK;ok;VLD';
      PART_NUMBER='C79254-001';
      JEDEC_TYPE='SOT23B';
      ALT_SYMBOLS='()';
      CLASS='IC';
      DESCRIPTION='2N7002 N-CHANNEL MOSFET';
      HEIGHT='.044 IN';
      COMPONENT_TYPE='SMALLSMT';
      LEAD_LENGTH='';
      LPID='';
      SPEED_URL='http://speed.intel.com:8081/speed/module/pdm/item/pdm_item_deta~
il_direct.asp?item_cde=C79254-001&item_rev=01&url_param=unused';
      STATUS='Approved';
      RPL='YES';
      AML='12';
      BUS_UNIT='SMO_IC';
      DAYS='112';
      PARENT_PART_TYPE='FET_N';
      PARENT_PPT='FET_N';
      PARENT_PPT_PART='FET_N_SOT23LF-2N7002,FET,C79254-001';
  end_body;
end_primitive;
primitive 'FSA3357_SM-IC,C63273-001';
  pin
    'A':
      PIN_NUMBER='(7)';
      BIDIRECTIONAL='TRUE';
      INPUT_LOAD='(-0.01,0.01)';
      OUTPUT_LOAD='(1.0,-1.0)';
      PINUSE='BI';
    'B0':
      PIN_NUMBER='(1)';
      BIDIRECTIONAL='TRUE';
      INPUT_LOAD='(-0.01,0.01)';
      OUTPUT_LOAD='(1.0,-1.0)';
      PINUSE='BI';
    'B1':
      PIN_NUMBER='(2)';
      BIDIRECTIONAL='TRUE';
      INPUT_LOAD='(-0.01,0.01)';
      OUTPUT_LOAD='(1.0,-1.0)';
      PINUSE='BI';
    'B2':
      PIN_NUMBER='(3)';
      BIDIRECTIONAL='TRUE';
      INPUT_LOAD='(-0.01,0.01)';
      OUTPUT_LOAD='(1.0,-1.0)';
      PINUSE='BI';
    'GND':
      PIN_NUMBER='(4)';
      PINUSE='GROUND';
      NO_LOAD_CHECK='Both';
      NO_IO_CHECK='Both';
      NO_ASSERT_CHECK='TRUE';
      NO_DIR_CHECK='TRUE';
      ALLOW_CONNECT='TRUE';
    'S1':
      PIN_NUMBER='(6)';
      INPUT_LOAD='(-0.01,0.01)';
      PINUSE='IN';
    'S2':
      PIN_NUMBER='(5)';
      INPUT_LOAD='(-0.01,0.01)';
      PINUSE='IN';
    'VCC':
      PIN_NUMBER='(8)';
      PINUSE='POWER';
      NO_LOAD_CHECK='Both';
      NO_IO_CHECK='Both';
      NO_ASSERT_CHECK='TRUE';
      NO_DIR_CHECK='TRUE';
      ALLOW_CONNECT='TRUE';
  end_pin;
  body
      PART_NAME='FSA3357';
      PHYS_DES_PREFIX='U';
      ENVCOMP='YES;YES;CNC;CNC;ok;VLD';
      PART_NUMBER='C63273-001';
      JEDEC_TYPE='SOI8_9_05MA';
      CLASS='IC';
      DESCRIPTION='IC,LIN,ANALOG SWITCH,SO-8,FSA3357K';
      HEIGHT='0.035 IN';
      COMPONENT_TYPE='SUB50';
      LPID='733';
      SPEED_URL='http://speed.intel.com:8081/speed/module/pdm/item/pdm_item_deta~
il_direct.asp?item_cde=C63273-001&item_rev=01&url_param=unused';
      STATUS='Design';
      RPL='NO';
      AML='1';
      BUS_UNIT='SMO_IC';
      DAYS='???';
      PARENT_PART_TYPE='FSA3357_SM';
      PARENT_PPT='FSA3357';
      PARENT_PPT_PART='FSA3357_SM-IC,C63273-001';
  end_body;
end_primitive;
primitive 'FUSE-3A75V-GP_DISCRET-G5-FUSE-A';
  pin
    '1':
      PIN_NUMBER='(1)';
      PIN_TYPE='ANALOG';
      NO_LOAD_CHECK='Both';
      NO_IO_CHECK='Both';
      NO_ASSERT_CHECK='TRUE';
      NO_DIR_CHECK='TRUE';
      ALLOW_CONNECT='TRUE';
      PINUSE='UNSPEC';
    '2':
      PIN_NUMBER='(2)';
      PIN_TYPE='ANALOG';
      NO_LOAD_CHECK='Both';
      NO_IO_CHECK='Both';
      NO_ASSERT_CHECK='TRUE';
      NO_DIR_CHECK='TRUE';
      ALLOW_CONNECT='TRUE';
      PINUSE='UNSPEC';
  end_pin;
  body
      PART_NAME='FUSE-3A75V-GP';
      BODY_NAME='FUSE-3A75V-GP';
      PHYS_DES_PREFIX='F';
      CLASS='DISCRETE';
      DESCRIPTION='CHIP FUSE 3A 75V 0458003.DR';
      JEDEC_TYPE='FUSE-3216-2H68';
      PARENT_PART_TYPE='FUSE-3A75V-GP';
      PARENT_PPT='FUSE-3A75V-GP';
      PARENT_PPT_PART='FUSE-3A75V-GP_DISCRET-G5-FUSE-3A75V-GP,69.43001.511';
  end_body;
end_primitive;
primitive 'FUSE_SM-IC,C94311-016';
  pin
    'A'<0>:
      PIN_NUMBER='(1)';
      PINUSE='UNSPEC';
      NO_LOAD_CHECK='BOTH';
      NO_IO_CHECK='BOTH';
      ALLOW_CONNECT='TRUE';
      PIN_GROUP='1';
    'B'<0>:
      PIN_NUMBER='(2)';
      PINUSE='UNSPEC';
      NO_LOAD_CHECK='BOTH';
      NO_IO_CHECK='BOTH';
      ALLOW_CONNECT='TRUE';
      PIN_GROUP='1';
  end_pin;
  body
      PART_NAME='FUSE';
      PHYS_DES_PREFIX='F';
      ENVCOMP='YES;YES;UNK;UNK;ok;CIP';
      PART_NUMBER='C94311-016';
      JEDEC_TYPE='SFU1812A';
      CLASS='IC';
      DESCRIPTION='POLYSWITCH,SMT,1812,2.600A,16V';
      HEIGHT='0.060 IN';
      COMPONENT_TYPE='CHIP';
      LEAD_LENGTH='';
      LPID='1144';
      SPEED_URL='http://speed.intel.com:8081/speed/module/pdm/item/pdm_item_deta~
il_direct.asp?item_cde=C94311-016&item_rev=01&url_param=unused';
      STATUS='Conditional';
      RPL='NO';
      AML='1';
      BUS_UNIT='SMO_BOARDS';
      DAYS='???';
      PARENT_PART_TYPE='FUSE_SM';
      PARENT_PPT='FUSE';
      PARENT_PPT_PART='FUSE_SM-IC,C94311-016';
  end_body;
end_primitive;
primitive 'FUSE_SMT-IC,H45581-001';
  pin
    'A'<0>:
      PIN_NUMBER='(1)';
      PINUSE='UNSPEC';
      NO_LOAD_CHECK='BOTH';
      NO_IO_CHECK='BOTH';
      ALLOW_CONNECT='TRUE';
      PIN_GROUP='1';
    'B'<0>:
      PIN_NUMBER='(2)';
      PINUSE='UNSPEC';
      NO_LOAD_CHECK='BOTH';
      NO_IO_CHECK='BOTH';
      ALLOW_CONNECT='TRUE';
      PIN_GROUP='1';
  end_pin;
  body
      PART_NAME='FUSE';
      PHYS_DES_PREFIX='F';
      ENVCOMP='';
      PART_NUMBER='H45581-001';
      JEDEC_TYPE='SFU0603B';
      CLASS='IC';
      DESCRIPTION='POLYSWITCH,SMT,0603,0.35A,6V';
      HEIGHT='0.061 IN';
      COMPONENT_TYPE='CHIP0603';
      LEAD_LENGTH='';
      LPID='3802';
      SPEED_URL='http://speed.intel.com:8081/speed/module/pdm/item/pdm_item_deta~
il_direct.asp?item_cde=H45581-001&item_rev=01&url_param=unused';
      STATUS='';
      RPL='';
      AML='';
      BUS_UNIT='';
      DAYS='';
      PARENT_PART_TYPE='FUSE_SMT';
      PARENT_PPT='FUSE';
      PARENT_PPT_PART='FUSE_SMT-IC,H45581-001';
  end_body;
end_primitive;
primitive 'GTL2014_SM-IC,D66151-001';
  pin
    'A0':
      PIN_NUMBER='(13)';
      BIDIRECTIONAL='TRUE';
      INPUT_LOAD='(-0.01,0.01)';
      OUTPUT_LOAD='(1.0,-1.0)';
      PINUSE='BI';
    'A1':
      PIN_NUMBER='(12)';
      BIDIRECTIONAL='TRUE';
      INPUT_LOAD='(-0.01,0.01)';
      OUTPUT_LOAD='(1.0,-1.0)';
      PINUSE='BI';
    'A2':
      PIN_NUMBER='(10)';
      BIDIRECTIONAL='TRUE';
      INPUT_LOAD='(-0.01,0.01)';
      OUTPUT_LOAD='(1.0,-1.0)';
      PINUSE='BI';
    'A3':
      PIN_NUMBER='(9)';
      BIDIRECTIONAL='TRUE';
      INPUT_LOAD='(-0.01,0.01)';
      OUTPUT_LOAD='(1.0,-1.0)';
      PINUSE='BI';
    'B0':
      PIN_NUMBER='(2)';
      BIDIRECTIONAL='TRUE';
      INPUT_LOAD='(-0.01,0.01)';
      OUTPUT_LOAD='(1.0,-1.0)';
      PINUSE='BI';
    'B1':
      PIN_NUMBER='(3)';
      BIDIRECTIONAL='TRUE';
      INPUT_LOAD='(-0.01,0.01)';
      OUTPUT_LOAD='(1.0,-1.0)';
      PINUSE='BI';
    'B2':
      PIN_NUMBER='(5)';
      BIDIRECTIONAL='TRUE';
      INPUT_LOAD='(-0.01,0.01)';
      OUTPUT_LOAD='(1.0,-1.0)';
      PINUSE='BI';
    'B3':
      PIN_NUMBER='(6)';
      BIDIRECTIONAL='TRUE';
      INPUT_LOAD='(-0.01,0.01)';
      OUTPUT_LOAD='(1.0,-1.0)';
      PINUSE='BI';
    'DIR':
      PIN_NUMBER='(1)';
      INPUT_LOAD='(-0.01,0.01)';
      PINUSE='IN';
    'GND'<2>:
      PIN_NUMBER='(11)';
      PINUSE='GROUND';
      NO_LOAD_CHECK='Both';
      NO_IO_CHECK='Both';
      NO_ASSERT_CHECK='TRUE';
      NO_DIR_CHECK='TRUE';
      ALLOW_CONNECT='TRUE';
    'GND'<1>:
      PIN_NUMBER='(8)';
      PINUSE='GROUND';
      NO_LOAD_CHECK='Both';
      NO_IO_CHECK='Both';
      NO_ASSERT_CHECK='TRUE';
      NO_DIR_CHECK='TRUE';
      ALLOW_CONNECT='TRUE';
    'GND'<0>:
      PIN_NUMBER='(7)';
      PINUSE='GROUND';
      NO_LOAD_CHECK='Both';
      NO_IO_CHECK='Both';
      NO_ASSERT_CHECK='TRUE';
      NO_DIR_CHECK='TRUE';
      ALLOW_CONNECT='TRUE';
    'VCC':
      PIN_NUMBER='(14)';
      PINUSE='POWER';
      NO_LOAD_CHECK='Both';
      NO_IO_CHECK='Both';
      NO_ASSERT_CHECK='TRUE';
      NO_DIR_CHECK='TRUE';
      ALLOW_CONNECT='TRUE';
    'VREF':
      PIN_NUMBER='(4)';
      PINUSE='POWER';
      NO_LOAD_CHECK='Both';
      NO_IO_CHECK='Both';
      NO_ASSERT_CHECK='TRUE';
      NO_DIR_CHECK='TRUE';
      ALLOW_CONNECT='TRUE';
  end_pin;
  body
      PART_NAME='GTL2014';
      PHYS_DES_PREFIX='U';
      ENVCOMP='NO;NO;NO;NO;NO;NO';
      PART_NUMBER='D66151-001';
      JEDEC_TYPE='SSOP14_18_65MA';
      CLASS='IC';
      DESCRIPTION='IC,LOG,TRANSCEIVE,TSSOP,GTL2014,NI3S';
      HEIGHT='0.043 IN';
      COMPONENT_TYPE='SUB50';
      LPID='1094';
      SPEED_URL='http://speed.intel.com:8081/speed/module/pdm/item/pdm_item_deta~
il_direct.asp?item_cde=D66151-001&item_rev=01&url_param=unused';
      STATUS='Unqual';
      RPL='YES';
      AML='1';
      BUS_UNIT='SMO_IC';
      DAYS='84';
      PARENT_PART_TYPE='GTL2014_SM';
      PARENT_PPT='GTL2014';
      PARENT_PPT_PART='GTL2014_SM-IC,D66151-001';
  end_body;
end_primitive;
primitive 'H5AN4G6NAFR-TFC-GP_MEMORY-G2-HA';
  pin
    'VPP'<0>:
      PIN_NUMBER='(B1)';
      PINUSE='POWER';
      NO_LOAD_CHECK='Both';
      NO_IO_CHECK='Both';
      NO_ASSERT_CHECK='TRUE';
      NO_DIR_CHECK='TRUE';
      ALLOW_CONNECT='TRUE';
    'VDD'<0>:
      PIN_NUMBER='(B3)';
      PINUSE='POWER';
      NO_LOAD_CHECK='Both';
      NO_IO_CHECK='Both';
      NO_ASSERT_CHECK='TRUE';
      NO_DIR_CHECK='TRUE';
      ALLOW_CONNECT='TRUE';
    'VDD'<1>:
      PIN_NUMBER='(B9)';
      PINUSE='POWER';
      NO_LOAD_CHECK='Both';
      NO_IO_CHECK='Both';
      NO_ASSERT_CHECK='TRUE';
      NO_DIR_CHECK='TRUE';
      ALLOW_CONNECT='TRUE';
    'VDD'<2>:
      PIN_NUMBER='(D1)';
      PINUSE='POWER';
      NO_LOAD_CHECK='Both';
      NO_IO_CHECK='Both';
      NO_ASSERT_CHECK='TRUE';
      NO_DIR_CHECK='TRUE';
      ALLOW_CONNECT='TRUE';
    'VDD'<3>:
      PIN_NUMBER='(G7)';
      PINUSE='POWER';
      NO_LOAD_CHECK='Both';
      NO_IO_CHECK='Both';
      NO_ASSERT_CHECK='TRUE';
      NO_DIR_CHECK='TRUE';
      ALLOW_CONNECT='TRUE';
    'VDD'<4>:
      PIN_NUMBER='(J1)';
      PINUSE='POWER';
      NO_LOAD_CHECK='Both';
      NO_IO_CHECK='Both';
      NO_ASSERT_CHECK='TRUE';
      NO_DIR_CHECK='TRUE';
      ALLOW_CONNECT='TRUE';
    'VDD'<5>:
      PIN_NUMBER='(J9)';
      PINUSE='POWER';
      NO_LOAD_CHECK='Both';
      NO_IO_CHECK='Both';
      NO_ASSERT_CHECK='TRUE';
      NO_DIR_CHECK='TRUE';
      ALLOW_CONNECT='TRUE';
    'VDD'<6>:
      PIN_NUMBER='(L1)';
      PINUSE='POWER';
      NO_LOAD_CHECK='Both';
      NO_IO_CHECK='Both';
      NO_ASSERT_CHECK='TRUE';
      NO_DIR_CHECK='TRUE';
      ALLOW_CONNECT='TRUE';
    'VDD'<7>:
      PIN_NUMBER='(L9)';
      PINUSE='POWER';
      NO_LOAD_CHECK='Both';
      NO_IO_CHECK='Both';
      NO_ASSERT_CHECK='TRUE';
      NO_DIR_CHECK='TRUE';
      ALLOW_CONNECT='TRUE';
    'VDD'<8>:
      PIN_NUMBER='(R1)';
      PINUSE='POWER';
      NO_LOAD_CHECK='Both';
      NO_IO_CHECK='Both';
      NO_ASSERT_CHECK='TRUE';
      NO_DIR_CHECK='TRUE';
      ALLOW_CONNECT='TRUE';
    'VDD'<9>:
      PIN_NUMBER='(T9)';
      PINUSE='POWER';
      NO_LOAD_CHECK='Both';
      NO_IO_CHECK='Both';
      NO_ASSERT_CHECK='TRUE';
      NO_DIR_CHECK='TRUE';
      ALLOW_CONNECT='TRUE';
    'VDDQ'<0>:
      PIN_NUMBER='(A1)';
      PINUSE='POWER';
      NO_LOAD_CHECK='Both';
      NO_IO_CHECK='Both';
      NO_ASSERT_CHECK='TRUE';
      NO_DIR_CHECK='TRUE';
      ALLOW_CONNECT='TRUE';
    'VDDQ'<1>:
      PIN_NUMBER='(A9)';
      PINUSE='POWER';
      NO_LOAD_CHECK='Both';
      NO_IO_CHECK='Both';
      NO_ASSERT_CHECK='TRUE';
      NO_DIR_CHECK='TRUE';
      ALLOW_CONNECT='TRUE';
    'VDDQ'<2>:
      PIN_NUMBER='(C1)';
      PINUSE='POWER';
      NO_LOAD_CHECK='Both';
      NO_IO_CHECK='Both';
      NO_ASSERT_CHECK='TRUE';
      NO_DIR_CHECK='TRUE';
      ALLOW_CONNECT='TRUE';
    'VDDQ'<3>:
      PIN_NUMBER='(D9)';
      PINUSE='POWER';
      NO_LOAD_CHECK='Both';
      NO_IO_CHECK='Both';
      NO_ASSERT_CHECK='TRUE';
      NO_DIR_CHECK='TRUE';
      ALLOW_CONNECT='TRUE';
    'VDDQ'<4>:
      PIN_NUMBER='(F2)';
      PINUSE='POWER';
      NO_LOAD_CHECK='Both';
      NO_IO_CHECK='Both';
      NO_ASSERT_CHECK='TRUE';
      NO_DIR_CHECK='TRUE';
      ALLOW_CONNECT='TRUE';
    'VDDQ'<5>:
      PIN_NUMBER='(F8)';
      PINUSE='POWER';
      NO_LOAD_CHECK='Both';
      NO_IO_CHECK='Both';
      NO_ASSERT_CHECK='TRUE';
      NO_DIR_CHECK='TRUE';
      ALLOW_CONNECT='TRUE';
    'VDDQ'<6>:
      PIN_NUMBER='(G1)';
      PINUSE='POWER';
      NO_LOAD_CHECK='Both';
      NO_IO_CHECK='Both';
      NO_ASSERT_CHECK='TRUE';
      NO_DIR_CHECK='TRUE';
      ALLOW_CONNECT='TRUE';
    'VDDQ'<7>:
      PIN_NUMBER='(G9)';
      PINUSE='POWER';
      NO_LOAD_CHECK='Both';
      NO_IO_CHECK='Both';
      NO_ASSERT_CHECK='TRUE';
      NO_DIR_CHECK='TRUE';
      ALLOW_CONNECT='TRUE';
    'VDDQ'<8>:
      PIN_NUMBER='(J2)';
      PINUSE='POWER';
      NO_LOAD_CHECK='Both';
      NO_IO_CHECK='Both';
      NO_ASSERT_CHECK='TRUE';
      NO_DIR_CHECK='TRUE';
      ALLOW_CONNECT='TRUE';
    'VDDQ'<9>:
      PIN_NUMBER='(J8)';
      PINUSE='POWER';
      NO_LOAD_CHECK='Both';
      NO_IO_CHECK='Both';
      NO_ASSERT_CHECK='TRUE';
      NO_DIR_CHECK='TRUE';
      ALLOW_CONNECT='TRUE';
    'DQU4':
      PIN_NUMBER='(C2)';
      PIN_TYPE='ANALOG';
      NO_LOAD_CHECK='Both';
      NO_IO_CHECK='Both';
      NO_ASSERT_CHECK='TRUE';
      NO_DIR_CHECK='TRUE';
      ALLOW_CONNECT='TRUE';
      PINUSE='UNSPEC';
    'DQU5':
      PIN_NUMBER='(C8)';
      PIN_TYPE='ANALOG';
      NO_LOAD_CHECK='Both';
      NO_IO_CHECK='Both';
      NO_ASSERT_CHECK='TRUE';
      NO_DIR_CHECK='TRUE';
      ALLOW_CONNECT='TRUE';
      PINUSE='UNSPEC';
    'DQU6':
      PIN_NUMBER='(D3)';
      PIN_TYPE='ANALOG';
      NO_LOAD_CHECK='Both';
      NO_IO_CHECK='Both';
      NO_ASSERT_CHECK='TRUE';
      NO_DIR_CHECK='TRUE';
      ALLOW_CONNECT='TRUE';
      PINUSE='UNSPEC';
    'DQU7':
      PIN_NUMBER='(D7)';
      PIN_TYPE='ANALOG';
      NO_LOAD_CHECK='Both';
      NO_IO_CHECK='Both';
      NO_ASSERT_CHECK='TRUE';
      NO_DIR_CHECK='TRUE';
      ALLOW_CONNECT='TRUE';
      PINUSE='UNSPEC';
    'DQU0':
      PIN_NUMBER='(A3)';
      PIN_TYPE='ANALOG';
      NO_LOAD_CHECK='Both';
      NO_IO_CHECK='Both';
      NO_ASSERT_CHECK='TRUE';
      NO_DIR_CHECK='TRUE';
      ALLOW_CONNECT='TRUE';
      PINUSE='UNSPEC';
    'DQU1':
      PIN_NUMBER='(B8)';
      PIN_TYPE='ANALOG';
      NO_LOAD_CHECK='Both';
      NO_IO_CHECK='Both';
      NO_ASSERT_CHECK='TRUE';
      NO_DIR_CHECK='TRUE';
      ALLOW_CONNECT='TRUE';
      PINUSE='UNSPEC';
    'DQU2':
      PIN_NUMBER='(C3)';
      PIN_TYPE='ANALOG';
      NO_LOAD_CHECK='Both';
      NO_IO_CHECK='Both';
      NO_ASSERT_CHECK='TRUE';
      NO_DIR_CHECK='TRUE';
      ALLOW_CONNECT='TRUE';
      PINUSE='UNSPEC';
    'DQU3':
      PIN_NUMBER='(C7)';
      PIN_TYPE='ANALOG';
      NO_LOAD_CHECK='Both';
      NO_IO_CHECK='Both';
      NO_ASSERT_CHECK='TRUE';
      NO_DIR_CHECK='TRUE';
      ALLOW_CONNECT='TRUE';
      PINUSE='UNSPEC';
    'DQL1':
      PIN_NUMBER='(F7)';
      PIN_TYPE='ANALOG';
      NO_LOAD_CHECK='Both';
      NO_IO_CHECK='Both';
      NO_ASSERT_CHECK='TRUE';
      NO_DIR_CHECK='TRUE';
      ALLOW_CONNECT='TRUE';
      PINUSE='UNSPEC';
    'DQL0':
      PIN_NUMBER='(G2)';
      PIN_TYPE='ANALOG';
      NO_LOAD_CHECK='Both';
      NO_IO_CHECK='Both';
      NO_ASSERT_CHECK='TRUE';
      NO_DIR_CHECK='TRUE';
      ALLOW_CONNECT='TRUE';
      PINUSE='UNSPEC';
    'DQL4':
      PIN_NUMBER='(H2)';
      PIN_TYPE='ANALOG';
      NO_LOAD_CHECK='Both';
      NO_IO_CHECK='Both';
      NO_ASSERT_CHECK='TRUE';
      NO_DIR_CHECK='TRUE';
      ALLOW_CONNECT='TRUE';
      PINUSE='UNSPEC';
    'DQL2':
      PIN_NUMBER='(H3)';
      PIN_TYPE='ANALOG';
      NO_LOAD_CHECK='Both';
      NO_IO_CHECK='Both';
      NO_ASSERT_CHECK='TRUE';
      NO_DIR_CHECK='TRUE';
      ALLOW_CONNECT='TRUE';
      PINUSE='UNSPEC';
    'DQL3':
      PIN_NUMBER='(H7)';
      PIN_TYPE='ANALOG';
      NO_LOAD_CHECK='Both';
      NO_IO_CHECK='Both';
      NO_ASSERT_CHECK='TRUE';
      NO_DIR_CHECK='TRUE';
      ALLOW_CONNECT='TRUE';
      PINUSE='UNSPEC';
    'DQL5':
      PIN_NUMBER='(H8)';
      PIN_TYPE='ANALOG';
      NO_LOAD_CHECK='Both';
      NO_IO_CHECK='Both';
      NO_ASSERT_CHECK='TRUE';
      NO_DIR_CHECK='TRUE';
      ALLOW_CONNECT='TRUE';
      PINUSE='UNSPEC';
    'DQL6':
      PIN_NUMBER='(J3)';
      PIN_TYPE='ANALOG';
      NO_LOAD_CHECK='Both';
      NO_IO_CHECK='Both';
      NO_ASSERT_CHECK='TRUE';
      NO_DIR_CHECK='TRUE';
      ALLOW_CONNECT='TRUE';
      PINUSE='UNSPEC';
    'DQL7':
      PIN_NUMBER='(J7)';
      PIN_TYPE='ANALOG';
      NO_LOAD_CHECK='Both';
      NO_IO_CHECK='Both';
      NO_ASSERT_CHECK='TRUE';
      NO_DIR_CHECK='TRUE';
      ALLOW_CONNECT='TRUE';
      PINUSE='UNSPEC';
    'A0':
      PIN_NUMBER='(P3)';
      INPUT_LOAD='(-0.01,0.01)';
      PINUSE='IN';
    'A1':
      PIN_NUMBER='(P7)';
      INPUT_LOAD='(-0.01,0.01)';
      PINUSE='IN';
    'A2':
      PIN_NUMBER='(R3)';
      INPUT_LOAD='(-0.01,0.01)';
      PINUSE='IN';
    'A3':
      PIN_NUMBER='(N7)';
      INPUT_LOAD='(-0.01,0.01)';
      PINUSE='IN';
    'A4':
      PIN_NUMBER='(N3)';
      INPUT_LOAD='(-0.01,0.01)';
      PINUSE='IN';
    'A5':
      PIN_NUMBER='(P8)';
      INPUT_LOAD='(-0.01,0.01)';
      PINUSE='IN';
    'A6':
      PIN_NUMBER='(P2)';
      INPUT_LOAD='(-0.01,0.01)';
      PINUSE='IN';
    'A7':
      PIN_NUMBER='(R8)';
      INPUT_LOAD='(-0.01,0.01)';
      PINUSE='IN';
    'A8':
      PIN_NUMBER='(R2)';
      INPUT_LOAD='(-0.01,0.01)';
      PINUSE='IN';
    'A9':
      PIN_NUMBER='(R7)';
      INPUT_LOAD='(-0.01,0.01)';
      PINUSE='IN';
    'A10/AP':
      PIN_NUMBER='(M3)';
      INPUT_LOAD='(-0.01,0.01)';
      PINUSE='IN';
    'A11':
      PIN_NUMBER='(T2)';
      INPUT_LOAD='(-0.01,0.01)';
      PINUSE='IN';
    'A12/BC#':
      PIN_NUMBER='(M7)';
      INPUT_LOAD='(-0.01,0.01)';
      PINUSE='IN';
    'A13':
      PIN_NUMBER='(T8)';
      INPUT_LOAD='(-0.01,0.01)';
      PINUSE='IN';
    'WE#/A14':
      PIN_NUMBER='(L2)';
      INPUT_LOAD='(-0.01,0.01)';
      PINUSE='IN';
    'CAS#/A15':
      PIN_NUMBER='(M8)';
      INPUT_LOAD='(-0.01,0.01)';
      PINUSE='IN';
    'RAS#/A16':
      PIN_NUMBER='(L8)';
      INPUT_LOAD='(-0.01,0.01)';
      PINUSE='IN';
    'VREFCA':
      PIN_NUMBER='(M1)';
      PIN_TYPE='ANALOG';
      NO_LOAD_CHECK='Both';
      NO_IO_CHECK='Both';
      NO_ASSERT_CHECK='TRUE';
      NO_DIR_CHECK='TRUE';
      ALLOW_CONNECT='TRUE';
      PINUSE='UNSPEC';
    'ZQ':
      PIN_NUMBER='(F9)';
      PIN_TYPE='ANALOG';
      NO_LOAD_CHECK='Both';
      NO_IO_CHECK='Both';
      NO_ASSERT_CHECK='TRUE';
      NO_DIR_CHECK='TRUE';
      ALLOW_CONNECT='TRUE';
      PINUSE='UNSPEC';
    'CKE':
      PIN_NUMBER='(K2)';
      INPUT_LOAD='(-0.01,0.01)';
      PINUSE='IN';
    'ODT':
      PIN_NUMBER='(K3)';
      INPUT_LOAD='(-0.01,0.01)';
      PINUSE='IN';
    'BG0':
      PIN_NUMBER='(M2)';
      INPUT_LOAD='(-0.01,0.01)';
      PINUSE='IN';
    'TEN':
      PIN_NUMBER='(N9)';
      INPUT_LOAD='(-0.01,0.01)';
      PINUSE='IN';
    'PAR':
      PIN_NUMBER='(T3)';
      INPUT_LOAD='(-0.01,0.01)';
      PINUSE='IN';
    'NC#T7':
      PIN_NUMBER='(T7)';
      PIN_TYPE='ANALOG';
      NO_LOAD_CHECK='Both';
      NO_IO_CHECK='Both';
      NO_ASSERT_CHECK='TRUE';
      NO_DIR_CHECK='TRUE';
      ALLOW_CONNECT='TRUE';
      PINUSE='UNSPEC';
    'CK_T':
      PIN_NUMBER='(K7)';
      INPUT_LOAD='(-0.01,0.01)';
      PINUSE='IN';
    'CK_C':
      PIN_NUMBER='(K8)';
      INPUT_LOAD='(-0.01,0.01)';
      PINUSE='IN';
    'VPP'<1>:
      PIN_NUMBER='(R9)';
      PINUSE='POWER';
      NO_LOAD_CHECK='Both';
      NO_IO_CHECK='Both';
      NO_ASSERT_CHECK='TRUE';
      NO_DIR_CHECK='TRUE';
      ALLOW_CONNECT='TRUE';
    'ACT#':
      PIN_NUMBER='(L3)';
      INPUT_LOAD='(-0.01,0.01)';
      PINUSE='IN';
    'CS#':
      PIN_NUMBER='(L7)';
      INPUT_LOAD='(-0.01,0.01)';
      PINUSE='IN';
    'RESET#':
      PIN_NUMBER='(P1)';
      INPUT_LOAD='(-0.01,0.01)';
      PINUSE='IN';
    'ALERT#':
      PIN_NUMBER='(P9)';
      OUTPUT_LOAD='(1.0,-1.0)';
      PINUSE='OUT';
    'VSS'<0>:
      PIN_NUMBER='(B2)';
      PINUSE='POWER';
      NO_LOAD_CHECK='Both';
      NO_IO_CHECK='Both';
      NO_ASSERT_CHECK='TRUE';
      NO_DIR_CHECK='TRUE';
      ALLOW_CONNECT='TRUE';
    'VSS'<1>:
      PIN_NUMBER='(E1)';
      PINUSE='POWER';
      NO_LOAD_CHECK='Both';
      NO_IO_CHECK='Both';
      NO_ASSERT_CHECK='TRUE';
      NO_DIR_CHECK='TRUE';
      ALLOW_CONNECT='TRUE';
    'VSS'<2>:
      PIN_NUMBER='(E9)';
      PINUSE='POWER';
      NO_LOAD_CHECK='Both';
      NO_IO_CHECK='Both';
      NO_ASSERT_CHECK='TRUE';
      NO_DIR_CHECK='TRUE';
      ALLOW_CONNECT='TRUE';
    'VSS'<3>:
      PIN_NUMBER='(G8)';
      PINUSE='POWER';
      NO_LOAD_CHECK='Both';
      NO_IO_CHECK='Both';
      NO_ASSERT_CHECK='TRUE';
      NO_DIR_CHECK='TRUE';
      ALLOW_CONNECT='TRUE';
    'VSS'<4>:
      PIN_NUMBER='(K1)';
      PINUSE='POWER';
      NO_LOAD_CHECK='Both';
      NO_IO_CHECK='Both';
      NO_ASSERT_CHECK='TRUE';
      NO_DIR_CHECK='TRUE';
      ALLOW_CONNECT='TRUE';
    'VSS'<5>:
      PIN_NUMBER='(K9)';
      PINUSE='POWER';
      NO_LOAD_CHECK='Both';
      NO_IO_CHECK='Both';
      NO_ASSERT_CHECK='TRUE';
      NO_DIR_CHECK='TRUE';
      ALLOW_CONNECT='TRUE';
    'VSS'<6>:
      PIN_NUMBER='(M9)';
      PINUSE='POWER';
      NO_LOAD_CHECK='Both';
      NO_IO_CHECK='Both';
      NO_ASSERT_CHECK='TRUE';
      NO_DIR_CHECK='TRUE';
      ALLOW_CONNECT='TRUE';
    'VSS'<7>:
      PIN_NUMBER='(N1)';
      PINUSE='POWER';
      NO_LOAD_CHECK='Both';
      NO_IO_CHECK='Both';
      NO_ASSERT_CHECK='TRUE';
      NO_DIR_CHECK='TRUE';
      ALLOW_CONNECT='TRUE';
    'VSS'<8>:
      PIN_NUMBER='(T1)';
      PINUSE='POWER';
      NO_LOAD_CHECK='Both';
      NO_IO_CHECK='Both';
      NO_ASSERT_CHECK='TRUE';
      NO_DIR_CHECK='TRUE';
      ALLOW_CONNECT='TRUE';
    'VSSQ'<0>:
      PIN_NUMBER='(A2)';
      PINUSE='POWER';
      NO_LOAD_CHECK='Both';
      NO_IO_CHECK='Both';
      NO_ASSERT_CHECK='TRUE';
      NO_DIR_CHECK='TRUE';
      ALLOW_CONNECT='TRUE';
    'VSSQ'<1>:
      PIN_NUMBER='(A8)';
      PINUSE='POWER';
      NO_LOAD_CHECK='Both';
      NO_IO_CHECK='Both';
      NO_ASSERT_CHECK='TRUE';
      NO_DIR_CHECK='TRUE';
      ALLOW_CONNECT='TRUE';
    'VSSQ'<2>:
      PIN_NUMBER='(C9)';
      PINUSE='POWER';
      NO_LOAD_CHECK='Both';
      NO_IO_CHECK='Both';
      NO_ASSERT_CHECK='TRUE';
      NO_DIR_CHECK='TRUE';
      ALLOW_CONNECT='TRUE';
    'VSSQ'<3>:
      PIN_NUMBER='(D2)';
      PINUSE='POWER';
      NO_LOAD_CHECK='Both';
      NO_IO_CHECK='Both';
      NO_ASSERT_CHECK='TRUE';
      NO_DIR_CHECK='TRUE';
      ALLOW_CONNECT='TRUE';
    'VSSQ'<4>:
      PIN_NUMBER='(D8)';
      PINUSE='POWER';
      NO_LOAD_CHECK='Both';
      NO_IO_CHECK='Both';
      NO_ASSERT_CHECK='TRUE';
      NO_DIR_CHECK='TRUE';
      ALLOW_CONNECT='TRUE';
    'VSSQ'<5>:
      PIN_NUMBER='(E3)';
      PINUSE='POWER';
      NO_LOAD_CHECK='Both';
      NO_IO_CHECK='Both';
      NO_ASSERT_CHECK='TRUE';
      NO_DIR_CHECK='TRUE';
      ALLOW_CONNECT='TRUE';
    'VSSQ'<6>:
      PIN_NUMBER='(E8)';
      PINUSE='POWER';
      NO_LOAD_CHECK='Both';
      NO_IO_CHECK='Both';
      NO_ASSERT_CHECK='TRUE';
      NO_DIR_CHECK='TRUE';
      ALLOW_CONNECT='TRUE';
    'VSSQ'<7>:
      PIN_NUMBER='(F1)';
      PINUSE='POWER';
      NO_LOAD_CHECK='Both';
      NO_IO_CHECK='Both';
      NO_ASSERT_CHECK='TRUE';
      NO_DIR_CHECK='TRUE';
      ALLOW_CONNECT='TRUE';
    'VSSQ'<8>:
      PIN_NUMBER='(H1)';
      PINUSE='POWER';
      NO_LOAD_CHECK='Both';
      NO_IO_CHECK='Both';
      NO_ASSERT_CHECK='TRUE';
      NO_DIR_CHECK='TRUE';
      ALLOW_CONNECT='TRUE';
    'VSSQ'<9>:
      PIN_NUMBER='(H9)';
      PINUSE='POWER';
      NO_LOAD_CHECK='Both';
      NO_IO_CHECK='Both';
      NO_ASSERT_CHECK='TRUE';
      NO_DIR_CHECK='TRUE';
      ALLOW_CONNECT='TRUE';
    'DQSU_C':
      PIN_NUMBER='(A7)';
      BIDIRECTIONAL='TRUE';
      INPUT_LOAD='(-0.01,0.01)';
      OUTPUT_LOAD='(1.0,-1.0)';
      PINUSE='BI';
    'DQSU_T':
      PIN_NUMBER='(B7)';
      BIDIRECTIONAL='TRUE';
      INPUT_LOAD='(-0.01,0.01)';
      OUTPUT_LOAD='(1.0,-1.0)';
      PINUSE='BI';
    'DQSL_C':
      PIN_NUMBER='(F3)';
      BIDIRECTIONAL='TRUE';
      INPUT_LOAD='(-0.01,0.01)';
      OUTPUT_LOAD='(1.0,-1.0)';
      PINUSE='BI';
    'DQSL_T':
      PIN_NUMBER='(G3)';
      BIDIRECTIONAL='TRUE';
      INPUT_LOAD='(-0.01,0.01)';
      OUTPUT_LOAD='(1.0,-1.0)';
      PINUSE='BI';
    'DMU#/DBIU#':
      PIN_NUMBER='(E2)';
      BIDIRECTIONAL='TRUE';
      INPUT_LOAD='(-0.01,0.01)';
      OUTPUT_LOAD='(1.0,-1.0)';
      PINUSE='BI';
    'DML#/DBIL#':
      PIN_NUMBER='(E7)';
      BIDIRECTIONAL='TRUE';
      INPUT_LOAD='(-0.01,0.01)';
      OUTPUT_LOAD='(1.0,-1.0)';
      PINUSE='BI';
    'BA0':
      PIN_NUMBER='(N2)';
      INPUT_LOAD='(-0.01,0.01)';
      PINUSE='IN';
    'BA1':
      PIN_NUMBER='(N8)';
      INPUT_LOAD='(-0.01,0.01)';
      PINUSE='IN';
  end_pin;
  body
      PART_NAME='H5AN4G6NAFR-TFC-GP';
      BODY_NAME='H5AN4G6NAFR-TFC-GP';
      PHYS_DES_PREFIX='U';
      CLASS='IC';
      DESCRIPTION='IC SDRAM H5AN4G6NAFR-TFC FBGA96P DDR4';
      JEDEC_TYPE='BGA96D075130H48';
      PARENT_PART_TYPE='H5AN4G6NAFR-TFC-GP';
      PARENT_PPT='H5AN4G6NAFR-TFC-GP';
      PARENT_PPT_PART='H5AN4G6NAFR-TFC-GP_MEMORY-G2-H5AN4G6NAFR-TFC-GP,072.00546.0A0U';
  end_body;
end_primitive;
primitive 'HCB1608KF-800T30-GP_DISCRET-G9A';
  pin
    '1':
      PIN_NUMBER='(1)';
      PIN_TYPE='ANALOG';
      NO_LOAD_CHECK='Both';
      NO_IO_CHECK='Both';
      NO_ASSERT_CHECK='TRUE';
      NO_DIR_CHECK='TRUE';
      ALLOW_CONNECT='TRUE';
      PINUSE='UNSPEC';
    '2':
      PIN_NUMBER='(2)';
      PIN_TYPE='ANALOG';
      NO_LOAD_CHECK='Both';
      NO_IO_CHECK='Both';
      NO_ASSERT_CHECK='TRUE';
      NO_DIR_CHECK='TRUE';
      ALLOW_CONNECT='TRUE';
      PINUSE='UNSPEC';
  end_pin;
  body
      PART_NAME='HCB1608KF-800T30-GP';
      BODY_NAME='HCB1608KF-800T30-GP';
      PHYS_DES_PREFIX='L';
      CLASS='DISCRETE';
      DESCRIPTION='CHIP BEAD HCB1608KF-800T30';
      JEDEC_TYPE='L603H38';
      PARENT_PART_TYPE='HCB1608KF-800T30-GP';
      PARENT_PPT='HCB1608KF-800T30-GP';
      PARENT_PPT_PART='HCB1608KF-800T30-GP_DISCRET-G9-HCB1608KF-800T30-GP,68.00230.231,80OHM@100MHZ,3A,DCR=4MOHM';
  end_body;
end_primitive;
primitive 'ICS9FGP204_MLFP-IC,E95226-001';
  pin
    'VDD32K':
      PIN_NUMBER='(12)';
      PINUSE='POWER';
      NO_LOAD_CHECK='Both';
      NO_IO_CHECK='Both';
      NO_ASSERT_CHECK='TRUE';
      NO_DIR_CHECK='TRUE';
      ALLOW_CONNECT='TRUE';
    '32KHZ':
      PIN_NUMBER='(13)';
      OUTPUT_LOAD='(1.0,-1.0)';
      PINUSE='OUT';
    'GND32K':
      PIN_NUMBER='(14)';
      PINUSE='GROUND';
      NO_LOAD_CHECK='Both';
      NO_IO_CHECK='Both';
      NO_ASSERT_CHECK='TRUE';
      NO_DIR_CHECK='TRUE';
      ALLOW_CONNECT='TRUE';
    '25MHZ_0':
      PIN_NUMBER='(16)';
      OUTPUT_LOAD='(1.0,-1.0)';
      PINUSE='OUT';
    '25MHZ_1':
      PIN_NUMBER='(17)';
      OUTPUT_LOAD='(1.0,-1.0)';
      PINUSE='OUT';
    'RMII'<1>:
      PIN_NUMBER='(32)';
      OUTPUT_LOAD='(1.0,-1.0)';
      PINUSE='OUT';
    'RMII'<2>:
      PIN_NUMBER='(29)';
      OUTPUT_LOAD='(1.0,-1.0)';
      PINUSE='OUT';
    'RMII'<5>:
      PIN_NUMBER='(24)';
      OUTPUT_LOAD='(1.0,-1.0)';
      PINUSE='OUT';
    'RMII'<4>:
      PIN_NUMBER='(25)';
      OUTPUT_LOAD='(1.0,-1.0)';
      PINUSE='OUT';
    'RMII'<3>:
      PIN_NUMBER='(28)';
      OUTPUT_LOAD='(1.0,-1.0)';
      PINUSE='OUT';
    'RMII'<0>:
      PIN_NUMBER='(33)';
      OUTPUT_LOAD='(1.0,-1.0)';
      PINUSE='OUT';
    'GND'<1>:
      PIN_NUMBER='(41)';
      PINUSE='GROUND';
      NO_LOAD_CHECK='Both';
      NO_IO_CHECK='Both';
      NO_ASSERT_CHECK='TRUE';
      NO_DIR_CHECK='TRUE';
      ALLOW_CONNECT='TRUE';
    'GND33':
      PIN_NUMBER='(21)';
      PINUSE='GROUND';
      NO_LOAD_CHECK='Both';
      NO_IO_CHECK='Both';
      NO_ASSERT_CHECK='TRUE';
      NO_DIR_CHECK='TRUE';
      ALLOW_CONNECT='TRUE';
    'GND'<0>:
      PIN_NUMBER='(1)';
      PINUSE='GROUND';
      NO_LOAD_CHECK='Both';
      NO_IO_CHECK='Both';
      NO_ASSERT_CHECK='TRUE';
      NO_DIR_CHECK='TRUE';
      ALLOW_CONNECT='TRUE';
    'DOT96SSC':
      PIN_NUMBER='(4)';
      OUTPUT_LOAD='(1.0,-1.0)';
      PINUSE='OUT';
    'DOT96SST':
      PIN_NUMBER='(3)';
      OUTPUT_LOAD='(1.0,-1.0)';
      PINUSE='OUT';
    'CPUCLKC0':
      PIN_NUMBER='(8)';
      OUTPUT_LOAD='(1.0,-1.0)';
      PINUSE='OUT';
    'GNDREF':
      PIN_NUMBER='(18)';
      PINUSE='GROUND';
      NO_LOAD_CHECK='Both';
      NO_IO_CHECK='Both';
      NO_ASSERT_CHECK='TRUE';
      NO_DIR_CHECK='TRUE';
      ALLOW_CONNECT='TRUE';
    'CPUCLKT0':
      PIN_NUMBER='(7)';
      OUTPUT_LOAD='(1.0,-1.0)';
      PINUSE='OUT';
    'VDDREF':
      PIN_NUMBER='(15)';
      PINUSE='POWER';
      NO_LOAD_CHECK='Both';
      NO_IO_CHECK='Both';
      NO_ASSERT_CHECK='TRUE';
      NO_DIR_CHECK='TRUE';
      ALLOW_CONNECT='TRUE';
    'IREF':
      PIN_NUMBER='(11)';
      OUTPUT_LOAD='(1.0,-1.0)';
      PINUSE='OUT';
    'X1_25':
      PIN_NUMBER='(19)';
      INPUT_LOAD='(-0.01,0.01)';
      PINUSE='IN';
    'GNDRMII'<0>:
      PIN_NUMBER='(27)';
      PINUSE='GROUND';
      NO_LOAD_CHECK='Both';
      NO_IO_CHECK='Both';
      NO_ASSERT_CHECK='TRUE';
      NO_DIR_CHECK='TRUE';
      ALLOW_CONNECT='TRUE';
    'VDDRMII'<0>:
      PIN_NUMBER='(26)';
      PINUSE='POWER';
      NO_LOAD_CHECK='Both';
      NO_IO_CHECK='Both';
      NO_ASSERT_CHECK='TRUE';
      NO_DIR_CHECK='TRUE';
      ALLOW_CONNECT='TRUE';
    'VDDRMII'<1>:
      PIN_NUMBER='(31)';
      PINUSE='POWER';
      NO_LOAD_CHECK='Both';
      NO_IO_CHECK='Both';
      NO_ASSERT_CHECK='TRUE';
      NO_DIR_CHECK='TRUE';
      ALLOW_CONNECT='TRUE';
    'GNDRMII'<1>:
      PIN_NUMBER='(30)';
      PINUSE='GROUND';
      NO_LOAD_CHECK='Both';
      NO_IO_CHECK='Both';
      NO_ASSERT_CHECK='TRUE';
      NO_DIR_CHECK='TRUE';
      ALLOW_CONNECT='TRUE';
    '33MHZ_SMBADR':
      PIN_NUMBER='(22)';
      BIDIRECTIONAL='TRUE';
      INPUT_LOAD='(-0.01,0.01)';
      OUTPUT_LOAD='(1.0,-1.0)';
      PINUSE='BI';
    'VDD33':
      PIN_NUMBER='(23)';
      PINUSE='POWER';
      NO_LOAD_CHECK='Both';
      NO_IO_CHECK='Both';
      NO_ASSERT_CHECK='TRUE';
      NO_DIR_CHECK='TRUE';
      ALLOW_CONNECT='TRUE';
    'OE_96':
      PIN_NUMBER='(5)';
      INPUT_LOAD='(-0.01,0.01)';
      PINUSE='IN';
    'VDD96':
      PIN_NUMBER='(2)';
      PINUSE='POWER';
      NO_LOAD_CHECK='Both';
      NO_IO_CHECK='Both';
      NO_ASSERT_CHECK='TRUE';
      NO_DIR_CHECK='TRUE';
      ALLOW_CONNECT='TRUE';
    'OE_CPU':
      PIN_NUMBER='(6)';
      INPUT_LOAD='(-0.01,0.01)';
      PINUSE='IN';
    'GNDCPU':
      PIN_NUMBER='(10)';
      PINUSE='GROUND';
      NO_LOAD_CHECK='Both';
      NO_IO_CHECK='Both';
      NO_ASSERT_CHECK='TRUE';
      NO_DIR_CHECK='TRUE';
      ALLOW_CONNECT='TRUE';
    'VDDCPU':
      PIN_NUMBER='(9)';
      PINUSE='POWER';
      NO_LOAD_CHECK='Both';
      NO_IO_CHECK='Both';
      NO_ASSERT_CHECK='TRUE';
      NO_DIR_CHECK='TRUE';
      ALLOW_CONNECT='TRUE';
    'VTTPWR_GD_PD_N':
      PIN_NUMBER='(40)';
      INPUT_LOAD='(-0.01,0.01)';
      PINUSE='IN';
    'SMBCLK':
      PIN_NUMBER='(38)';
      INPUT_LOAD='(-0.01,0.01)';
      PINUSE='IN';
    'X2_25':
      PIN_NUMBER='(20)';
      OUTPUT_LOAD='(1.0,-1.0)';
      PINUSE='OUT';
    'SMBDAT':
      PIN_NUMBER='(39)';
      BIDIRECTIONAL='TRUE';
      INPUT_LOAD='(-0.01,0.01)';
      OUTPUT_LOAD='(1.0,-1.0)';
      PINUSE='BI';
    'VDD_RGMII':
      PIN_NUMBER='(34)';
      INPUT_LOAD='(-0.01,0.01)';
      PINUSE='IN';
    'GND_RGMII':
      PIN_NUMBER='(35)';
      PINUSE='GROUND';
      NO_LOAD_CHECK='Both';
      NO_IO_CHECK='Both';
      NO_ASSERT_CHECK='TRUE';
      NO_DIR_CHECK='TRUE';
      ALLOW_CONNECT='TRUE';
    'RGMII'<0>:
      PIN_NUMBER='(37)';
      OUTPUT_LOAD='(1.0,-1.0)';
      PINUSE='OUT';
    'RGMII'<1>:
      PIN_NUMBER='(36)';
      OUTPUT_LOAD='(1.0,-1.0)';
      PINUSE='OUT';
  end_pin;
  body
      PART_NAME='ICS9FGP204';
      BODY_NAME='ICS9FGP204';
      PHYS_DES_PREFIX='EU';
      ENVCOMP='YES;YES;YES;UNK;ok;VLD';
      PART_NUMBER='E95226-001';
      JEDEC_TYPE='MLFP40_6_50MA';
      DESCRIPTION='FREQUENCY TIMING GENERATOR FOR PERIPHERALS';
      CLASS='IC';
      HEIGHT='0.039 IN';
      COMPONENT_TYPE='LCC';
      LPID='751';
      SPEED_URL='http://speed.intel.com:8081/speed/module/pdm/item/pdm_item_deta~
il_direct.asp?item_cde=E95226-001&item_rev=01&url_param=unused';
      STATUS='Conditional';
      RPL='YES';
      AML='2';
      BUS_UNIT='SMO_IC';
      DAYS='84';
      PARENT_PART_TYPE='ICS9FGP204_MLFP';
      PARENT_PPT='ICS9FGP204';
      PARENT_PPT_PART='ICS9FGP204_MLFP-IC,E95226-001';
  end_body;
end_primitive;
primitive 'IND-100NH-35-GP_DISCRET-G8-INDA';
  pin
    'S':
      PIN_NUMBER='(1)';
      PIN_TYPE='ANALOG';
      NO_LOAD_CHECK='Both';
      NO_IO_CHECK='Both';
      NO_ASSERT_CHECK='TRUE';
      NO_DIR_CHECK='TRUE';
      ALLOW_CONNECT='TRUE';
      PINUSE='UNSPEC';
    'F':
      PIN_NUMBER='(2)';
      PIN_TYPE='ANALOG';
      NO_LOAD_CHECK='Both';
      NO_IO_CHECK='Both';
      NO_ASSERT_CHECK='TRUE';
      NO_DIR_CHECK='TRUE';
      ALLOW_CONNECT='TRUE';
      PINUSE='UNSPEC';
  end_pin;
  body
      PART_NAME='IND-100NH-35-GP';
      BODY_NAME='IND-100NH-35-GP';
      PHYS_DES_PREFIX='L';
      CLASS='DISCRETE';
      DESCRIPTION='CHIP IND 100NH M HCBS404045-101(FIONA)';
      JEDEC_TYPE='L4040-13D7H178';
      PARENT_PART_TYPE='IND-100NH-35-GP';
      PARENT_PPT='IND-100NH-35-GP';
      PARENT_PPT_PART='IND-100NH-35-GP_DISCRET-G8-IND-100NH-35-GP,068.1011N.M001,100NH,ISAT=16A@25C,DCR=0.16MOHM,IRMS=29A@DELTA_T<45C';
  end_body;
end_primitive;
primitive 'IND-120NH-30-GP_DISCRET-GB2-INA';
  pin
    'S':
      PIN_NUMBER='(1)';
      PIN_TYPE='ANALOG';
      NO_LOAD_CHECK='Both';
      NO_IO_CHECK='Both';
      NO_ASSERT_CHECK='TRUE';
      NO_DIR_CHECK='TRUE';
      ALLOW_CONNECT='TRUE';
      PINUSE='UNSPEC';
    'F':
      PIN_NUMBER='(2)';
      PIN_TYPE='ANALOG';
      NO_LOAD_CHECK='Both';
      NO_IO_CHECK='Both';
      NO_ASSERT_CHECK='TRUE';
      NO_DIR_CHECK='TRUE';
      ALLOW_CONNECT='TRUE';
      PINUSE='UNSPEC';
  end_pin;
  body
      PART_NAME='IND-120NH-30-GP';
      BODY_NAME='IND-120NH-30-GP';
      PHYS_DES_PREFIX='L';
      CLASS='DISCRETE';
      DESCRIPTION='CHIP IND 120NH K HCUVE966490D-121(FIONA)';
      JEDEC_TYPE='L9664-2526H355';
      PARENT_PART_TYPE='IND-120NH-30-GP';
      PARENT_PPT='IND-120NH-30-GP';
      PARENT_PPT_PART='IND-120NH-30-GP_DISCRET-GB2-IND-120NH-30-GP,068.1202N.M001,120NH,ISAT=94A@25C,DCR=0.17MOHM,IRMS=66A@DELTA_T<40C';
  end_body;
end_primitive;
primitive 'IND-150NH-56-GP_DISCRET-GA1-INA';
  pin
    'S':
      PIN_NUMBER='(1)';
      PIN_TYPE='ANALOG';
      NO_LOAD_CHECK='Both';
      NO_IO_CHECK='Both';
      NO_ASSERT_CHECK='TRUE';
      NO_DIR_CHECK='TRUE';
      ALLOW_CONNECT='TRUE';
      PINUSE='UNSPEC';
    'F':
      PIN_NUMBER='(2)';
      PIN_TYPE='ANALOG';
      NO_LOAD_CHECK='Both';
      NO_IO_CHECK='Both';
      NO_ASSERT_CHECK='TRUE';
      NO_DIR_CHECK='TRUE';
      ALLOW_CONNECT='TRUE';
      PINUSE='UNSPEC';
  end_pin;
  body
      PART_NAME='IND-150NH-56-GP';
      BODY_NAME='IND-150NH-56-GP';
      PHYS_DES_PREFIX='L';
      CLASS='DISCRETE';
      DESCRIPTION='CHIP IND 150NH K HCUVE966490D-151(FIONA)';
      JEDEC_TYPE='L9664-2526H355';
      PARENT_PART_TYPE='IND-150NH-56-GP';
      PARENT_PPT='IND-150NH-56-GP';
      PARENT_PPT_PART='IND-150NH-56-GP_DISCRET-GA1-IND-150NH-56-GP,068.1512N.M001,150NH,ISAT=75A@25C,DCR=0.17MOHM,IRMS=66A@DELTA_T<40C';
  end_body;
end_primitive;
primitive 'IND-1UH-361-GP_DISCRET-GC1-INDA';
  pin
    '1':
      PIN_NUMBER='(1)';
      PIN_TYPE='ANALOG';
      NO_LOAD_CHECK='Both';
      NO_IO_CHECK='Both';
      NO_ASSERT_CHECK='TRUE';
      NO_DIR_CHECK='TRUE';
      ALLOW_CONNECT='TRUE';
      PINUSE='UNSPEC';
    '2':
      PIN_NUMBER='(2)';
      PIN_TYPE='ANALOG';
      NO_LOAD_CHECK='Both';
      NO_IO_CHECK='Both';
      NO_ASSERT_CHECK='TRUE';
      NO_DIR_CHECK='TRUE';
      ALLOW_CONNECT='TRUE';
      PINUSE='UNSPEC';
  end_pin;
  body
      PART_NAME='IND-1UH-361-GP';
      BODY_NAME='IND-1UH-361-GP';
      PHYS_DES_PREFIX='L';
      CLASS='DISCRETE';
      DESCRIPTION='CHIP IND 1.0UH M MHD-07EZP1R0M-XCW SMD';
      JEDEC_TYPE='L7572-5015H197';
      PARENT_PART_TYPE='IND-1UH-361-GP';
      PARENT_PPT='IND-1UH-361-GP';
      PARENT_PPT_PART='IND-1UH-361-GP_DISCRET-GC1-IND-1UH-361-GP,068.1R010.1781,1.0UH,ISAT=24A@25C,DCR=4.6MOHM';
  end_body;
end_primitive;
primitive 'IND-300NH-20-GP_DISCRET-GB1-INA';
  pin
    'S':
      PIN_NUMBER='(1)';
      PIN_TYPE='ANALOG';
      NO_LOAD_CHECK='Both';
      NO_IO_CHECK='Both';
      NO_ASSERT_CHECK='TRUE';
      NO_DIR_CHECK='TRUE';
      ALLOW_CONNECT='TRUE';
      PINUSE='UNSPEC';
    'F':
      PIN_NUMBER='(2)';
      PIN_TYPE='ANALOG';
      NO_LOAD_CHECK='Both';
      NO_IO_CHECK='Both';
      NO_ASSERT_CHECK='TRUE';
      NO_DIR_CHECK='TRUE';
      ALLOW_CONNECT='TRUE';
      PINUSE='UNSPEC';
  end_pin;
  body
      PART_NAME='IND-300NH-20-GP';
      BODY_NAME='IND-300NH-20-GP';
      PHYS_DES_PREFIX='L';
      CLASS='DISCRETE';
      DESCRIPTION='CHIP IND 300NH K HCUVE966490D-301(FIONA)';
      JEDEC_TYPE='L9664-2526H355';
      PARENT_PART_TYPE='IND-300NH-20-GP';
      PARENT_PPT='IND-300NH-20-GP';
      PARENT_PPT_PART='IND-300NH-20-GP_DISCRET-GB1-IND-300NH-20-GP,068.3012N.M001,300NH,ISAT=33A@25C,DCR=0.17MOHM,IRMS=66A@DELTA_T<40C';
  end_body;
end_primitive;
primitive 'IND-68NH-15-GP_DISCRET-GC1-INDA';
  pin
    '1':
      PIN_NUMBER='(1)';
      PIN_TYPE='ANALOG';
      NO_LOAD_CHECK='Both';
      NO_IO_CHECK='Both';
      NO_ASSERT_CHECK='TRUE';
      NO_DIR_CHECK='TRUE';
      ALLOW_CONNECT='TRUE';
      PINUSE='UNSPEC';
    '2':
      PIN_NUMBER='(2)';
      PIN_TYPE='ANALOG';
      NO_LOAD_CHECK='Both';
      NO_IO_CHECK='Both';
      NO_ASSERT_CHECK='TRUE';
      NO_DIR_CHECK='TRUE';
      ALLOW_CONNECT='TRUE';
      PINUSE='UNSPEC';
  end_pin;
  body
      PART_NAME='IND-68NH-15-GP';
      BODY_NAME='IND-68NH-15-GP';
      PHYS_DES_PREFIX='L';
      CLASS='DISCRETE';
      DESCRIPTION='CHIP IND 68NH LQG18HN68NJ00D';
      JEDEC_TYPE='L603H38';
      PARENT_PART_TYPE='IND-68NH-15-GP';
      PARENT_PPT='IND-68NH-15-GP';
      PARENT_PPT_PART='IND-68NH-15-GP_DISCRET-GC1-IND-68NH-15-GP,68.6803N.10D,68NH,300MA,DCR=800MOHM';
  end_body;
end_primitive;
primitive 'IND-80NH-1-GP_DISCRET-GC2-IND-A';
  pin
    'S':
      PIN_NUMBER='(1)';
      PIN_TYPE='ANALOG';
      NO_LOAD_CHECK='Both';
      NO_IO_CHECK='Both';
      NO_ASSERT_CHECK='TRUE';
      NO_DIR_CHECK='TRUE';
      ALLOW_CONNECT='TRUE';
      PINUSE='UNSPEC';
    'F':
      PIN_NUMBER='(2)';
      PIN_TYPE='ANALOG';
      NO_LOAD_CHECK='Both';
      NO_IO_CHECK='Both';
      NO_ASSERT_CHECK='TRUE';
      NO_DIR_CHECK='TRUE';
      ALLOW_CONNECT='TRUE';
      PINUSE='UNSPEC';
  end_pin;
  body
      PART_NAME='IND-80NH-1-GP';
      BODY_NAME='IND-80NH-1-GP';
      PHYS_DES_PREFIX='L';
      CLASS='DISCRETE';
      DESCRIPTION='CHIP IND 80NH M HCBS5265-800 SMD(FIONA)';
      JEDEC_TYPE='L5252-D720H256';
      PARENT_PART_TYPE='IND-80NH-1-GP';
      PARENT_PPT='IND-80NH-1-GP';
      PARENT_PPT_PART='IND-80NH-1-GP_DISCRET-GC2-IND-80NH-1-GP,068.8001N.M001,80NH,ISAT=50A@25C,DCR=0.22MOHM,IRMS=34A@DELTA_T<45C';
  end_body;
end_primitive;
primitive 'INDUCTOR_SM-0.47UH,IND,E13358-A';
  pin
    'INA':
      PIN_NUMBER='(1)';
      PINUSE='UNSPEC';
      NO_LOAD_CHECK='BOTH';
      NO_IO_CHECK='BOTH';
      ALLOW_CONNECT='TRUE';
      PIN_GROUP='0';
    'INB':
      PIN_NUMBER='(2)';
      PINUSE='UNSPEC';
      NO_LOAD_CHECK='BOTH';
      NO_IO_CHECK='BOTH';
      ALLOW_CONNECT='TRUE';
      PIN_GROUP='0';
  end_pin;
  body
      BODY_NAME='INDUCTOR';
      PART_NAME='INDUCTOR';
      PHYS_DES_PREFIX='L';
      ENVCOMP='YES;YES;YES;UNK;OK;VLD';
      PART_NUMBER='E13358-018';
      JEDEC_TYPE='SMI2626A';
      ALT_SYMBOLS='';
      VALUE='0.47UH';
      CLASS='DISCRETE';
      DESCRIPTION='INDUCTOR 0.47UH';
      COMPONENT_TYPE='SMTOTHER';
      HEIGHT='0.118 IN';
      LEAD_LENGTH='';
      LPID='2139';
      SPEED_URL='http://speed.intel.com:8081/speed/module/pdm/item/pdm_item_deta~
il_direct.asp?item_cde=E13358-018&item_rev=01&url_param=unused';
      STATUS='UNQUAL';
      RPL='YES';
      AML='3';
      BUS_UNIT='SMO_BOARDS';
      DAYS='???';
      PARENT_PART_TYPE='INDUCTOR';
      PARENT_PPT='INDUCTOR';
      PARENT_PPT_PART='INDUCTOR_SM-0.47UH,IND,E13358-018';
  end_body;
end_primitive;
primitive 'INDUCTOR_SM-2.2UH,IND,E98761-0A';
  pin
    'INA':
      PIN_NUMBER='(1)';
      PINUSE='UNSPEC';
      NO_LOAD_CHECK='BOTH';
      NO_IO_CHECK='BOTH';
      ALLOW_CONNECT='TRUE';
      PIN_GROUP='0';
    'INB':
      PIN_NUMBER='(2)';
      PINUSE='UNSPEC';
      NO_LOAD_CHECK='BOTH';
      NO_IO_CHECK='BOTH';
      ALLOW_CONNECT='TRUE';
      PIN_GROUP='0';
  end_pin;
  body
      BODY_NAME='INDUCTOR';
      PART_NAME='INDUCTOR';
      PHYS_DES_PREFIX='L';
      ENVCOMP='YES;YES;YES;UNK;OK;VLD';
      PART_NUMBER='E98761-003';
      JEDEC_TYPE='SMI2626A';
      ALT_SYMBOLS='';
      VALUE='2.2UH';
      CLASS='DISCRETE';
      DESCRIPTION='INDUCTOR 2.2UH';
      COMPONENT_TYPE='SMTOTHER';
      HEIGHT='0.118 IN';
      LEAD_LENGTH='';
      LPID='2139';
      SPEED_URL='http://speed.intel.com:8081/speed/module/pdm/item/pdm_item_deta~
il_direct.asp?item_cde=E98761-003&item_rev=01&url_param=unused';
      STATUS='DESIGN';
      RPL='NO';
      AML='4';
      BUS_UNIT='SMO_BOARDS';
      DAYS='???';
      PARENT_PART_TYPE='INDUCTOR';
      PARENT_PPT='INDUCTOR';
      PARENT_PPT_PART='INDUCTOR_SM-2.2UH,IND,E98761-003';
  end_body;
end_primitive;
primitive 'INDUCTOR_SMT-0.022UH,IND,72189A';
  pin
    'INA':
      PIN_NUMBER='(1)';
      PINUSE='UNSPEC';
      NO_LOAD_CHECK='BOTH';
      NO_IO_CHECK='BOTH';
      ALLOW_CONNECT='TRUE';
      PIN_GROUP='0';
    'INB':
      PIN_NUMBER='(2)';
      PINUSE='UNSPEC';
      NO_LOAD_CHECK='BOTH';
      NO_IO_CHECK='BOTH';
      ALLOW_CONNECT='TRUE';
      PIN_GROUP='0';
  end_pin;
  body
      BODY_NAME='INDUCTOR';
      PART_NAME='INDUCTOR';
      PHYS_DES_PREFIX='L';
      ENVCOMP='';
      PART_NUMBER='721891-082';
      JEDEC_TYPE='SMI0805D';
      ALT_SYMBOLS='(SMX0805)';
      VALUE='0.022UH';
      CLASS='DISCRETE';
      DESCRIPTION='INDCT,MTILAYER,22.00nH,1.85A,0805,10.00%';
      COMPONENT_TYPE='CHIP0805';
      HEIGHT='0.039 IN';
      LEAD_LENGTH='';
      LPID='2375';
      SPEED_URL='http://speed.intel.com:8081/speed/module/pdm/item/pdm_item_deta~
il_direct.asp?item_cde=721891-082&item_rev=01&url_param=unused';
      STATUS='';
      RPL='';
      AML='';
      BUS_UNIT='';
      DAYS='';
      PARENT_PART_TYPE='INDUCTOR';
      PARENT_PPT='INDUCTOR';
      PARENT_PPT_PART='INDUCTOR_SMT-0.022UH,IND,721891-082';
  end_body;
end_primitive;
primitive 'IR354XX_SM-IR35411,IC,H73688-0A';
  pin
    'BOOST':
      PIN_NUMBER='(33)';
      BIDIRECTIONAL='TRUE';
      INPUT_LOAD='(-0.01,0.01)';
      OUTPUT_LOAD='(1.0,-1.0)';
      PINUSE='BI';
    'EN':
      PIN_NUMBER='(35)';
      BIDIRECTIONAL='TRUE';
      INPUT_LOAD='(-0.01,0.01)';
      OUTPUT_LOAD='(1.0,-1.0)';
      PINUSE='BI';
    'GL'<1>:
      PIN_NUMBER='(41)';
      BIDIRECTIONAL='TRUE';
      INPUT_LOAD='(-0.01,0.01)';
      OUTPUT_LOAD='(1.0,-1.0)';
      PINUSE='BI';
    'GL'<0>:
      PIN_NUMBER='(6)';
      BIDIRECTIONAL='TRUE';
      INPUT_LOAD='(-0.01,0.01)';
      OUTPUT_LOAD='(1.0,-1.0)';
      PINUSE='BI';
    'IOUT':
      PIN_NUMBER='(38)';
      OUTPUT_LOAD='(1.0,-1.0)';
      PINUSE='OUT';
    'LGND':
      PIN_NUMBER='(2)';
      PINUSE='GROUND';
      NO_LOAD_CHECK='Both';
      NO_IO_CHECK='Both';
      NO_ASSERT_CHECK='TRUE';
      NO_DIR_CHECK='TRUE';
      ALLOW_CONNECT='TRUE';
    'NC':
      PIN_NUMBER='(31)';
      PINUSE='NC';
      NO_LOAD_CHECK='Both';
      NO_IO_CHECK='Both';
      NO_ASSERT_CHECK='TRUE';
      NO_DIR_CHECK='TRUE';
      ALLOW_CONNECT='TRUE';
    'OCSET':
      PIN_NUMBER='(37)';
      BIDIRECTIONAL='TRUE';
      INPUT_LOAD='(-0.01,0.01)';
      OUTPUT_LOAD='(1.0,-1.0)';
      PINUSE='BI';
    'PGND'<2>:
      PIN_NUMBER='(40)';
      PINUSE='GROUND';
      NO_LOAD_CHECK='Both';
      NO_IO_CHECK='Both';
      NO_ASSERT_CHECK='TRUE';
      NO_DIR_CHECK='TRUE';
      ALLOW_CONNECT='TRUE';
    'PGND'<1>:
      PIN_NUMBER='(7)';
      PINUSE='GROUND';
      NO_LOAD_CHECK='Both';
      NO_IO_CHECK='Both';
      NO_ASSERT_CHECK='TRUE';
      NO_DIR_CHECK='TRUE';
      ALLOW_CONNECT='TRUE';
    'PGND'<0>:
      PIN_NUMBER='(5)';
      PINUSE='GROUND';
      NO_LOAD_CHECK='Both';
      NO_IO_CHECK='Both';
      NO_ASSERT_CHECK='TRUE';
      NO_DIR_CHECK='TRUE';
      ALLOW_CONNECT='TRUE';
    'PHASE':
      PIN_NUMBER='(32)';
      BIDIRECTIONAL='TRUE';
      INPUT_LOAD='(-0.01,0.01)';
      OUTPUT_LOAD='(1.0,-1.0)';
      PINUSE='BI';
    'PWM':
      PIN_NUMBER='(34)';
      INPUT_LOAD='(-0.01,0.01)';
      PINUSE='IN';
    'REFIN':
      PIN_NUMBER='(39)';
      INPUT_LOAD='(-0.01,0.01)';
      PINUSE='IN';
    'SW':
      PIN_NUMBER='(10)';
      BIDIRECTIONAL='TRUE';
      INPUT_LOAD='(-0.01,0.01)';
      OUTPUT_LOAD='(1.0,-1.0)';
      PINUSE='BI';
    'TOUT_FLT':
      PIN_NUMBER='(36)';
      BIDIRECTIONAL='TRUE';
      INPUT_LOAD='(-0.01,0.01)';
      OUTPUT_LOAD='(1.0,-1.0)';
      PINUSE='BI';
    'VCC':
      PIN_NUMBER='(3)';
      PINUSE='POWER';
      NO_LOAD_CHECK='Both';
      NO_IO_CHECK='Both';
      NO_ASSERT_CHECK='TRUE';
      NO_DIR_CHECK='TRUE';
      ALLOW_CONNECT='TRUE';
    'VDRV':
      PIN_NUMBER='(4)';
      BIDIRECTIONAL='TRUE';
      INPUT_LOAD='(-0.01,0.01)';
      OUTPUT_LOAD='(1.0,-1.0)';
      PINUSE='BI';
    'VIN'<1>:
      PIN_NUMBER='(30)';
      PINUSE='POWER';
      NO_LOAD_CHECK='Both';
      NO_IO_CHECK='Both';
      NO_ASSERT_CHECK='TRUE';
      NO_DIR_CHECK='TRUE';
      ALLOW_CONNECT='TRUE';
    'VIN'<0>:
      PIN_NUMBER='(25)';
      PINUSE='POWER';
      NO_LOAD_CHECK='Both';
      NO_IO_CHECK='Both';
      NO_ASSERT_CHECK='TRUE';
      NO_DIR_CHECK='TRUE';
      ALLOW_CONNECT='TRUE';
    'VOS':
      PIN_NUMBER='(1)';
      BIDIRECTIONAL='TRUE';
      INPUT_LOAD='(-0.01,0.01)';
      OUTPUT_LOAD='(1.0,-1.0)';
      PINUSE='BI';
  end_pin;
  body
      PART_NAME='IR354XX';
      PHYS_DES_PREFIX='EU';
      ENVCOMP='';
      PART_NUMBER='H73688-001';
      JEDEC_TYPE='QFN21_24_20_45MA';
      CLASS='IC';
      DESCRIPTION='IC,LIN,DRVR,40,QFN,IR35411,FETDVR';
      HEIGHT='0.039 IN';
      COMPONENT_TYPE='LCC';
      LPID='3919';
      SPEED_URL='http://speed.intel.com:8081/speed/module/pdm/item/pdm_item_deta~
il_direct.asp?item_cde=H73688-001&item_rev=01&url_param=unused';
      STATUS='';
      RPL='';
      AML='';
      BUS_UNIT='';
      DAYS='';
      PARENT_PART_TYPE='IR354XX_SM';
      PARENT_PPT='IR354XX';
      PARENT_PPT_PART='IR354XX_SM-IR35411,IC,H73688-001';
  end_body;
end_primitive;
primitive 'IR354XX_SM-IR35412,IC,H73684-0A';
  pin
    'BOOST':
      PIN_NUMBER='(33)';
      BIDIRECTIONAL='TRUE';
      INPUT_LOAD='(-0.01,0.01)';
      OUTPUT_LOAD='(1.0,-1.0)';
      PINUSE='BI';
    'EN':
      PIN_NUMBER='(35)';
      BIDIRECTIONAL='TRUE';
      INPUT_LOAD='(-0.01,0.01)';
      OUTPUT_LOAD='(1.0,-1.0)';
      PINUSE='BI';
    'GL'<1>:
      PIN_NUMBER='(41)';
      BIDIRECTIONAL='TRUE';
      INPUT_LOAD='(-0.01,0.01)';
      OUTPUT_LOAD='(1.0,-1.0)';
      PINUSE='BI';
    'GL'<0>:
      PIN_NUMBER='(6)';
      BIDIRECTIONAL='TRUE';
      INPUT_LOAD='(-0.01,0.01)';
      OUTPUT_LOAD='(1.0,-1.0)';
      PINUSE='BI';
    'IOUT':
      PIN_NUMBER='(38)';
      OUTPUT_LOAD='(1.0,-1.0)';
      PINUSE='OUT';
    'LGND':
      PIN_NUMBER='(2)';
      PINUSE='GROUND';
      NO_LOAD_CHECK='Both';
      NO_IO_CHECK='Both';
      NO_ASSERT_CHECK='TRUE';
      NO_DIR_CHECK='TRUE';
      ALLOW_CONNECT='TRUE';
    'NC':
      PIN_NUMBER='(31)';
      PINUSE='NC';
      NO_LOAD_CHECK='Both';
      NO_IO_CHECK='Both';
      NO_ASSERT_CHECK='TRUE';
      NO_DIR_CHECK='TRUE';
      ALLOW_CONNECT='TRUE';
    'OCSET':
      PIN_NUMBER='(37)';
      BIDIRECTIONAL='TRUE';
      INPUT_LOAD='(-0.01,0.01)';
      OUTPUT_LOAD='(1.0,-1.0)';
      PINUSE='BI';
    'PGND'<2>:
      PIN_NUMBER='(40)';
      PINUSE='GROUND';
      NO_LOAD_CHECK='Both';
      NO_IO_CHECK='Both';
      NO_ASSERT_CHECK='TRUE';
      NO_DIR_CHECK='TRUE';
      ALLOW_CONNECT='TRUE';
    'PGND'<1>:
      PIN_NUMBER='(7)';
      PINUSE='GROUND';
      NO_LOAD_CHECK='Both';
      NO_IO_CHECK='Both';
      NO_ASSERT_CHECK='TRUE';
      NO_DIR_CHECK='TRUE';
      ALLOW_CONNECT='TRUE';
    'PGND'<0>:
      PIN_NUMBER='(5)';
      PINUSE='GROUND';
      NO_LOAD_CHECK='Both';
      NO_IO_CHECK='Both';
      NO_ASSERT_CHECK='TRUE';
      NO_DIR_CHECK='TRUE';
      ALLOW_CONNECT='TRUE';
    'PHASE':
      PIN_NUMBER='(32)';
      BIDIRECTIONAL='TRUE';
      INPUT_LOAD='(-0.01,0.01)';
      OUTPUT_LOAD='(1.0,-1.0)';
      PINUSE='BI';
    'PWM':
      PIN_NUMBER='(34)';
      INPUT_LOAD='(-0.01,0.01)';
      PINUSE='IN';
    'REFIN':
      PIN_NUMBER='(39)';
      INPUT_LOAD='(-0.01,0.01)';
      PINUSE='IN';
    'SW':
      PIN_NUMBER='(10)';
      BIDIRECTIONAL='TRUE';
      INPUT_LOAD='(-0.01,0.01)';
      OUTPUT_LOAD='(1.0,-1.0)';
      PINUSE='BI';
    'TOUT_FLT':
      PIN_NUMBER='(36)';
      BIDIRECTIONAL='TRUE';
      INPUT_LOAD='(-0.01,0.01)';
      OUTPUT_LOAD='(1.0,-1.0)';
      PINUSE='BI';
    'VCC':
      PIN_NUMBER='(3)';
      PINUSE='POWER';
      NO_LOAD_CHECK='Both';
      NO_IO_CHECK='Both';
      NO_ASSERT_CHECK='TRUE';
      NO_DIR_CHECK='TRUE';
      ALLOW_CONNECT='TRUE';
    'VDRV':
      PIN_NUMBER='(4)';
      BIDIRECTIONAL='TRUE';
      INPUT_LOAD='(-0.01,0.01)';
      OUTPUT_LOAD='(1.0,-1.0)';
      PINUSE='BI';
    'VIN'<1>:
      PIN_NUMBER='(30)';
      PINUSE='POWER';
      NO_LOAD_CHECK='Both';
      NO_IO_CHECK='Both';
      NO_ASSERT_CHECK='TRUE';
      NO_DIR_CHECK='TRUE';
      ALLOW_CONNECT='TRUE';
    'VIN'<0>:
      PIN_NUMBER='(25)';
      PINUSE='POWER';
      NO_LOAD_CHECK='Both';
      NO_IO_CHECK='Both';
      NO_ASSERT_CHECK='TRUE';
      NO_DIR_CHECK='TRUE';
      ALLOW_CONNECT='TRUE';
    'VOS':
      PIN_NUMBER='(1)';
      BIDIRECTIONAL='TRUE';
      INPUT_LOAD='(-0.01,0.01)';
      OUTPUT_LOAD='(1.0,-1.0)';
      PINUSE='BI';
  end_pin;
  body
      PART_NAME='IR354XX';
      PHYS_DES_PREFIX='EU';
      ENVCOMP='';
      PART_NUMBER='H73684-001';
      JEDEC_TYPE='QFN21_24_20_45MA';
      CLASS='IC';
      DESCRIPTION='IC,LIN,DRVR,40,QFN,IR35412,FETDVR';
      HEIGHT='0.039 IN';
      COMPONENT_TYPE='LCC';
      LPID='3919';
      SPEED_URL='http://speed.intel.com:8081/speed/module/pdm/item/pdm_item_deta~
il_direct.asp?item_cde=H73684-001&item_rev=01&url_param=unused';
      STATUS='';
      RPL='';
      AML='';
      BUS_UNIT='';
      DAYS='';
      PARENT_PART_TYPE='IR354XX_SM';
      PARENT_PPT='IR354XX';
      PARENT_PPT_PART='IR354XX_SM-IR35412,IC,H73684-001';
  end_body;
end_primitive;
primitive 'LBG_CORE_QAT_EXT_D_BGA1-IC,H91A';
  pin
    'CGC_DUT_DETECT_N':
      PIN_NUMBER='(0,0,0,0,0,0,0,C70,0,0,0,0,0,0)';
      BIDIRECTIONAL='TRUE';
      INPUT_LOAD='(-0.01,0.01)';
      OUTPUT_LOAD='(1.0,-1.0)';
      PINUSE='BI';
    'CLKOUT_ITPXDPN':
      PIN_NUMBER='(A39,0,0,0,0,0,0,0,0,0,0,0,0,0)';
      BIDIRECTIONAL='TRUE';
      INPUT_LOAD='(-0.01,0.01)';
      OUTPUT_LOAD='(1.0,-1.0)';
      PINUSE='BI';
    'CLKOUT_ITPXDPP':
      PIN_NUMBER='(C39,0,0,0,0,0,0,0,0,0,0,0,0,0)';
      BIDIRECTIONAL='TRUE';
      INPUT_LOAD='(-0.01,0.01)';
      OUTPUT_LOAD='(1.0,-1.0)';
      PINUSE='BI';
    'CLKOUT_NSSCCAP0N':
      PIN_NUMBER='(A32,0,0,0,0,0,0,0,0,0,0,0,0,0)';
      BIDIRECTIONAL='TRUE';
      INPUT_LOAD='(-0.01,0.01)';
      OUTPUT_LOAD='(1.0,-1.0)';
      PINUSE='BI';
    'CLKOUT_NSSCCAP0P':
      PIN_NUMBER='(C32,0,0,0,0,0,0,0,0,0,0,0,0,0)';
      BIDIRECTIONAL='TRUE';
      INPUT_LOAD='(-0.01,0.01)';
      OUTPUT_LOAD='(1.0,-1.0)';
      PINUSE='BI';
    'CLKOUT_NSSCCAP1N':
      PIN_NUMBER='(B38,0,0,0,0,0,0,0,0,0,0,0,0,0)';
      BIDIRECTIONAL='TRUE';
      INPUT_LOAD='(-0.01,0.01)';
      OUTPUT_LOAD='(1.0,-1.0)';
      PINUSE='BI';
    'CLKOUT_NSSCCAP1P':
      PIN_NUMBER='(D38,0,0,0,0,0,0,0,0,0,0,0,0,0)';
      BIDIRECTIONAL='TRUE';
      INPUT_LOAD='(-0.01,0.01)';
      OUTPUT_LOAD='(1.0,-1.0)';
      PINUSE='BI';
    'CLKOUT_PLAT0N':
      PIN_NUMBER='(B29,0,0,0,0,0,0,0,0,0,0,0,0,0)';
      BIDIRECTIONAL='TRUE';
      INPUT_LOAD='(-0.01,0.01)';
      OUTPUT_LOAD='(1.0,-1.0)';
      PINUSE='BI';
    'CLKOUT_PLAT0P':
      PIN_NUMBER='(D29,0,0,0,0,0,0,0,0,0,0,0,0,0)';
      BIDIRECTIONAL='TRUE';
      INPUT_LOAD='(-0.01,0.01)';
      OUTPUT_LOAD='(1.0,-1.0)';
      PINUSE='BI';
    'CLKOUT_PLAT1N':
      PIN_NUMBER='(B40,0,0,0,0,0,0,0,0,0,0,0,0,0)';
      BIDIRECTIONAL='TRUE';
      INPUT_LOAD='(-0.01,0.01)';
      OUTPUT_LOAD='(1.0,-1.0)';
      PINUSE='BI';
    'CLKOUT_PLAT1P':
      PIN_NUMBER='(D40,0,0,0,0,0,0,0,0,0,0,0,0,0)';
      BIDIRECTIONAL='TRUE';
      INPUT_LOAD='(-0.01,0.01)';
      OUTPUT_LOAD='(1.0,-1.0)';
      PINUSE='BI';
    'CLKOUT_SRCN'<15>:
      PIN_NUMBER='(K27,0,0,0,0,0,0,0,0,0,0,0,0,0)';
      BIDIRECTIONAL='TRUE';
      INPUT_LOAD='(-0.01,0.01)';
      OUTPUT_LOAD='(1.0,-1.0)';
      PINUSE='BI';
    'CLKOUT_SRCN'<14>:
      PIN_NUMBER='(C20,0,0,0,0,0,0,0,0,0,0,0,0,0)';
      BIDIRECTIONAL='TRUE';
      INPUT_LOAD='(-0.01,0.01)';
      OUTPUT_LOAD='(1.0,-1.0)';
      PINUSE='BI';
    'CLKOUT_SRCN'<13>:
      PIN_NUMBER='(C24,0,0,0,0,0,0,0,0,0,0,0,0,0)';
      BIDIRECTIONAL='TRUE';
      INPUT_LOAD='(-0.01,0.01)';
      OUTPUT_LOAD='(1.0,-1.0)';
      PINUSE='BI';
    'CLKOUT_SRCN'<12>:
      PIN_NUMBER='(K24,0,0,0,0,0,0,0,0,0,0,0,0,0)';
      BIDIRECTIONAL='TRUE';
      INPUT_LOAD='(-0.01,0.01)';
      OUTPUT_LOAD='(1.0,-1.0)';
      PINUSE='BI';
    'CLKOUT_SRCN'<11>:
      PIN_NUMBER='(B21,0,0,0,0,0,0,0,0,0,0,0,0,0)';
      BIDIRECTIONAL='TRUE';
      INPUT_LOAD='(-0.01,0.01)';
      OUTPUT_LOAD='(1.0,-1.0)';
      PINUSE='BI';
    'CLKOUT_SRCN'<10>:
      PIN_NUMBER='(B23,0,0,0,0,0,0,0,0,0,0,0,0,0)';
      BIDIRECTIONAL='TRUE';
      INPUT_LOAD='(-0.01,0.01)';
      OUTPUT_LOAD='(1.0,-1.0)';
      PINUSE='BI';
    'CLKOUT_SRCN'<9>:
      PIN_NUMBER='(J26,0,0,0,0,0,0,0,0,0,0,0,0,0)';
      BIDIRECTIONAL='TRUE';
      INPUT_LOAD='(-0.01,0.01)';
      OUTPUT_LOAD='(1.0,-1.0)';
      PINUSE='BI';
    'CLKOUT_SRCN'<8>:
      PIN_NUMBER='(D31,0,0,0,0,0,0,0,0,0,0,0,0,0)';
      BIDIRECTIONAL='TRUE';
      INPUT_LOAD='(-0.01,0.01)';
      OUTPUT_LOAD='(1.0,-1.0)';
      PINUSE='BI';
    'CLKOUT_SRCN'<7>:
      PIN_NUMBER='(H31,0,0,0,0,0,0,0,0,0,0,0,0,0)';
      BIDIRECTIONAL='TRUE';
      INPUT_LOAD='(-0.01,0.01)';
      OUTPUT_LOAD='(1.0,-1.0)';
      PINUSE='BI';
    'CLKOUT_SRCN'<6>:
      PIN_NUMBER='(D33,0,0,0,0,0,0,0,0,0,0,0,0,0)';
      BIDIRECTIONAL='TRUE';
      INPUT_LOAD='(-0.01,0.01)';
      OUTPUT_LOAD='(1.0,-1.0)';
      PINUSE='BI';
    'CLKOUT_SRCN'<5>:
      PIN_NUMBER='(J40,0,0,0,0,0,0,0,0,0,0,0,0,0)';
      BIDIRECTIONAL='TRUE';
      INPUT_LOAD='(-0.01,0.01)';
      OUTPUT_LOAD='(1.0,-1.0)';
      PINUSE='BI';
    'CLKOUT_SRCN'<4>:
      PIN_NUMBER='(A28,0,0,0,0,0,0,0,0,0,0,0,0,0)';
      BIDIRECTIONAL='TRUE';
      INPUT_LOAD='(-0.01,0.01)';
      OUTPUT_LOAD='(1.0,-1.0)';
      PINUSE='BI';
    'CLKOUT_SRCN'<3>:
      PIN_NUMBER='(K42,0,0,0,0,0,0,0,0,0,0,0,0,0)';
      BIDIRECTIONAL='TRUE';
      INPUT_LOAD='(-0.01,0.01)';
      OUTPUT_LOAD='(1.0,-1.0)';
      PINUSE='BI';
    'CLKOUT_SRCN'<2>:
      PIN_NUMBER='(J33,0,0,0,0,0,0,0,0,0,0,0,0,0)';
      BIDIRECTIONAL='TRUE';
      INPUT_LOAD='(-0.01,0.01)';
      OUTPUT_LOAD='(1.0,-1.0)';
      PINUSE='BI';
    'CLKOUT_SRCN'<1>:
      PIN_NUMBER='(K35,0,0,0,0,0,0,0,0,0,0,0,0,0)';
      BIDIRECTIONAL='TRUE';
      INPUT_LOAD='(-0.01,0.01)';
      OUTPUT_LOAD='(1.0,-1.0)';
      PINUSE='BI';
    'CLKOUT_SRCN'<0>:
      PIN_NUMBER='(K38,0,0,0,0,0,0,0,0,0,0,0,0,0)';
      BIDIRECTIONAL='TRUE';
      INPUT_LOAD='(-0.01,0.01)';
      OUTPUT_LOAD='(1.0,-1.0)';
      PINUSE='BI';
    'CLKOUT_SRCP'<15>:
      PIN_NUMBER='(H27,0,0,0,0,0,0,0,0,0,0,0,0,0)';
      BIDIRECTIONAL='TRUE';
      INPUT_LOAD='(-0.01,0.01)';
      OUTPUT_LOAD='(1.0,-1.0)';
      PINUSE='BI';
    'CLKOUT_SRCP'<14>:
      PIN_NUMBER='(A20,0,0,0,0,0,0,0,0,0,0,0,0,0)';
      BIDIRECTIONAL='TRUE';
      INPUT_LOAD='(-0.01,0.01)';
      OUTPUT_LOAD='(1.0,-1.0)';
      PINUSE='BI';
    'CLKOUT_SRCP'<13>:
      PIN_NUMBER='(A24,0,0,0,0,0,0,0,0,0,0,0,0,0)';
      BIDIRECTIONAL='TRUE';
      INPUT_LOAD='(-0.01,0.01)';
      OUTPUT_LOAD='(1.0,-1.0)';
      PINUSE='BI';
    'CLKOUT_SRCP'<12>:
      PIN_NUMBER='(H24,0,0,0,0,0,0,0,0,0,0,0,0,0)';
      BIDIRECTIONAL='TRUE';
      INPUT_LOAD='(-0.01,0.01)';
      OUTPUT_LOAD='(1.0,-1.0)';
      PINUSE='BI';
    'CLKOUT_SRCP'<11>:
      PIN_NUMBER='(D21,0,0,0,0,0,0,0,0,0,0,0,0,0)';
      BIDIRECTIONAL='TRUE';
      INPUT_LOAD='(-0.01,0.01)';
      OUTPUT_LOAD='(1.0,-1.0)';
      PINUSE='BI';
    'CLKOUT_SRCP'<10>:
      PIN_NUMBER='(D23,0,0,0,0,0,0,0,0,0,0,0,0,0)';
      BIDIRECTIONAL='TRUE';
      INPUT_LOAD='(-0.01,0.01)';
      OUTPUT_LOAD='(1.0,-1.0)';
      PINUSE='BI';
    'CLKOUT_SRCP'<9>:
      PIN_NUMBER='(G26,0,0,0,0,0,0,0,0,0,0,0,0,0)';
      BIDIRECTIONAL='TRUE';
      INPUT_LOAD='(-0.01,0.01)';
      OUTPUT_LOAD='(1.0,-1.0)';
      PINUSE='BI';
    'CLKOUT_SRCP'<8>:
      PIN_NUMBER='(B31,0,0,0,0,0,0,0,0,0,0,0,0,0)';
      BIDIRECTIONAL='TRUE';
      INPUT_LOAD='(-0.01,0.01)';
      OUTPUT_LOAD='(1.0,-1.0)';
      PINUSE='BI';
    'CLKOUT_SRCP'<7>:
      PIN_NUMBER='(K31,0,0,0,0,0,0,0,0,0,0,0,0,0)';
      BIDIRECTIONAL='TRUE';
      INPUT_LOAD='(-0.01,0.01)';
      OUTPUT_LOAD='(1.0,-1.0)';
      PINUSE='BI';
    'CLKOUT_SRCP'<6>:
      PIN_NUMBER='(B33,0,0,0,0,0,0,0,0,0,0,0,0,0)';
      BIDIRECTIONAL='TRUE';
      INPUT_LOAD='(-0.01,0.01)';
      OUTPUT_LOAD='(1.0,-1.0)';
      PINUSE='BI';
    'CLKOUT_SRCP'<5>:
      PIN_NUMBER='(G40,0,0,0,0,0,0,0,0,0,0,0,0,0)';
      BIDIRECTIONAL='TRUE';
      INPUT_LOAD='(-0.01,0.01)';
      OUTPUT_LOAD='(1.0,-1.0)';
      PINUSE='BI';
    'CLKOUT_SRCP'<4>:
      PIN_NUMBER='(C28,0,0,0,0,0,0,0,0,0,0,0,0,0)';
      BIDIRECTIONAL='TRUE';
      INPUT_LOAD='(-0.01,0.01)';
      OUTPUT_LOAD='(1.0,-1.0)';
      PINUSE='BI';
    'CLKOUT_SRCP'<3>:
      PIN_NUMBER='(H42,0,0,0,0,0,0,0,0,0,0,0,0,0)';
      BIDIRECTIONAL='TRUE';
      INPUT_LOAD='(-0.01,0.01)';
      OUTPUT_LOAD='(1.0,-1.0)';
      PINUSE='BI';
    'CLKOUT_SRCP'<2>:
      PIN_NUMBER='(G33,0,0,0,0,0,0,0,0,0,0,0,0,0)';
      BIDIRECTIONAL='TRUE';
      INPUT_LOAD='(-0.01,0.01)';
      OUTPUT_LOAD='(1.0,-1.0)';
      PINUSE='BI';
    'CLKOUT_SRCP'<1>:
      PIN_NUMBER='(H35,0,0,0,0,0,0,0,0,0,0,0,0,0)';
      BIDIRECTIONAL='TRUE';
      INPUT_LOAD='(-0.01,0.01)';
      OUTPUT_LOAD='(1.0,-1.0)';
      PINUSE='BI';
    'CLKOUT_SRCP'<0>:
      PIN_NUMBER='(H38,0,0,0,0,0,0,0,0,0,0,0,0,0)';
      BIDIRECTIONAL='TRUE';
      INPUT_LOAD='(-0.01,0.01)';
      OUTPUT_LOAD='(1.0,-1.0)';
      PINUSE='BI';
    'CLOCKSE_BMCCLK':
      PIN_NUMBER='(BW50,0,0,0,0,0,0,0,0,0,0,0,0,0)';
      BIDIRECTIONAL='TRUE';
      INPUT_LOAD='(-0.01,0.01)';
      OUTPUT_LOAD='(1.0,-1.0)';
      PINUSE='BI';
    'CLOCKSE_PMSYNCCLK1':
      PIN_NUMBER='(BY51,0,0,0,0,0,0,0,0,0,0,0,0,0)';
      BIDIRECTIONAL='TRUE';
      INPUT_LOAD='(-0.01,0.01)';
      OUTPUT_LOAD='(1.0,-1.0)';
      PINUSE='BI';
    'CLOCKSE_PMSYNCCLK2':
      PIN_NUMBER='(BV51,0,0,0,0,0,0,0,0,0,0,0,0,0)';
      BIDIRECTIONAL='TRUE';
      INPUT_LOAD='(-0.01,0.01)';
      OUTPUT_LOAD='(1.0,-1.0)';
      PINUSE='BI';
    'CPU_TRST_N':
      PIN_NUMBER='(0,0,0,0,AT56,0,0,0,0,0,0,0,0,0)';
      BIDIRECTIONAL='TRUE';
      INPUT_LOAD='(-0.01,0.01)';
      OUTPUT_LOAD='(1.0,-1.0)';
      PINUSE='BI';
    'DMI_RXN'<3>:
      PIN_NUMBER='(0,0,0,C45,0,0,0,0,0,0,0,0,0,0)';
      BIDIRECTIONAL='TRUE';
      INPUT_LOAD='(-0.01,0.01)';
      OUTPUT_LOAD='(1.0,-1.0)';
      PINUSE='BI';
    'DMI_RXN'<2>:
      PIN_NUMBER='(0,0,0,D44,0,0,0,0,0,0,0,0,0,0)';
      BIDIRECTIONAL='TRUE';
      INPUT_LOAD='(-0.01,0.01)';
      OUTPUT_LOAD='(1.0,-1.0)';
      PINUSE='BI';
    'DMI_RXN'<1>:
      PIN_NUMBER='(0,0,0,C43,0,0,0,0,0,0,0,0,0,0)';
      BIDIRECTIONAL='TRUE';
      INPUT_LOAD='(-0.01,0.01)';
      OUTPUT_LOAD='(1.0,-1.0)';
      PINUSE='BI';
    'DMI_RXN'<0>:
      PIN_NUMBER='(0,0,0,D42,0,0,0,0,0,0,0,0,0,0)';
      BIDIRECTIONAL='TRUE';
      INPUT_LOAD='(-0.01,0.01)';
      OUTPUT_LOAD='(1.0,-1.0)';
      PINUSE='BI';
    'DMI_RXP'<3>:
      PIN_NUMBER='(0,0,0,A45,0,0,0,0,0,0,0,0,0,0)';
      BIDIRECTIONAL='TRUE';
      INPUT_LOAD='(-0.01,0.01)';
      OUTPUT_LOAD='(1.0,-1.0)';
      PINUSE='BI';
    'DMI_RXP'<2>:
      PIN_NUMBER='(0,0,0,B44,0,0,0,0,0,0,0,0,0,0)';
      BIDIRECTIONAL='TRUE';
      INPUT_LOAD='(-0.01,0.01)';
      OUTPUT_LOAD='(1.0,-1.0)';
      PINUSE='BI';
    'DMI_RXP'<1>:
      PIN_NUMBER='(0,0,0,A43,0,0,0,0,0,0,0,0,0,0)';
      BIDIRECTIONAL='TRUE';
      INPUT_LOAD='(-0.01,0.01)';
      OUTPUT_LOAD='(1.0,-1.0)';
      PINUSE='BI';
    'DMI_RXP'<0>:
      PIN_NUMBER='(0,0,0,B42,0,0,0,0,0,0,0,0,0,0)';
      BIDIRECTIONAL='TRUE';
      INPUT_LOAD='(-0.01,0.01)';
      OUTPUT_LOAD='(1.0,-1.0)';
      PINUSE='BI';
    'DMI_TXN'<3>:
      PIN_NUMBER='(0,0,0,P52,0,0,0,0,0,0,0,0,0,0)';
      BIDIRECTIONAL='TRUE';
      INPUT_LOAD='(-0.01,0.01)';
      OUTPUT_LOAD='(1.0,-1.0)';
      PINUSE='BI';
    'DMI_TXN'<2>:
      PIN_NUMBER='(0,0,0,K50,0,0,0,0,0,0,0,0,0,0)';
      BIDIRECTIONAL='TRUE';
      INPUT_LOAD='(-0.01,0.01)';
      OUTPUT_LOAD='(1.0,-1.0)';
      PINUSE='BI';
    'DMI_TXN'<1>:
      PIN_NUMBER='(0,0,0,J48,0,0,0,0,0,0,0,0,0,0)';
      BIDIRECTIONAL='TRUE';
      INPUT_LOAD='(-0.01,0.01)';
      OUTPUT_LOAD='(1.0,-1.0)';
      PINUSE='BI';
    'DMI_TXN'<0>:
      PIN_NUMBER='(0,0,0,H46,0,0,0,0,0,0,0,0,0,0)';
      BIDIRECTIONAL='TRUE';
      INPUT_LOAD='(-0.01,0.01)';
      OUTPUT_LOAD='(1.0,-1.0)';
      PINUSE='BI';
    'DMI_TXP'<3>:
      PIN_NUMBER='(0,0,0,N54,0,0,0,0,0,0,0,0,0,0)';
      BIDIRECTIONAL='TRUE';
      INPUT_LOAD='(-0.01,0.01)';
      OUTPUT_LOAD='(1.0,-1.0)';
      PINUSE='BI';
    'DMI_TXP'<2>:
      PIN_NUMBER='(0,0,0,M52,0,0,0,0,0,0,0,0,0,0)';
      BIDIRECTIONAL='TRUE';
      INPUT_LOAD='(-0.01,0.01)';
      OUTPUT_LOAD='(1.0,-1.0)';
      PINUSE='BI';
    'DMI_TXP'<1>:
      PIN_NUMBER='(0,0,0,H50,0,0,0,0,0,0,0,0,0,0)';
      BIDIRECTIONAL='TRUE';
      INPUT_LOAD='(-0.01,0.01)';
      OUTPUT_LOAD='(1.0,-1.0)';
      PINUSE='BI';
    'DMI_TXP'<0>:
      PIN_NUMBER='(0,0,0,K46,0,0,0,0,0,0,0,0,0,0)';
      BIDIRECTIONAL='TRUE';
      INPUT_LOAD='(-0.01,0.01)';
      OUTPUT_LOAD='(1.0,-1.0)';
      PINUSE='BI';
    'DSW_PWROK':
      PIN_NUMBER='(0,0,0,0,K13,0,0,0,0,0,0,0,0,0)';
      BIDIRECTIONAL='TRUE';
      INPUT_LOAD='(-0.01,0.01)';
      OUTPUT_LOAD='(1.0,-1.0)';
      PINUSE='BI';
    'EXTCLKN':
      PIN_NUMBER='(0,0,D66,0,0,0,0,0,0,0,0,0,0,0)';
      BIDIRECTIONAL='TRUE';
      INPUT_LOAD='(-0.01,0.01)';
      OUTPUT_LOAD='(1.0,-1.0)';
      PINUSE='BI';
    'EXTCLKP':
      PIN_NUMBER='(0,0,E67,0,0,0,0,0,0,0,0,0,0,0)';
      BIDIRECTIONAL='TRUE';
      INPUT_LOAD='(-0.01,0.01)';
      OUTPUT_LOAD='(1.0,-1.0)';
      PINUSE='BI';
    'GPD0':
      PIN_NUMBER='(0,0,0,0,G15,0,0,0,0,0,0,0,0,0)';
      BIDIRECTIONAL='TRUE';
      INPUT_LOAD='(-0.01,0.01)';
      OUTPUT_LOAD='(1.0,-1.0)';
      PINUSE='BI';
    'GPD10_SLP_S5_N':
      PIN_NUMBER='(0,0,0,0,B14,0,0,0,0,0,0,0,0,0)';
      BIDIRECTIONAL='TRUE';
      INPUT_LOAD='(-0.01,0.01)';
      OUTPUT_LOAD='(1.0,-1.0)';
      PINUSE='BI';
    'GPD11_GBEPHY':
      PIN_NUMBER='(0,0,0,0,A13,0,0,0,0,0,0,0,0,0)';
      BIDIRECTIONAL='TRUE';
      INPUT_LOAD='(-0.01,0.01)';
      OUTPUT_LOAD='(1.0,-1.0)';
      PINUSE='BI';
    'GPD1_ACPRESENT':
      PIN_NUMBER='(0,0,0,0,H13,0,0,0,0,0,0,0,0,0)';
      BIDIRECTIONAL='TRUE';
      INPUT_LOAD='(-0.01,0.01)';
      OUTPUT_LOAD='(1.0,-1.0)';
      PINUSE='BI';
    'GPD2_GBE_WAKE_N':
      PIN_NUMBER='(0,0,0,0,M11,0,0,0,0,0,0,0,0,0)';
      BIDIRECTIONAL='TRUE';
      INPUT_LOAD='(-0.01,0.01)';
      OUTPUT_LOAD='(1.0,-1.0)';
      PINUSE='BI';
    'GPD3_PWRBTN_N':
      PIN_NUMBER='(0,0,0,0,C15,0,0,0,0,0,0,0,0,0)';
      BIDIRECTIONAL='TRUE';
      INPUT_LOAD='(-0.01,0.01)';
      OUTPUT_LOAD='(1.0,-1.0)';
      PINUSE='BI';
    'GPD4_SLP_S3_N':
      PIN_NUMBER='(0,0,0,0,D14,0,0,0,0,0,0,0,0,0)';
      BIDIRECTIONAL='TRUE';
      INPUT_LOAD='(-0.01,0.01)';
      OUTPUT_LOAD='(1.0,-1.0)';
      PINUSE='BI';
    'GPD5_SLP_S4_N':
      PIN_NUMBER='(0,0,0,0,B16,0,0,0,0,0,0,0,0,0)';
      BIDIRECTIONAL='TRUE';
      INPUT_LOAD='(-0.01,0.01)';
      OUTPUT_LOAD='(1.0,-1.0)';
      PINUSE='BI';
    'GPD6_SLP_A_N':
      PIN_NUMBER='(0,0,0,0,G11,0,0,0,0,0,0,0,0,0)';
      BIDIRECTIONAL='TRUE';
      INPUT_LOAD='(-0.01,0.01)';
      OUTPUT_LOAD='(1.0,-1.0)';
      PINUSE='BI';
    'GPD7':
      PIN_NUMBER='(0,0,0,0,H9,0,0,0,0,0,0,0,0,0)';
      BIDIRECTIONAL='TRUE';
      INPUT_LOAD='(-0.01,0.01)';
      OUTPUT_LOAD='(1.0,-1.0)';
      PINUSE='BI';
    'GPD8_SUSCLK':
      PIN_NUMBER='(0,0,0,0,C13,0,0,0,0,0,0,0,0,0)';
      BIDIRECTIONAL='TRUE';
      INPUT_LOAD='(-0.01,0.01)';
      OUTPUT_LOAD='(1.0,-1.0)';
      PINUSE='BI';
    'GPD9':
      PIN_NUMBER='(0,0,0,0,A15,0,0,0,0,0,0,0,0,0)';
      BIDIRECTIONAL='TRUE';
      INPUT_LOAD='(-0.01,0.01)';
      OUTPUT_LOAD='(1.0,-1.0)';
      PINUSE='BI';
    'GPIO_RCOMP_1P8_3P3':
      PIN_NUMBER='(0,0,0,0,0,0,0,AM4,0,0,0,0,0,0)';
      BIDIRECTIONAL='TRUE';
      INPUT_LOAD='(-0.01,0.01)';
      OUTPUT_LOAD='(1.0,-1.0)';
      PINUSE='BI';
    'GPIO_RCOMP_3P3':
      PIN_NUMBER='(0,0,0,0,0,0,BY25,0,0,0,0,0,0,0)';
      BIDIRECTIONAL='TRUE';
      INPUT_LOAD='(-0.01,0.01)';
      OUTPUT_LOAD='(1.0,-1.0)';
      PINUSE='BI';
    'GPP_A0_RCIN_N_ESPI_ALERT1_N':
      PIN_NUMBER='(0,0,0,0,0,N3,0,0,0,0,0,0,0,0)';
      BIDIRECTIONAL='TRUE';
      INPUT_LOAD='(-0.01,0.01)';
      OUTPUT_LOAD='(1.0,-1.0)';
      PINUSE='BI';
    'GPP_A10_CLKOUT_LPC1':
      PIN_NUMBER='(0,0,0,0,0,AA4,0,0,0,0,0,0,0,0)';
      BIDIRECTIONAL='TRUE';
      INPUT_LOAD='(-0.01,0.01)';
      OUTPUT_LOAD='(1.0,-1.0)';
      PINUSE='BI';
    'GPP_A11_PME_N':
      PIN_NUMBER='(0,0,0,0,0,AC2,0,0,0,0,0,0,0,0)';
      BIDIRECTIONAL='TRUE';
      INPUT_LOAD='(-0.01,0.01)';
      OUTPUT_LOAD='(1.0,-1.0)';
      PINUSE='BI';
    'GPP_A12_BMBUSY_N_SXEXITHLDOFF_N':
      PIN_NUMBER='(0,0,0,0,0,R1,0,0,0,0,0,0,0,0)';
      BIDIRECTIONAL='TRUE';
      INPUT_LOAD='(-0.01,0.01)';
      OUTPUT_LOAD='(1.0,-1.0)';
      PINUSE='BI';
    'GPP_A13_SUSWARN_N_SUSPWRDNACK':
      PIN_NUMBER='(0,0,0,0,0,T4,0,0,0,0,0,0,0,0)';
      BIDIRECTIONAL='TRUE';
      INPUT_LOAD='(-0.01,0.01)';
      OUTPUT_LOAD='(1.0,-1.0)';
      PINUSE='BI';
    'GPP_A14_ESPI_RESET_N':
      PIN_NUMBER='(0,0,0,0,0,AB3,0,0,0,0,0,0,0,0)';
      BIDIRECTIONAL='TRUE';
      INPUT_LOAD='(-0.01,0.01)';
      OUTPUT_LOAD='(1.0,-1.0)';
      PINUSE='BI';
    'GPP_A15_SUSACK_N':
      PIN_NUMBER='(0,0,0,0,0,AC4,0,0,0,0,0,0,0,0)';
      BIDIRECTIONAL='TRUE';
      INPUT_LOAD='(-0.01,0.01)';
      OUTPUT_LOAD='(1.0,-1.0)';
      PINUSE='BI';
    'GPP_A16_CLKOUT_LPC2':
      PIN_NUMBER='(0,0,0,0,0,T2,0,0,0,0,0,0,0,0)';
      BIDIRECTIONAL='TRUE';
      INPUT_LOAD='(-0.01,0.01)';
      OUTPUT_LOAD='(1.0,-1.0)';
      PINUSE='BI';
    'GPP_A17':
      PIN_NUMBER='(0,0,0,0,0,AD1,0,0,0,0,0,0,0,0)';
      BIDIRECTIONAL='TRUE';
      INPUT_LOAD='(-0.01,0.01)';
      OUTPUT_LOAD='(1.0,-1.0)';
      PINUSE='BI';
    'GPP_A18':
      PIN_NUMBER='(0,0,0,0,0,AD3,0,0,0,0,0,0,0,0)';
      BIDIRECTIONAL='TRUE';
      INPUT_LOAD='(-0.01,0.01)';
      OUTPUT_LOAD='(1.0,-1.0)';
      PINUSE='BI';
    'GPP_A19':
      PIN_NUMBER='(0,0,0,0,0,V3,0,0,0,0,0,0,0,0)';
      BIDIRECTIONAL='TRUE';
      INPUT_LOAD='(-0.01,0.01)';
      OUTPUT_LOAD='(1.0,-1.0)';
      PINUSE='BI';
    'GPP_A1_LAD0_ESPI_IO0':
      PIN_NUMBER='(0,0,0,0,0,Y3,0,0,0,0,0,0,0,0)';
      BIDIRECTIONAL='TRUE';
      INPUT_LOAD='(-0.01,0.01)';
      OUTPUT_LOAD='(1.0,-1.0)';
      PINUSE='BI';
    'GPP_A20':
      PIN_NUMBER='(0,0,0,0,0,W4,0,0,0,0,0,0,0,0)';
      BIDIRECTIONAL='TRUE';
      INPUT_LOAD='(-0.01,0.01)';
      OUTPUT_LOAD='(1.0,-1.0)';
      PINUSE='BI';
    'GPP_A21':
      PIN_NUMBER='(0,0,0,0,0,AE2,0,0,0,0,0,0,0,0)';
      BIDIRECTIONAL='TRUE';
      INPUT_LOAD='(-0.01,0.01)';
      OUTPUT_LOAD='(1.0,-1.0)';
      PINUSE='BI';
    'GPP_A22':
      PIN_NUMBER='(0,0,0,0,0,AE4,0,0,0,0,0,0,0,0)';
      BIDIRECTIONAL='TRUE';
      INPUT_LOAD='(-0.01,0.01)';
      OUTPUT_LOAD='(1.0,-1.0)';
      PINUSE='BI';
    'GPP_A23':
      PIN_NUMBER='(0,0,0,0,0,V1,0,0,0,0,0,0,0,0)';
      BIDIRECTIONAL='TRUE';
      INPUT_LOAD='(-0.01,0.01)';
      OUTPUT_LOAD='(1.0,-1.0)';
      PINUSE='BI';
    'GPP_A2_LAD1_ESPI_IO1':
      PIN_NUMBER='(0,0,0,0,0,N1,0,0,0,0,0,0,0,0)';
      BIDIRECTIONAL='TRUE';
      INPUT_LOAD='(-0.01,0.01)';
      OUTPUT_LOAD='(1.0,-1.0)';
      PINUSE='BI';
    'GPP_A3_LAD2_ESPI_IO2':
      PIN_NUMBER='(0,0,0,0,0,W2,0,0,0,0,0,0,0,0)';
      BIDIRECTIONAL='TRUE';
      INPUT_LOAD='(-0.01,0.01)';
      OUTPUT_LOAD='(1.0,-1.0)';
      PINUSE='BI';
    'GPP_A4_LAD3_ESPI_IO3':
      PIN_NUMBER='(0,0,0,0,0,Y1,0,0,0,0,0,0,0,0)';
      BIDIRECTIONAL='TRUE';
      INPUT_LOAD='(-0.01,0.01)';
      OUTPUT_LOAD='(1.0,-1.0)';
      PINUSE='BI';
    'GPP_A5_LFRAME_N_ESPI_CS0_N':
      PIN_NUMBER='(0,0,0,0,0,P4,0,0,0,0,0,0,0,0)';
      BIDIRECTIONAL='TRUE';
      INPUT_LOAD='(-0.01,0.01)';
      OUTPUT_LOAD='(1.0,-1.0)';
      PINUSE='BI';
    'GPP_A6_SERIRQ_ESPI_CS1_N':
      PIN_NUMBER='(0,0,0,0,0,P2,0,0,0,0,0,0,0,0)';
      BIDIRECTIONAL='TRUE';
      INPUT_LOAD='(-0.01,0.01)';
      OUTPUT_LOAD='(1.0,-1.0)';
      PINUSE='BI';
    'GPP_A7_PIRQA_N_ESPI_ALERT0_N':
      PIN_NUMBER='(0,0,0,0,0,AA2,0,0,0,0,0,0,0,0)';
      BIDIRECTIONAL='TRUE';
      INPUT_LOAD='(-0.01,0.01)';
      OUTPUT_LOAD='(1.0,-1.0)';
      PINUSE='BI';
    'GPP_A8_CLKRUN_N':
      PIN_NUMBER='(0,0,0,0,0,AB1,0,0,0,0,0,0,0,0)';
      BIDIRECTIONAL='TRUE';
      INPUT_LOAD='(-0.01,0.01)';
      OUTPUT_LOAD='(1.0,-1.0)';
      PINUSE='BI';
    'GPP_A9_CLKOUT_LPC0_ESPI_CLK':
      PIN_NUMBER='(0,0,0,0,0,R3,0,0,0,0,0,0,0,0)';
      BIDIRECTIONAL='TRUE';
      INPUT_LOAD='(-0.01,0.01)';
      OUTPUT_LOAD='(1.0,-1.0)';
      PINUSE='BI';
    'GPP_B0_CORE_VID0':
      PIN_NUMBER='(0,0,0,0,0,BL7,0,0,0,0,0,0,0,0)';
      BIDIRECTIONAL='TRUE';
      INPUT_LOAD='(-0.01,0.01)';
      OUTPUT_LOAD='(1.0,-1.0)';
      PINUSE='BI';
    'GPP_B10_SRCCLKREQ5_N':
      PIN_NUMBER='(0,0,0,0,0,BL11,0,0,0,0,0,0,0,0)';
      BIDIRECTIONAL='TRUE';
      INPUT_LOAD='(-0.01,0.01)';
      OUTPUT_LOAD='(1.0,-1.0)';
      PINUSE='BI';
    'GPP_B11':
      PIN_NUMBER='(0,0,0,0,0,BK9,0,0,0,0,0,0,0,0)';
      BIDIRECTIONAL='TRUE';
      INPUT_LOAD='(-0.01,0.01)';
      OUTPUT_LOAD='(1.0,-1.0)';
      PINUSE='BI';
    'GPP_B12_GLB_RST_WARN_N':
      PIN_NUMBER='(0,0,0,0,0,BL18,0,0,0,0,0,0,0,0)';
      BIDIRECTIONAL='TRUE';
      INPUT_LOAD='(-0.01,0.01)';
      OUTPUT_LOAD='(1.0,-1.0)';
      PINUSE='BI';
    'GPP_B13_PLTRST_N':
      PIN_NUMBER='(0,0,0,0,0,BN18,0,0,0,0,0,0,0,0)';
      BIDIRECTIONAL='TRUE';
      INPUT_LOAD='(-0.01,0.01)';
      OUTPUT_LOAD='(1.0,-1.0)';
      PINUSE='BI';
    'GPP_B14_SPKR':
      PIN_NUMBER='(0,0,0,0,0,BH13,0,0,0,0,0,0,0,0)';
      BIDIRECTIONAL='TRUE';
      INPUT_LOAD='(-0.01,0.01)';
      OUTPUT_LOAD='(1.0,-1.0)';
      PINUSE='BI';
    'GPP_B15':
      PIN_NUMBER='(0,0,0,0,0,BK13,0,0,0,0,0,0,0,0)';
      BIDIRECTIONAL='TRUE';
      INPUT_LOAD='(-0.01,0.01)';
      OUTPUT_LOAD='(1.0,-1.0)';
      PINUSE='BI';
    'GPP_B16':
      PIN_NUMBER='(0,0,0,0,0,BG22,0,0,0,0,0,0,0,0)';
      BIDIRECTIONAL='TRUE';
      INPUT_LOAD='(-0.01,0.01)';
      OUTPUT_LOAD='(1.0,-1.0)';
      PINUSE='BI';
    'GPP_B17':
      PIN_NUMBER='(0,0,0,0,0,BG15,0,0,0,0,0,0,0,0)';
      BIDIRECTIONAL='TRUE';
      INPUT_LOAD='(-0.01,0.01)';
      OUTPUT_LOAD='(1.0,-1.0)';
      PINUSE='BI';
    'GPP_B18':
      PIN_NUMBER='(0,0,0,0,0,BL15,0,0,0,0,0,0,0,0)';
      BIDIRECTIONAL='TRUE';
      INPUT_LOAD='(-0.01,0.01)';
      OUTPUT_LOAD='(1.0,-1.0)';
      PINUSE='BI';
    'GPP_B19':
      PIN_NUMBER='(0,0,0,0,0,BK20,0,0,0,0,0,0,0,0)';
      BIDIRECTIONAL='TRUE';
      INPUT_LOAD='(-0.01,0.01)';
      OUTPUT_LOAD='(1.0,-1.0)';
      PINUSE='BI';
    'GPP_B1_CORE_VID1':
      PIN_NUMBER='(0,0,0,0,0,BH9,0,0,0,0,0,0,0,0)';
      BIDIRECTIONAL='TRUE';
      INPUT_LOAD='(-0.01,0.01)';
      OUTPUT_LOAD='(1.0,-1.0)';
      PINUSE='BI';
    'GPP_B2':
      PIN_NUMBER='(0,0,0,0,0,BN15,0,0,0,0,0,0,0,0)';
      BIDIRECTIONAL='TRUE';
      INPUT_LOAD='(-0.01,0.01)';
      OUTPUT_LOAD='(1.0,-1.0)';
      PINUSE='BI';
    'GPP_B20':
      PIN_NUMBER='(0,0,0,0,0,BJ22,0,0,0,0,0,0,0,0)';
      BIDIRECTIONAL='TRUE';
      INPUT_LOAD='(-0.01,0.01)';
      OUTPUT_LOAD='(1.0,-1.0)';
      PINUSE='BI';
    'GPP_B21':
      PIN_NUMBER='(0,0,0,0,0,BH17,0,0,0,0,0,0,0,0)';
      BIDIRECTIONAL='TRUE';
      INPUT_LOAD='(-0.01,0.01)';
      OUTPUT_LOAD='(1.0,-1.0)';
      PINUSE='BI';
    'GPP_B22':
      PIN_NUMBER='(0,0,0,0,0,BR17,0,0,0,0,0,0,0,0)';
      BIDIRECTIONAL='TRUE';
      INPUT_LOAD='(-0.01,0.01)';
      OUTPUT_LOAD='(1.0,-1.0)';
      PINUSE='BI';
    'GPP_B23_MEIE_SML1ALRT_N_PHOT_N':
      PIN_NUMBER='(0,0,0,0,0,BM20,0,0,0,0,0,0,0,0)';
      BIDIRECTIONAL='TRUE';
      INPUT_LOAD='(-0.01,0.01)';
      OUTPUT_LOAD='(1.0,-1.0)';
      PINUSE='BI';
    'GPP_B3_CPU_GP2':
      PIN_NUMBER='(0,0,0,0,0,BR9,0,0,0,0,0,0,0,0)';
      BIDIRECTIONAL='TRUE';
      INPUT_LOAD='(-0.01,0.01)';
      OUTPUT_LOAD='(1.0,-1.0)';
      PINUSE='BI';
    'GPP_B4_CPU_GP3':
      PIN_NUMBER='(0,0,0,0,0,BN7,0,0,0,0,0,0,0,0)';
      BIDIRECTIONAL='TRUE';
      INPUT_LOAD='(-0.01,0.01)';
      OUTPUT_LOAD='(1.0,-1.0)';
      PINUSE='BI';
    'GPP_B5_SRCCLKREQ0_N':
      PIN_NUMBER='(0,0,0,0,0,BK17,0,0,0,0,0,0,0,0)';
      BIDIRECTIONAL='TRUE';
      INPUT_LOAD='(-0.01,0.01)';
      OUTPUT_LOAD='(1.0,-1.0)';
      PINUSE='BI';
    'GPP_B6_SRCCLKREQ1_N':
      PIN_NUMBER='(0,0,0,0,0,BG18,0,0,0,0,0,0,0,0)';
      BIDIRECTIONAL='TRUE';
      INPUT_LOAD='(-0.01,0.01)';
      OUTPUT_LOAD='(1.0,-1.0)';
      PINUSE='BI';
    'GPP_B7_SRCCLKREQ2_N':
      PIN_NUMBER='(0,0,0,0,0,BR13,0,0,0,0,0,0,0,0)';
      BIDIRECTIONAL='TRUE';
      INPUT_LOAD='(-0.01,0.01)';
      OUTPUT_LOAD='(1.0,-1.0)';
      PINUSE='BI';
    'GPP_B8_SRCCLKREQ3_N':
      PIN_NUMBER='(0,0,0,0,0,BN11,0,0,0,0,0,0,0,0)';
      BIDIRECTIONAL='TRUE';
      INPUT_LOAD='(-0.01,0.01)';
      OUTPUT_LOAD='(1.0,-1.0)';
      PINUSE='BI';
    'GPP_B9_SRCCLKREQ4_N':
      PIN_NUMBER='(0,0,0,0,0,BH20,0,0,0,0,0,0,0,0)';
      BIDIRECTIONAL='TRUE';
      INPUT_LOAD='(-0.01,0.01)';
      OUTPUT_LOAD='(1.0,-1.0)';
      PINUSE='BI';
    'GPP_C0_SMBCLK':
      PIN_NUMBER='(0,0,0,0,0,BW28,0,0,0,0,0,0,0,0)';
      BIDIRECTIONAL='TRUE';
      INPUT_LOAD='(-0.01,0.01)';
      OUTPUT_LOAD='(1.0,-1.0)';
      PINUSE='BI';
    'GPP_C10':
      PIN_NUMBER='(0,0,0,0,0,BV31,0,0,0,0,0,0,0,0)';
      BIDIRECTIONAL='TRUE';
      INPUT_LOAD='(-0.01,0.01)';
      OUTPUT_LOAD='(1.0,-1.0)';
      PINUSE='BI';
    'GPP_C11':
      PIN_NUMBER='(0,0,0,0,0,BV33,0,0,0,0,0,0,0,0)';
      BIDIRECTIONAL='TRUE';
      INPUT_LOAD='(-0.01,0.01)';
      OUTPUT_LOAD='(1.0,-1.0)';
      PINUSE='BI';
    'GPP_C12':
      PIN_NUMBER='(0,0,0,0,0,CA30,0,0,0,0,0,0,0,0)';
      BIDIRECTIONAL='TRUE';
      INPUT_LOAD='(-0.01,0.01)';
      OUTPUT_LOAD='(1.0,-1.0)';
      PINUSE='BI';
    'GPP_C13':
      PIN_NUMBER='(0,0,0,0,0,BV38,0,0,0,0,0,0,0,0)';
      BIDIRECTIONAL='TRUE';
      INPUT_LOAD='(-0.01,0.01)';
      OUTPUT_LOAD='(1.0,-1.0)';
      PINUSE='BI';
    'GPP_C14':
      PIN_NUMBER='(0,0,0,0,0,BY38,0,0,0,0,0,0,0,0)';
      BIDIRECTIONAL='TRUE';
      INPUT_LOAD='(-0.01,0.01)';
      OUTPUT_LOAD='(1.0,-1.0)';
      PINUSE='BI';
    'GPP_C15':
      PIN_NUMBER='(0,0,0,0,0,CA32,0,0,0,0,0,0,0,0)';
      BIDIRECTIONAL='TRUE';
      INPUT_LOAD='(-0.01,0.01)';
      OUTPUT_LOAD='(1.0,-1.0)';
      PINUSE='BI';
    'GPP_C16':
      PIN_NUMBER='(0,0,0,0,0,BW37,0,0,0,0,0,0,0,0)';
      BIDIRECTIONAL='TRUE';
      INPUT_LOAD='(-0.01,0.01)';
      OUTPUT_LOAD='(1.0,-1.0)';
      PINUSE='BI';
    'GPP_C17':
      PIN_NUMBER='(0,0,0,0,0,BY31,0,0,0,0,0,0,0,0)';
      BIDIRECTIONAL='TRUE';
      INPUT_LOAD='(-0.01,0.01)';
      OUTPUT_LOAD='(1.0,-1.0)';
      PINUSE='BI';
    'GPP_C18':
      PIN_NUMBER='(0,0,0,0,0,BY35,0,0,0,0,0,0,0,0)';
      BIDIRECTIONAL='TRUE';
      INPUT_LOAD='(-0.01,0.01)';
      OUTPUT_LOAD='(1.0,-1.0)';
      PINUSE='BI';
    'GPP_C19':
      PIN_NUMBER='(0,0,0,0,0,BW39,0,0,0,0,0,0,0,0)';
      BIDIRECTIONAL='TRUE';
      INPUT_LOAD='(-0.01,0.01)';
      OUTPUT_LOAD='(1.0,-1.0)';
      PINUSE='BI';
    'GPP_C1_SMBDATA':
      PIN_NUMBER='(0,0,0,0,0,BV27,0,0,0,0,0,0,0,0)';
      BIDIRECTIONAL='TRUE';
      INPUT_LOAD='(-0.01,0.01)';
      OUTPUT_LOAD='(1.0,-1.0)';
      PINUSE='BI';
    'GPP_C20':
      PIN_NUMBER='(0,0,0,0,0,CA39,0,0,0,0,0,0,0,0)';
      BIDIRECTIONAL='TRUE';
      INPUT_LOAD='(-0.01,0.01)';
      OUTPUT_LOAD='(1.0,-1.0)';
      PINUSE='BI';
    'GPP_C21':
      PIN_NUMBER='(0,0,0,0,0,BY33,0,0,0,0,0,0,0,0)';
      BIDIRECTIONAL='TRUE';
      INPUT_LOAD='(-0.01,0.01)';
      OUTPUT_LOAD='(1.0,-1.0)';
      PINUSE='BI';
    'GPP_C22':
      PIN_NUMBER='(0,0,0,0,0,CA34,0,0,0,0,0,0,0,0)';
      BIDIRECTIONAL='TRUE';
      INPUT_LOAD='(-0.01,0.01)';
      OUTPUT_LOAD='(1.0,-1.0)';
      PINUSE='BI';
    'GPP_C23':
      PIN_NUMBER='(0,0,0,0,0,CA37,0,0,0,0,0,0,0,0)';
      BIDIRECTIONAL='TRUE';
      INPUT_LOAD='(-0.01,0.01)';
      OUTPUT_LOAD='(1.0,-1.0)';
      PINUSE='BI';
    'GPP_C2_SMBALERT_N':
      PIN_NUMBER='(0,0,0,0,0,BY27,0,0,0,0,0,0,0,0)';
      BIDIRECTIONAL='TRUE';
      INPUT_LOAD='(-0.01,0.01)';
      OUTPUT_LOAD='(1.0,-1.0)';
      PINUSE='BI';
    'GPP_C3_SML0CLK_IE':
      PIN_NUMBER='(0,0,0,0,0,BV29,0,0,0,0,0,0,0,0)';
      BIDIRECTIONAL='TRUE';
      INPUT_LOAD='(-0.01,0.01)';
      OUTPUT_LOAD='(1.0,-1.0)';
      PINUSE='BI';
    'GPP_C4_SML0DATA_IE':
      PIN_NUMBER='(0,0,0,0,0,BW30,0,0,0,0,0,0,0,0)';
      BIDIRECTIONAL='TRUE';
      INPUT_LOAD='(-0.01,0.01)';
      OUTPUT_LOAD='(1.0,-1.0)';
      PINUSE='BI';
    'GPP_C5_SML0ALERT_IE_N':
      PIN_NUMBER='(0,0,0,0,0,BW34,0,0,0,0,0,0,0,0)';
      BIDIRECTIONAL='TRUE';
      INPUT_LOAD='(-0.01,0.01)';
      OUTPUT_LOAD='(1.0,-1.0)';
      PINUSE='BI';
    'GPP_C6_SML1CLK_IE':
      PIN_NUMBER='(0,0,0,0,0,CA28,0,0,0,0,0,0,0,0)';
      BIDIRECTIONAL='TRUE';
      INPUT_LOAD='(-0.01,0.01)';
      OUTPUT_LOAD='(1.0,-1.0)';
      PINUSE='BI';
    'GPP_C7_SML1DATA_IE':
      PIN_NUMBER='(0,0,0,0,0,BV35,0,0,0,0,0,0,0,0)';
      BIDIRECTIONAL='TRUE';
      INPUT_LOAD='(-0.01,0.01)';
      OUTPUT_LOAD='(1.0,-1.0)';
      PINUSE='BI';
    'GPP_C8':
      PIN_NUMBER='(0,0,0,0,0,BW32,0,0,0,0,0,0,0,0)';
      BIDIRECTIONAL='TRUE';
      INPUT_LOAD='(-0.01,0.01)';
      OUTPUT_LOAD='(1.0,-1.0)';
      PINUSE='BI';
    'GPP_C9':
      PIN_NUMBER='(0,0,0,0,0,BY29,0,0,0,0,0,0,0,0)';
      BIDIRECTIONAL='TRUE';
      INPUT_LOAD='(-0.01,0.01)';
      OUTPUT_LOAD='(1.0,-1.0)';
      PINUSE='BI';
    'GPP_D0':
      PIN_NUMBER='(0,0,0,0,0,BR42,0,0,0,0,0,0,0,0)';
      BIDIRECTIONAL='TRUE';
      INPUT_LOAD='(-0.01,0.01)';
      OUTPUT_LOAD='(1.0,-1.0)';
      PINUSE='BI';
    'GPP_D1':
      PIN_NUMBER='(0,0,0,0,0,BK46,0,0,0,0,0,0,0,0)';
      BIDIRECTIONAL='TRUE';
      INPUT_LOAD='(-0.01,0.01)';
      OUTPUT_LOAD='(1.0,-1.0)';
      PINUSE='BI';
    'GPP_D10_SSATA_DEVSLP4':
      PIN_NUMBER='(0,0,0,0,0,BV47,0,0,0,0,0,0,0,0)';
      BIDIRECTIONAL='TRUE';
      INPUT_LOAD='(-0.01,0.01)';
      OUTPUT_LOAD='(1.0,-1.0)';
      PINUSE='BI';
    'GPP_D11_SSATA_DEVSLP5':
      PIN_NUMBER='(0,0,0,0,0,BY47,0,0,0,0,0,0,0,0)';
      BIDIRECTIONAL='TRUE';
      INPUT_LOAD='(-0.01,0.01)';
      OUTPUT_LOAD='(1.0,-1.0)';
      PINUSE='BI';
    'GPP_D12_SSATA_SDATAOUT1':
      PIN_NUMBER='(0,0,0,0,0,BN40,0,0,0,0,0,0,0,0)';
      BIDIRECTIONAL='TRUE';
      INPUT_LOAD='(-0.01,0.01)';
      OUTPUT_LOAD='(1.0,-1.0)';
      PINUSE='BI';
    'GPP_D13_SML0BCLK_IE':
      PIN_NUMBER='(0,0,0,0,0,BY44,0,0,0,0,0,0,0,0)';
      BIDIRECTIONAL='TRUE';
      INPUT_LOAD='(-0.01,0.01)';
      OUTPUT_LOAD='(1.0,-1.0)';
      PINUSE='BI';
    'GPP_D14_SML0BDATA_IE':
      PIN_NUMBER='(0,0,0,0,0,BL44,0,0,0,0,0,0,0,0)';
      BIDIRECTIONAL='TRUE';
      INPUT_LOAD='(-0.01,0.01)';
      OUTPUT_LOAD='(1.0,-1.0)';
      PINUSE='BI';
    'GPP_D15_SSATA_SDATAOUT0':
      PIN_NUMBER='(0,0,0,0,0,BW43,0,0,0,0,0,0,0,0)';
      BIDIRECTIONAL='TRUE';
      INPUT_LOAD='(-0.01,0.01)';
      OUTPUT_LOAD='(1.0,-1.0)';
      PINUSE='BI';
    'GPP_D16_SML0BALERT_IE_N':
      PIN_NUMBER='(0,0,0,0,0,BV42,0,0,0,0,0,0,0,0)';
      BIDIRECTIONAL='TRUE';
      INPUT_LOAD='(-0.01,0.01)';
      OUTPUT_LOAD='(1.0,-1.0)';
      PINUSE='BI';
    'GPP_D17':
      PIN_NUMBER='(0,0,0,0,0,BW48,0,0,0,0,0,0,0,0)';
      BIDIRECTIONAL='TRUE';
      INPUT_LOAD='(-0.01,0.01)';
      OUTPUT_LOAD='(1.0,-1.0)';
      PINUSE='BI';
    'GPP_D18':
      PIN_NUMBER='(0,0,0,0,0,CA41,0,0,0,0,0,0,0,0)';
      BIDIRECTIONAL='TRUE';
      INPUT_LOAD='(-0.01,0.01)';
      OUTPUT_LOAD='(1.0,-1.0)';
      PINUSE='BI';
    'GPP_D19':
      PIN_NUMBER='(0,0,0,0,0,CA43,0,0,0,0,0,0,0,0)';
      BIDIRECTIONAL='TRUE';
      INPUT_LOAD='(-0.01,0.01)';
      OUTPUT_LOAD='(1.0,-1.0)';
      PINUSE='BI';
    'GPP_D2':
      PIN_NUMBER='(0,0,0,0,0,BJ44,0,0,0,0,0,0,0,0)';
      BIDIRECTIONAL='TRUE';
      INPUT_LOAD='(-0.01,0.01)';
      OUTPUT_LOAD='(1.0,-1.0)';
      PINUSE='BI';
    'GPP_D20':
      PIN_NUMBER='(0,0,0,0,0,CA48,0,0,0,0,0,0,0,0)';
      BIDIRECTIONAL='TRUE';
      INPUT_LOAD='(-0.01,0.01)';
      OUTPUT_LOAD='(1.0,-1.0)';
      PINUSE='BI';
    'GPP_D21_IE_UART_RX':
      PIN_NUMBER='(0,0,0,0,0,BV44,0,0,0,0,0,0,0,0)';
      BIDIRECTIONAL='TRUE';
      INPUT_LOAD='(-0.01,0.01)';
      OUTPUT_LOAD='(1.0,-1.0)';
      PINUSE='BI';
    'GPP_D22_IE_UART_TX':
      PIN_NUMBER='(0,0,0,0,0,BR46,0,0,0,0,0,0,0,0)';
      BIDIRECTIONAL='TRUE';
      INPUT_LOAD='(-0.01,0.01)';
      OUTPUT_LOAD='(1.0,-1.0)';
      PINUSE='BI';
    'GPP_D23':
      PIN_NUMBER='(0,0,0,0,0,BN44,0,0,0,0,0,0,0,0)';
      BIDIRECTIONAL='TRUE';
      INPUT_LOAD='(-0.01,0.01)';
      OUTPUT_LOAD='(1.0,-1.0)';
      PINUSE='BI';
    'GPP_D3':
      PIN_NUMBER='(0,0,0,0,0,BW45,0,0,0,0,0,0,0,0)';
      BIDIRECTIONAL='TRUE';
      INPUT_LOAD='(-0.01,0.01)';
      OUTPUT_LOAD='(1.0,-1.0)';
      PINUSE='BI';
    'GPP_D4':
      PIN_NUMBER='(0,0,0,0,0,BM42,0,0,0,0,0,0,0,0)';
      BIDIRECTIONAL='TRUE';
      INPUT_LOAD='(-0.01,0.01)';
      OUTPUT_LOAD='(1.0,-1.0)';
      PINUSE='BI';
    'GPP_D5':
      PIN_NUMBER='(0,0,0,0,0,BM38,0,0,0,0,0,0,0,0)';
      BIDIRECTIONAL='TRUE';
      INPUT_LOAD='(-0.01,0.01)';
      OUTPUT_LOAD='(1.0,-1.0)';
      PINUSE='BI';
    'GPP_D6':
      PIN_NUMBER='(0,0,0,0,0,BW41,0,0,0,0,0,0,0,0)';
      BIDIRECTIONAL='TRUE';
      INPUT_LOAD='(-0.01,0.01)';
      OUTPUT_LOAD='(1.0,-1.0)';
      PINUSE='BI';
    'GPP_D7':
      PIN_NUMBER='(0,0,0,0,0,CA45,0,0,0,0,0,0,0,0)';
      BIDIRECTIONAL='TRUE';
      INPUT_LOAD='(-0.01,0.01)';
      OUTPUT_LOAD='(1.0,-1.0)';
      PINUSE='BI';
    'GPP_D8':
      PIN_NUMBER='(0,0,0,0,0,BR38,0,0,0,0,0,0,0,0)';
      BIDIRECTIONAL='TRUE';
      INPUT_LOAD='(-0.01,0.01)';
      OUTPUT_LOAD='(1.0,-1.0)';
      PINUSE='BI';
    'GPP_D9_SSATA_DEVSLP3':
      PIN_NUMBER='(0,0,0,0,0,BY42,0,0,0,0,0,0,0,0)';
      BIDIRECTIONAL='TRUE';
      INPUT_LOAD='(-0.01,0.01)';
      OUTPUT_LOAD='(1.0,-1.0)';
      PINUSE='BI';
    'GPP_E0_SATAXPCIE0_SATAGP0':
      PIN_NUMBER='(0,0,0,0,0,0,BH50,0,0,0,0,0,0,0)';
      BIDIRECTIONAL='TRUE';
      INPUT_LOAD='(-0.01,0.01)';
      OUTPUT_LOAD='(1.0,-1.0)';
      PINUSE='BI';
    'GPP_E10_USB2_OC1_N':
      PIN_NUMBER='(0,0,0,0,0,0,BN48,0,0,0,0,0,0,0)';
      BIDIRECTIONAL='TRUE';
      INPUT_LOAD='(-0.01,0.01)';
      OUTPUT_LOAD='(1.0,-1.0)';
      PINUSE='BI';
    'GPP_E11_USB2_OC2_N':
      PIN_NUMBER='(0,0,0,0,0,0,AW54,0,0,0,0,0,0,0)';
      BIDIRECTIONAL='TRUE';
      INPUT_LOAD='(-0.01,0.01)';
      OUTPUT_LOAD='(1.0,-1.0)';
      PINUSE='BI';
    'GPP_E12_USB2_OC3_N':
      PIN_NUMBER='(0,0,0,0,0,0,AU58,0,0,0,0,0,0,0)';
      BIDIRECTIONAL='TRUE';
      INPUT_LOAD='(-0.01,0.01)';
      OUTPUT_LOAD='(1.0,-1.0)';
      PINUSE='BI';
    'GPP_E1_SATAXPCIE1_SATAGP1':
      PIN_NUMBER='(0,0,0,0,0,0,AY52,0,0,0,0,0,0,0)';
      BIDIRECTIONAL='TRUE';
      INPUT_LOAD='(-0.01,0.01)';
      OUTPUT_LOAD='(1.0,-1.0)';
      PINUSE='BI';
    'GPP_E2_SATAXPCIE2_SATAGP2':
      PIN_NUMBER='(0,0,0,0,0,0,BG52,0,0,0,0,0,0,0)';
      BIDIRECTIONAL='TRUE';
      INPUT_LOAD='(-0.01,0.01)';
      OUTPUT_LOAD='(1.0,-1.0)';
      PINUSE='BI';
    'GPP_E3_CPU_GP0':
      PIN_NUMBER='(0,0,0,0,0,0,BE52,0,0,0,0,0,0,0)';
      BIDIRECTIONAL='TRUE';
      INPUT_LOAD='(-0.01,0.01)';
      OUTPUT_LOAD='(1.0,-1.0)';
      PINUSE='BI';
    'GPP_E4_SATA_DEVSLP0':
      PIN_NUMBER='(0,0,0,0,0,0,AV52,0,0,0,0,0,0,0)';
      BIDIRECTIONAL='TRUE';
      INPUT_LOAD='(-0.01,0.01)';
      OUTPUT_LOAD='(1.0,-1.0)';
      PINUSE='BI';
    'GPP_E5_SATA_DEVSLP1':
      PIN_NUMBER='(0,0,0,0,0,0,AT52,0,0,0,0,0,0,0)';
      BIDIRECTIONAL='TRUE';
      INPUT_LOAD='(-0.01,0.01)';
      OUTPUT_LOAD='(1.0,-1.0)';
      PINUSE='BI';
    'GPP_E6_SATA_DEVSLP2':
      PIN_NUMBER='(0,0,0,0,0,0,BB52,0,0,0,0,0,0,0)';
      BIDIRECTIONAL='TRUE';
      INPUT_LOAD='(-0.01,0.01)';
      OUTPUT_LOAD='(1.0,-1.0)';
      PINUSE='BI';
    'GPP_E7_CPU_GP1':
      PIN_NUMBER='(0,0,0,0,0,0,BJ48,0,0,0,0,0,0,0)';
      BIDIRECTIONAL='TRUE';
      INPUT_LOAD='(-0.01,0.01)';
      OUTPUT_LOAD='(1.0,-1.0)';
      PINUSE='BI';
    'GPP_E8_SATA_LED_N':
      PIN_NUMBER='(0,0,0,0,0,0,AV56,0,0,0,0,0,0,0)';
      BIDIRECTIONAL='TRUE';
      INPUT_LOAD='(-0.01,0.01)';
      OUTPUT_LOAD='(1.0,-1.0)';
      PINUSE='BI';
    'GPP_E9_USB2_OC0_N':
      PIN_NUMBER='(0,0,0,0,0,0,BL48,0,0,0,0,0,0,0)';
      BIDIRECTIONAL='TRUE';
      INPUT_LOAD='(-0.01,0.01)';
      OUTPUT_LOAD='(1.0,-1.0)';
      PINUSE='BI';
    'GPP_F0_SATAXPCIE3_SATAGP3':
      PIN_NUMBER='(0,0,0,0,0,0,AG7,0,0,0,0,0,0,0)';
      BIDIRECTIONAL='TRUE';
      INPUT_LOAD='(-0.01,0.01)';
      OUTPUT_LOAD='(1.0,-1.0)';
      PINUSE='BI';
    'GPP_F10_SATA_SCLOCK':
      PIN_NUMBER='(0,0,0,0,0,0,AL7,0,0,0,0,0,0,0)';
      BIDIRECTIONAL='TRUE';
      INPUT_LOAD='(-0.01,0.01)';
      OUTPUT_LOAD='(1.0,-1.0)';
      PINUSE='BI';
    'GPP_F11_SATA_SLOAD':
      PIN_NUMBER='(0,0,0,0,0,0,AR9,0,0,0,0,0,0,0)';
      BIDIRECTIONAL='TRUE';
      INPUT_LOAD='(-0.01,0.01)';
      OUTPUT_LOAD='(1.0,-1.0)';
      PINUSE='BI';
    'GPP_F12_SATA_SDATAOUT1':
      PIN_NUMBER='(0,0,0,0,0,0,AP7,0,0,0,0,0,0,0)';
      BIDIRECTIONAL='TRUE';
      INPUT_LOAD='(-0.01,0.01)';
      OUTPUT_LOAD='(1.0,-1.0)';
      PINUSE='BI';
    'GPP_F13_SATA_SDATAOUT0':
      PIN_NUMBER='(0,0,0,0,0,0,AP11,0,0,0,0,0,0,0)';
      BIDIRECTIONAL='TRUE';
      INPUT_LOAD='(-0.01,0.01)';
      OUTPUT_LOAD='(1.0,-1.0)';
      PINUSE='BI';
    'GPP_F14_SSATA_LED_N':
      PIN_NUMBER='(0,0,0,0,0,0,AL11,0,0,0,0,0,0,0)';
      BIDIRECTIONAL='TRUE';
      INPUT_LOAD='(-0.01,0.01)';
      OUTPUT_LOAD='(1.0,-1.0)';
      PINUSE='BI';
    'GPP_F15_USB2_OC4_N':
      PIN_NUMBER='(0,0,0,0,0,0,AR13,0,0,0,0,0,0,0)';
      BIDIRECTIONAL='TRUE';
      INPUT_LOAD='(-0.01,0.01)';
      OUTPUT_LOAD='(1.0,-1.0)';
      PINUSE='BI';
    'GPP_F16_USB2_OC5_N':
      PIN_NUMBER='(0,0,0,0,0,0,AU13,0,0,0,0,0,0,0)';
      BIDIRECTIONAL='TRUE';
      INPUT_LOAD='(-0.01,0.01)';
      OUTPUT_LOAD='(1.0,-1.0)';
      PINUSE='BI';
    'GPP_F17_USB2_OC6_N':
      PIN_NUMBER='(0,0,0,0,0,0,AP15,0,0,0,0,0,0,0)';
      BIDIRECTIONAL='TRUE';
      INPUT_LOAD='(-0.01,0.01)';
      OUTPUT_LOAD='(1.0,-1.0)';
      PINUSE='BI';
    'GPP_F18_USB2_OC7_N':
      PIN_NUMBER='(0,0,0,0,0,0,AL15,0,0,0,0,0,0,0)';
      BIDIRECTIONAL='TRUE';
      INPUT_LOAD='(-0.01,0.01)';
      OUTPUT_LOAD='(1.0,-1.0)';
      PINUSE='BI';
    'GPP_F19_LAN_SMBCLK':
      PIN_NUMBER='(0,0,0,0,0,0,AU9,0,0,0,0,0,0,0)';
      BIDIRECTIONAL='TRUE';
      INPUT_LOAD='(-0.01,0.01)';
      OUTPUT_LOAD='(1.0,-1.0)';
      PINUSE='BI';
    'GPP_F1_SATAXPCIE4_SATAGP4':
      PIN_NUMBER='(0,0,0,0,0,0,AK9,0,0,0,0,0,0,0)';
      BIDIRECTIONAL='TRUE';
      INPUT_LOAD='(-0.01,0.01)';
      OUTPUT_LOAD='(1.0,-1.0)';
      PINUSE='BI';
    'GPP_F20_LAN_SMBDATA':
      PIN_NUMBER='(0,0,0,0,0,0,AU20,0,0,0,0,0,0,0)';
      BIDIRECTIONAL='TRUE';
      INPUT_LOAD='(-0.01,0.01)';
      OUTPUT_LOAD='(1.0,-1.0)';
      PINUSE='BI';
    'GPP_F21_LAN_SMBALRT_N':
      PIN_NUMBER='(0,0,0,0,0,0,AR17,0,0,0,0,0,0,0)';
      BIDIRECTIONAL='TRUE';
      INPUT_LOAD='(-0.01,0.01)';
      OUTPUT_LOAD='(1.0,-1.0)';
      PINUSE='BI';
    'GPP_F22_SSATA_SCLOCK':
      PIN_NUMBER='(0,0,0,0,0,0,AP18,0,0,0,0,0,0,0)';
      BIDIRECTIONAL='TRUE';
      INPUT_LOAD='(-0.01,0.01)';
      OUTPUT_LOAD='(1.0,-1.0)';
      PINUSE='BI';
    'GPP_F23_SSATA_SLOAD':
      PIN_NUMBER='(0,0,0,0,0,0,AU17,0,0,0,0,0,0,0)';
      BIDIRECTIONAL='TRUE';
      INPUT_LOAD='(-0.01,0.01)';
      OUTPUT_LOAD='(1.0,-1.0)';
      PINUSE='BI';
    'GPP_F2_SATAXPCIE5_SATAGP5':
      PIN_NUMBER='(0,0,0,0,0,0,AK20,0,0,0,0,0,0,0)';
      BIDIRECTIONAL='TRUE';
      INPUT_LOAD='(-0.01,0.01)';
      OUTPUT_LOAD='(1.0,-1.0)';
      PINUSE='BI';
    'GPP_F3_SATAXPCIE6_SATAGP6':
      PIN_NUMBER='(0,0,0,0,0,0,AK13,0,0,0,0,0,0,0)';
      BIDIRECTIONAL='TRUE';
      INPUT_LOAD='(-0.01,0.01)';
      OUTPUT_LOAD='(1.0,-1.0)';
      PINUSE='BI';
    'GPP_F4_SATAXPCIE7_SATAGP7':
      PIN_NUMBER='(0,0,0,0,0,0,AH13,0,0,0,0,0,0,0)';
      BIDIRECTIONAL='TRUE';
      INPUT_LOAD='(-0.01,0.01)';
      OUTPUT_LOAD='(1.0,-1.0)';
      PINUSE='BI';
    'GPP_F5_SATA_DEVSLP3':
      PIN_NUMBER='(0,0,0,0,0,0,AH17,0,0,0,0,0,0,0)';
      BIDIRECTIONAL='TRUE';
      INPUT_LOAD='(-0.01,0.01)';
      OUTPUT_LOAD='(1.0,-1.0)';
      PINUSE='BI';
    'GPP_F6_SATA_DEVSLP4':
      PIN_NUMBER='(0,0,0,0,0,0,AL18,0,0,0,0,0,0,0)';
      BIDIRECTIONAL='TRUE';
      INPUT_LOAD='(-0.01,0.01)';
      OUTPUT_LOAD='(1.0,-1.0)';
      PINUSE='BI';
    'GPP_F7_SATA_DEVSLP5':
      PIN_NUMBER='(0,0,0,0,0,0,AK17,0,0,0,0,0,0,0)';
      BIDIRECTIONAL='TRUE';
      INPUT_LOAD='(-0.01,0.01)';
      OUTPUT_LOAD='(1.0,-1.0)';
      PINUSE='BI';
    'GPP_F8_SATA_DEVSLP6':
      PIN_NUMBER='(0,0,0,0,0,0,AH9,0,0,0,0,0,0,0)';
      BIDIRECTIONAL='TRUE';
      INPUT_LOAD='(-0.01,0.01)';
      OUTPUT_LOAD='(1.0,-1.0)';
      PINUSE='BI';
    'GPP_F9_SATA_DEVSLP7':
      PIN_NUMBER='(0,0,0,0,0,0,AR20,0,0,0,0,0,0,0)';
      BIDIRECTIONAL='TRUE';
      INPUT_LOAD='(-0.01,0.01)';
      OUTPUT_LOAD='(1.0,-1.0)';
      PINUSE='BI';
    'GPP_G0_FANTACH0_FANTACH0IE':
      PIN_NUMBER='(0,0,0,0,0,0,AY11,0,0,0,0,0,0,0)';
      BIDIRECTIONAL='TRUE';
      INPUT_LOAD='(-0.01,0.01)';
      OUTPUT_LOAD='(1.0,-1.0)';
      PINUSE='BI';
    'GPP_G10_FANPWM2_FANPWM2IE':
      PIN_NUMBER='(0,0,0,0,0,0,BE11,0,0,0,0,0,0,0)';
      BIDIRECTIONAL='TRUE';
      INPUT_LOAD='(-0.01,0.01)';
      OUTPUT_LOAD='(1.0,-1.0)';
      PINUSE='BI';
    'GPP_G11_FANPWM3_FANPMW3IE':
      PIN_NUMBER='(0,0,0,0,0,0,BA20,0,0,0,0,0,0,0)';
      BIDIRECTIONAL='TRUE';
      INPUT_LOAD='(-0.01,0.01)';
      OUTPUT_LOAD='(1.0,-1.0)';
      PINUSE='BI';
    'GPP_G12':
      PIN_NUMBER='(0,0,0,0,0,0,BD13,0,0,0,0,0,0,0)';
      BIDIRECTIONAL='TRUE';
      INPUT_LOAD='(-0.01,0.01)';
      OUTPUT_LOAD='(1.0,-1.0)';
      PINUSE='BI';
    'GPP_G13':
      PIN_NUMBER='(0,0,0,0,0,0,AY18,0,0,0,0,0,0,0)';
      BIDIRECTIONAL='TRUE';
      INPUT_LOAD='(-0.01,0.01)';
      OUTPUT_LOAD='(1.0,-1.0)';
      PINUSE='BI';
    'GPP_G14':
      PIN_NUMBER='(0,0,0,0,0,0,AV7,0,0,0,0,0,0,0)';
      BIDIRECTIONAL='TRUE';
      INPUT_LOAD='(-0.01,0.01)';
      OUTPUT_LOAD='(1.0,-1.0)';
      PINUSE='BI';
    'GPP_G15':
      PIN_NUMBER='(0,0,0,0,0,0,BE18,0,0,0,0,0,0,0)';
      BIDIRECTIONAL='TRUE';
      INPUT_LOAD='(-0.01,0.01)';
      OUTPUT_LOAD='(1.0,-1.0)';
      PINUSE='BI';
    'GPP_G16':
      PIN_NUMBER='(0,0,0,0,0,0,BD17,0,0,0,0,0,0,0)';
      BIDIRECTIONAL='TRUE';
      INPUT_LOAD='(-0.01,0.01)';
      OUTPUT_LOAD='(1.0,-1.0)';
      PINUSE='BI';
    'GPP_G17_ADR_COMPLETE':
      PIN_NUMBER='(0,0,0,0,0,0,BD9,0,0,0,0,0,0,0)';
      BIDIRECTIONAL='TRUE';
      INPUT_LOAD='(-0.01,0.01)';
      OUTPUT_LOAD='(1.0,-1.0)';
      PINUSE='BI';
    'GPP_G18_NMI_N':
      PIN_NUMBER='(0,0,0,0,0,0,BE7,0,0,0,0,0,0,0)';
      BIDIRECTIONAL='TRUE';
      INPUT_LOAD='(-0.01,0.01)';
      OUTPUT_LOAD='(1.0,-1.0)';
      PINUSE='BI';
    'GPP_G19_SMI_N':
      PIN_NUMBER='(0,0,0,0,0,0,BE15,0,0,0,0,0,0,0)';
      BIDIRECTIONAL='TRUE';
      INPUT_LOAD='(-0.01,0.01)';
      OUTPUT_LOAD='(1.0,-1.0)';
      PINUSE='BI';
    'GPP_G1_FANTACH1_FANTACH1IE':
      PIN_NUMBER='(0,0,0,0,0,0,AV15,0,0,0,0,0,0,0)';
      BIDIRECTIONAL='TRUE';
      INPUT_LOAD='(-0.01,0.01)';
      OUTPUT_LOAD='(1.0,-1.0)';
      PINUSE='BI';
    'GPP_G20_SSATA_DEVSLP0':
      PIN_NUMBER='(0,0,0,0,0,0,BA17,0,0,0,0,0,0,0)';
      BIDIRECTIONAL='TRUE';
      INPUT_LOAD='(-0.01,0.01)';
      OUTPUT_LOAD='(1.0,-1.0)';
      PINUSE='BI';
    'GPP_G21_SSATA_DEVSLP1':
      PIN_NUMBER='(0,0,0,0,0,0,BG7,0,0,0,0,0,0,0)';
      BIDIRECTIONAL='TRUE';
      INPUT_LOAD='(-0.01,0.01)';
      OUTPUT_LOAD='(1.0,-1.0)';
      PINUSE='BI';
    'GPP_G22_SSATA_DEVSLP2':
      PIN_NUMBER='(0,0,0,0,0,0,BD20,0,0,0,0,0,0,0)';
      BIDIRECTIONAL='TRUE';
      INPUT_LOAD='(-0.01,0.01)';
      OUTPUT_LOAD='(1.0,-1.0)';
      PINUSE='BI';
    'GPP_G23_SSATAXPCIE0_SSATAGP0':
      PIN_NUMBER='(0,0,0,0,0,0,BA13,0,0,0,0,0,0,0)';
      BIDIRECTIONAL='TRUE';
      INPUT_LOAD='(-0.01,0.01)';
      OUTPUT_LOAD='(1.0,-1.0)';
      PINUSE='BI';
    'GPP_G2_FANTACH2_FANTACH2IE':
      PIN_NUMBER='(0,0,0,0,0,0,BE22,0,0,0,0,0,0,0)';
      BIDIRECTIONAL='TRUE';
      INPUT_LOAD='(-0.01,0.01)';
      OUTPUT_LOAD='(1.0,-1.0)';
      PINUSE='BI';
    'GPP_G3_FANTACH3_FANTACH3IE':
      PIN_NUMBER='(0,0,0,0,0,0,AY7,0,0,0,0,0,0,0)';
      BIDIRECTIONAL='TRUE';
      INPUT_LOAD='(-0.01,0.01)';
      OUTPUT_LOAD='(1.0,-1.0)';
      PINUSE='BI';
    'GPP_G4_FANTACH4_FANTACH4IE':
      PIN_NUMBER='(0,0,0,0,0,0,BA9,0,0,0,0,0,0,0)';
      BIDIRECTIONAL='TRUE';
      INPUT_LOAD='(-0.01,0.01)';
      OUTPUT_LOAD='(1.0,-1.0)';
      PINUSE='BI';
    'GPP_G5_FANTACH5_FANTACH5IE':
      PIN_NUMBER='(0,0,0,0,0,0,AW20,0,0,0,0,0,0,0)';
      BIDIRECTIONAL='TRUE';
      INPUT_LOAD='(-0.01,0.01)';
      OUTPUT_LOAD='(1.0,-1.0)';
      PINUSE='BI';
    'GPP_G6_FANTACH6_FANTACH6IE':
      PIN_NUMBER='(0,0,0,0,0,0,AV18,0,0,0,0,0,0,0)';
      BIDIRECTIONAL='TRUE';
      INPUT_LOAD='(-0.01,0.01)';
      OUTPUT_LOAD='(1.0,-1.0)';
      PINUSE='BI';
    'GPP_G7_FANTACH7_FANTACH7IE':
      PIN_NUMBER='(0,0,0,0,0,0,AY15,0,0,0,0,0,0,0)';
      BIDIRECTIONAL='TRUE';
      INPUT_LOAD='(-0.01,0.01)';
      OUTPUT_LOAD='(1.0,-1.0)';
      PINUSE='BI';
    'GPP_G8_FANPWM0_FANPWM0IE':
      PIN_NUMBER='(0,0,0,0,0,0,BG11,0,0,0,0,0,0,0)';
      BIDIRECTIONAL='TRUE';
      INPUT_LOAD='(-0.01,0.01)';
      OUTPUT_LOAD='(1.0,-1.0)';
      PINUSE='BI';
    'GPP_G9_FANPWM1_FAMPWM1IE':
      PIN_NUMBER='(0,0,0,0,0,0,AV11,0,0,0,0,0,0,0)';
      BIDIRECTIONAL='TRUE';
      INPUT_LOAD='(-0.01,0.01)';
      OUTPUT_LOAD='(1.0,-1.0)';
      PINUSE='BI';
    'GPP_H0_SRCCLKREQ6_N':
      PIN_NUMBER='(0,0,0,0,0,0,AT4,0,0,0,0,0,0,0)';
      BIDIRECTIONAL='TRUE';
      INPUT_LOAD='(-0.01,0.01)';
      OUTPUT_LOAD='(1.0,-1.0)';
      PINUSE='BI';
    'GPP_H10_SML2CLK_IE':
      PIN_NUMBER='(0,0,0,0,0,0,BA4,0,0,0,0,0,0,0)';
      BIDIRECTIONAL='TRUE';
      INPUT_LOAD='(-0.01,0.01)';
      OUTPUT_LOAD='(1.0,-1.0)';
      PINUSE='BI';
    'GPP_H11_SML2DATA_IE':
      PIN_NUMBER='(0,0,0,0,0,0,BD1,0,0,0,0,0,0,0)';
      BIDIRECTIONAL='TRUE';
      INPUT_LOAD='(-0.01,0.01)';
      OUTPUT_LOAD='(1.0,-1.0)';
      PINUSE='BI';
    'GPP_H12_SML2ALERT_N_IE_N':
      PIN_NUMBER='(0,0,0,0,0,0,BB1,0,0,0,0,0,0,0)';
      BIDIRECTIONAL='TRUE';
      INPUT_LOAD='(-0.01,0.01)';
      OUTPUT_LOAD='(1.0,-1.0)';
      PINUSE='BI';
    'GPP_H13_SML3CLK_IE':
      PIN_NUMBER='(0,0,0,0,0,0,AY1,0,0,0,0,0,0,0)';
      BIDIRECTIONAL='TRUE';
      INPUT_LOAD='(-0.01,0.01)';
      OUTPUT_LOAD='(1.0,-1.0)';
      PINUSE='BI';
    'GPP_H14_SML3DATA_IE':
      PIN_NUMBER='(0,0,0,0,0,0,BC2,0,0,0,0,0,0,0)';
      BIDIRECTIONAL='TRUE';
      INPUT_LOAD='(-0.01,0.01)';
      OUTPUT_LOAD='(1.0,-1.0)';
      PINUSE='BI';
    'GPP_H15_SML3ALERT_N_IE_N':
      PIN_NUMBER='(0,0,0,0,0,0,BB3,0,0,0,0,0,0,0)';
      BIDIRECTIONAL='TRUE';
      INPUT_LOAD='(-0.01,0.01)';
      OUTPUT_LOAD='(1.0,-1.0)';
      PINUSE='BI';
    'GPP_H16_SML4CLK_IE':
      PIN_NUMBER='(0,0,0,0,0,0,BF1,0,0,0,0,0,0,0)';
      BIDIRECTIONAL='TRUE';
      INPUT_LOAD='(-0.01,0.01)';
      OUTPUT_LOAD='(1.0,-1.0)';
      PINUSE='BI';
    'GPP_H17_SML4DATA_IE':
      PIN_NUMBER='(0,0,0,0,0,0,BE4,0,0,0,0,0,0,0)';
      BIDIRECTIONAL='TRUE';
      INPUT_LOAD='(-0.01,0.01)';
      OUTPUT_LOAD='(1.0,-1.0)';
      PINUSE='BI';
    'GPP_H18_SML4ALERT_N_IE_N':
      PIN_NUMBER='(0,0,0,0,0,0,BC4,0,0,0,0,0,0,0)';
      BIDIRECTIONAL='TRUE';
      INPUT_LOAD='(-0.01,0.01)';
      OUTPUT_LOAD='(1.0,-1.0)';
      PINUSE='BI';
    'GPP_H19_SSATAXPCIE1_SSATAGP1':
      PIN_NUMBER='(0,0,0,0,0,0,BD3,0,0,0,0,0,0,0)';
      BIDIRECTIONAL='TRUE';
      INPUT_LOAD='(-0.01,0.01)';
      OUTPUT_LOAD='(1.0,-1.0)';
      PINUSE='BI';
    'GPP_H1_SRCCLKREQ7_N':
      PIN_NUMBER='(0,0,0,0,0,0,AW4,0,0,0,0,0,0,0)';
      BIDIRECTIONAL='TRUE';
      INPUT_LOAD='(-0.01,0.01)';
      OUTPUT_LOAD='(1.0,-1.0)';
      PINUSE='BI';
    'GPP_H20_SSATAXPCIE2_SSATAGP2':
      PIN_NUMBER='(0,0,0,0,0,0,BF3,0,0,0,0,0,0,0)';
      BIDIRECTIONAL='TRUE';
      INPUT_LOAD='(-0.01,0.01)';
      OUTPUT_LOAD='(1.0,-1.0)';
      PINUSE='BI';
    'GPP_H21_SSATAXPCIE3_SSATAGP3':
      PIN_NUMBER='(0,0,0,0,0,0,BA2,0,0,0,0,0,0,0)';
      BIDIRECTIONAL='TRUE';
      INPUT_LOAD='(-0.01,0.01)';
      OUTPUT_LOAD='(1.0,-1.0)';
      PINUSE='BI';
    'GPP_H22_SSATAXPCIE4_SSATAGP4':
      PIN_NUMBER='(0,0,0,0,0,0,BH2,0,0,0,0,0,0,0)';
      BIDIRECTIONAL='TRUE';
      INPUT_LOAD='(-0.01,0.01)';
      OUTPUT_LOAD='(1.0,-1.0)';
      PINUSE='BI';
    'GPP_H23_SSATAXPCIE5_SSATAGP5':
      PIN_NUMBER='(0,0,0,0,0,0,BH4,0,0,0,0,0,0,0)';
      BIDIRECTIONAL='TRUE';
      INPUT_LOAD='(-0.01,0.01)';
      OUTPUT_LOAD='(1.0,-1.0)';
      PINUSE='BI';
    'GPP_H2_SRCCLKREQ8_N':
      PIN_NUMBER='(0,0,0,0,0,0,AV3,0,0,0,0,0,0,0)';
      BIDIRECTIONAL='TRUE';
      INPUT_LOAD='(-0.01,0.01)';
      OUTPUT_LOAD='(1.0,-1.0)';
      PINUSE='BI';
    'GPP_H3_SRCCLKREQ9_N':
      PIN_NUMBER='(0,0,0,0,0,0,AR1,0,0,0,0,0,0,0)';
      BIDIRECTIONAL='TRUE';
      INPUT_LOAD='(-0.01,0.01)';
      OUTPUT_LOAD='(1.0,-1.0)';
      PINUSE='BI';
    'GPP_H4_SRCCLKREQ10_N':
      PIN_NUMBER='(0,0,0,0,0,0,AT2,0,0,0,0,0,0,0)';
      BIDIRECTIONAL='TRUE';
      INPUT_LOAD='(-0.01,0.01)';
      OUTPUT_LOAD='(1.0,-1.0)';
      PINUSE='BI';
    'GPP_H5_SRCCLKREQ11_N':
      PIN_NUMBER='(0,0,0,0,0,0,AY3,0,0,0,0,0,0,0)';
      BIDIRECTIONAL='TRUE';
      INPUT_LOAD='(-0.01,0.01)';
      OUTPUT_LOAD='(1.0,-1.0)';
      PINUSE='BI';
    'GPP_H6_SRCCLKREQ12_N':
      PIN_NUMBER='(0,0,0,0,0,0,AW2,0,0,0,0,0,0,0)';
      BIDIRECTIONAL='TRUE';
      INPUT_LOAD='(-0.01,0.01)';
      OUTPUT_LOAD='(1.0,-1.0)';
      PINUSE='BI';
    'GPP_H7_SRCCLKREQ13_N':
      PIN_NUMBER='(0,0,0,0,0,0,AV1,0,0,0,0,0,0,0)';
      BIDIRECTIONAL='TRUE';
      INPUT_LOAD='(-0.01,0.01)';
      OUTPUT_LOAD='(1.0,-1.0)';
      PINUSE='BI';
    'GPP_H8_SRCCLKREQ14_N':
      PIN_NUMBER='(0,0,0,0,0,0,AR3,0,0,0,0,0,0,0)';
      BIDIRECTIONAL='TRUE';
      INPUT_LOAD='(-0.01,0.01)';
      OUTPUT_LOAD='(1.0,-1.0)';
      PINUSE='BI';
    'GPP_H9_SRCCLKREQ15_N':
      PIN_NUMBER='(0,0,0,0,0,0,BE2,0,0,0,0,0,0,0)';
      BIDIRECTIONAL='TRUE';
      INPUT_LOAD='(-0.01,0.01)';
      OUTPUT_LOAD='(1.0,-1.0)';
      PINUSE='BI';
    'GPP_I0_LAN_TDO':
      PIN_NUMBER='(0,0,0,0,0,0,CA20,0,0,0,0,0,0,0)';
      PINUSE='UNSPEC';
      NO_LOAD_CHECK='Both';
      NO_IO_CHECK='Both';
      NO_ASSERT_CHECK='TRUE';
      NO_DIR_CHECK='TRUE';
      ALLOW_CONNECT='TRUE';
    'GPP_I10':
      PIN_NUMBER='(0,0,0,0,0,0,BV25,0,0,0,0,0,0,0)';
      BIDIRECTIONAL='TRUE';
      INPUT_LOAD='(-0.01,0.01)';
      OUTPUT_LOAD='(1.0,-1.0)';
      PINUSE='BI';
    'GPP_I1_LAN_TCK':
      PIN_NUMBER='(0,0,0,0,0,0,BV21,0,0,0,0,0,0,0)';
      PINUSE='UNSPEC';
      NO_LOAD_CHECK='Both';
      NO_IO_CHECK='Both';
      NO_ASSERT_CHECK='TRUE';
      NO_DIR_CHECK='TRUE';
      ALLOW_CONNECT='TRUE';
    'GPP_I2_LAN_TMS':
      PIN_NUMBER='(0,0,0,0,0,0,CA22,0,0,0,0,0,0,0)';
      PINUSE='UNSPEC';
      NO_LOAD_CHECK='Both';
      NO_IO_CHECK='Both';
      NO_ASSERT_CHECK='TRUE';
      NO_DIR_CHECK='TRUE';
      ALLOW_CONNECT='TRUE';
    'GPP_I3_LAN_TDI':
      PIN_NUMBER='(0,0,0,0,0,0,BY23,0,0,0,0,0,0,0)';
      PINUSE='UNSPEC';
      NO_LOAD_CHECK='Both';
      NO_IO_CHECK='Both';
      NO_ASSERT_CHECK='TRUE';
      NO_DIR_CHECK='TRUE';
      ALLOW_CONNECT='TRUE';
    'GPP_I4_DO_RESET_IN_N':
      PIN_NUMBER='(0,0,0,0,0,0,BW20,0,0,0,0,0,0,0)';
      BIDIRECTIONAL='TRUE';
      INPUT_LOAD='(-0.01,0.01)';
      OUTPUT_LOAD='(1.0,-1.0)';
      PINUSE='BI';
    'GPP_I5_DO_RESET_OUT_N':
      PIN_NUMBER='(0,0,0,0,0,0,BW24,0,0,0,0,0,0,0)';
      BIDIRECTIONAL='TRUE';
      INPUT_LOAD='(-0.01,0.01)';
      OUTPUT_LOAD='(1.0,-1.0)';
      PINUSE='BI';
    'GPP_I6_RESET_DONE':
      PIN_NUMBER='(0,0,0,0,0,0,BV23,0,0,0,0,0,0,0)';
      BIDIRECTIONAL='TRUE';
      INPUT_LOAD='(-0.01,0.01)';
      OUTPUT_LOAD='(1.0,-1.0)';
      PINUSE='BI';
    'GPP_I7_LAN_TRST_N':
      PIN_NUMBER='(0,0,0,0,0,0,CA24,0,0,0,0,0,0,0)';
      PINUSE='UNSPEC';
      NO_LOAD_CHECK='Both';
      NO_IO_CHECK='Both';
      NO_ASSERT_CHECK='TRUE';
      NO_DIR_CHECK='TRUE';
      ALLOW_CONNECT='TRUE';
    'GPP_I8_PCI_DIS_N':
      PIN_NUMBER='(0,0,0,0,0,0,BW22,0,0,0,0,0,0,0)';
      PINUSE='UNSPEC';
      NO_LOAD_CHECK='Both';
      NO_IO_CHECK='Both';
      NO_ASSERT_CHECK='TRUE';
      NO_DIR_CHECK='TRUE';
      ALLOW_CONNECT='TRUE';
    'GPP_I9_LAN_DIS_N':
      PIN_NUMBER='(0,0,0,0,0,0,BY21,0,0,0,0,0,0,0)';
      PINUSE='UNSPEC';
      NO_LOAD_CHECK='Both';
      NO_IO_CHECK='Both';
      NO_ASSERT_CHECK='TRUE';
      NO_DIR_CHECK='TRUE';
      ALLOW_CONNECT='TRUE';
    'GPP_J0_LAN_LED_P0_0':
      PIN_NUMBER='(0,0,0,0,0,0,BL1,0,0,0,0,0,0,0)';
      BIDIRECTIONAL='TRUE';
      INPUT_LOAD='(-0.01,0.01)';
      OUTPUT_LOAD='(1.0,-1.0)';
      PINUSE='BI';
    'GPP_J10_LAN_I2C_SCL_MDC_P1':
      PIN_NUMBER='(0,0,0,0,0,0,BW5,0,0,0,0,0,0,0)';
      BIDIRECTIONAL='TRUE';
      INPUT_LOAD='(-0.01,0.01)';
      OUTPUT_LOAD='(1.0,-1.0)';
      PINUSE='BI';
    'GPP_J11_LAN_I2C_SDA_MDIO_P1':
      PIN_NUMBER='(0,0,0,0,0,0,BV8,0,0,0,0,0,0,0)';
      BIDIRECTIONAL='TRUE';
      INPUT_LOAD='(-0.01,0.01)';
      OUTPUT_LOAD='(1.0,-1.0)';
      PINUSE='BI';
    'GPP_J12_LAN_I2C_SCL_MDC_P2':
      PIN_NUMBER='(0,0,0,0,0,0,BT5,0,0,0,0,0,0,0)';
      BIDIRECTIONAL='TRUE';
      INPUT_LOAD='(-0.01,0.01)';
      OUTPUT_LOAD='(1.0,-1.0)';
      PINUSE='BI';
    'GPP_J13_LAN_I2C_SDA_MDIO_P2':
      PIN_NUMBER='(0,0,0,0,0,0,BW11,0,0,0,0,0,0,0)';
      BIDIRECTIONAL='TRUE';
      INPUT_LOAD='(-0.01,0.01)';
      OUTPUT_LOAD='(1.0,-1.0)';
      PINUSE='BI';
    'GPP_J14_LAN_I2C_SCL_MDC_P3':
      PIN_NUMBER='(0,0,0,0,0,0,BW6,0,0,0,0,0,0,0)';
      BIDIRECTIONAL='TRUE';
      INPUT_LOAD='(-0.01,0.01)';
      OUTPUT_LOAD='(1.0,-1.0)';
      PINUSE='BI';
    'GPP_J15_LAN_I2C_SDA_MDIO_P3':
      PIN_NUMBER='(0,0,0,0,0,0,BW9,0,0,0,0,0,0,0)';
      BIDIRECTIONAL='TRUE';
      INPUT_LOAD='(-0.01,0.01)';
      OUTPUT_LOAD='(1.0,-1.0)';
      PINUSE='BI';
    'GPP_J16_LAN_SDP_P0_0':
      PIN_NUMBER='(0,0,0,0,0,0,BV10,0,0,0,0,0,0,0)';
      BIDIRECTIONAL='TRUE';
      INPUT_LOAD='(-0.01,0.01)';
      OUTPUT_LOAD='(1.0,-1.0)';
      PINUSE='BI';
    'GPP_J17_LAN_SDP_P0_1':
      PIN_NUMBER='(0,0,0,0,0,0,CA11,0,0,0,0,0,0,0)';
      BIDIRECTIONAL='TRUE';
      INPUT_LOAD='(-0.01,0.01)';
      OUTPUT_LOAD='(1.0,-1.0)';
      PINUSE='BI';
    'GPP_J18_LAN_SDP_P1_0':
      PIN_NUMBER='(0,0,0,0,0,0,BY10,0,0,0,0,0,0,0)';
      BIDIRECTIONAL='TRUE';
      INPUT_LOAD='(-0.01,0.01)';
      OUTPUT_LOAD='(1.0,-1.0)';
      PINUSE='BI';
    'GPP_J19_LAN_SDP_P1_1':
      PIN_NUMBER='(0,0,0,0,0,0,BY14,0,0,0,0,0,0,0)';
      BIDIRECTIONAL='TRUE';
      INPUT_LOAD='(-0.01,0.01)';
      OUTPUT_LOAD='(1.0,-1.0)';
      PINUSE='BI';
    'GPP_J1_LAN_LED_P0_1':
      PIN_NUMBER='(0,0,0,0,0,0,BK4,0,0,0,0,0,0,0)';
      BIDIRECTIONAL='TRUE';
      INPUT_LOAD='(-0.01,0.01)';
      OUTPUT_LOAD='(1.0,-1.0)';
      PINUSE='BI';
    'GPP_J20_LAN_SDP_P2_0':
      PIN_NUMBER='(0,0,0,0,0,0,BW13,0,0,0,0,0,0,0)';
      BIDIRECTIONAL='TRUE';
      INPUT_LOAD='(-0.01,0.01)';
      OUTPUT_LOAD='(1.0,-1.0)';
      PINUSE='BI';
    'GPP_J21_LAN_SDP_P2_1':
      PIN_NUMBER='(0,0,0,0,0,0,BV12,0,0,0,0,0,0,0)';
      BIDIRECTIONAL='TRUE';
      INPUT_LOAD='(-0.01,0.01)';
      OUTPUT_LOAD='(1.0,-1.0)';
      PINUSE='BI';
    'GPP_J22_LAN_SDP_P3_0':
      PIN_NUMBER='(0,0,0,0,0,0,BY12,0,0,0,0,0,0,0)';
      BIDIRECTIONAL='TRUE';
      INPUT_LOAD='(-0.01,0.01)';
      OUTPUT_LOAD='(1.0,-1.0)';
      PINUSE='BI';
    'GPP_J23_LAN_SDP_P3_1':
      PIN_NUMBER='(0,0,0,0,0,0,BV14,0,0,0,0,0,0,0)';
      BIDIRECTIONAL='TRUE';
      INPUT_LOAD='(-0.01,0.01)';
      OUTPUT_LOAD='(1.0,-1.0)';
      PINUSE='BI';
    'GPP_J2_LAN_LED_P1_0':
      PIN_NUMBER='(0,0,0,0,0,0,BP4,0,0,0,0,0,0,0)';
      BIDIRECTIONAL='TRUE';
      INPUT_LOAD='(-0.01,0.01)';
      OUTPUT_LOAD='(1.0,-1.0)';
      PINUSE='BI';
    'GPP_J3_LAN_LED_P1_1':
      PIN_NUMBER='(0,0,0,0,0,0,BK2,0,0,0,0,0,0,0)';
      BIDIRECTIONAL='TRUE';
      INPUT_LOAD='(-0.01,0.01)';
      OUTPUT_LOAD='(1.0,-1.0)';
      PINUSE='BI';
    'GPP_J4_LAN_LED_P2_0':
      PIN_NUMBER='(0,0,0,0,0,0,BL3,0,0,0,0,0,0,0)';
      BIDIRECTIONAL='TRUE';
      INPUT_LOAD='(-0.01,0.01)';
      OUTPUT_LOAD='(1.0,-1.0)';
      PINUSE='BI';
    'GPP_J5_LAN_LED_P2_1':
      PIN_NUMBER='(0,0,0,0,0,0,BU6,0,0,0,0,0,0,0)';
      BIDIRECTIONAL='TRUE';
      INPUT_LOAD='(-0.01,0.01)';
      OUTPUT_LOAD='(1.0,-1.0)';
      PINUSE='BI';
    'GPP_J6_LAN_LED_P3_0':
      PIN_NUMBER='(0,0,0,0,0,0,CA13,0,0,0,0,0,0,0)';
      BIDIRECTIONAL='TRUE';
      INPUT_LOAD='(-0.01,0.01)';
      OUTPUT_LOAD='(1.0,-1.0)';
      PINUSE='BI';
    'GPP_J7_LAN_LED_P3_1':
      PIN_NUMBER='(0,0,0,0,0,0,BM2,0,0,0,0,0,0,0)';
      BIDIRECTIONAL='TRUE';
      INPUT_LOAD='(-0.01,0.01)';
      OUTPUT_LOAD='(1.0,-1.0)';
      PINUSE='BI';
    'GPP_J8_LAN_I2C_SCL_MDC_P0':
      PIN_NUMBER='(0,0,0,0,0,0,BM4,0,0,0,0,0,0,0)';
      BIDIRECTIONAL='TRUE';
      INPUT_LOAD='(-0.01,0.01)';
      OUTPUT_LOAD='(1.0,-1.0)';
      PINUSE='BI';
    'GPP_J9_LAN_I2C_SDA_MDIO_P0':
      PIN_NUMBER='(0,0,0,0,0,0,BN3,0,0,0,0,0,0,0)';
      BIDIRECTIONAL='TRUE';
      INPUT_LOAD='(-0.01,0.01)';
      OUTPUT_LOAD='(1.0,-1.0)';
      PINUSE='BI';
    'GPP_K0_LAN_NCSI_CLK_IN':
      PIN_NUMBER='(0,0,0,0,0,0,0,AJ1,0,0,0,0,0,0)';
      BIDIRECTIONAL='TRUE';
      INPUT_LOAD='(-0.01,0.01)';
      OUTPUT_LOAD='(1.0,-1.0)';
      PINUSE='BI';
    'GPP_K10_PE_RST_N':
      PIN_NUMBER='(0,0,0,0,0,0,0,AH4,0,0,0,0,0,0)';
      BIDIRECTIONAL='TRUE';
      INPUT_LOAD='(-0.01,0.01)';
      OUTPUT_LOAD='(1.0,-1.0)';
      PINUSE='BI';
    'GPP_K1_LAN_NCSI_TXD0':
      PIN_NUMBER='(0,0,0,0,0,0,0,AM2,0,0,0,0,0,0)';
      BIDIRECTIONAL='TRUE';
      INPUT_LOAD='(-0.01,0.01)';
      OUTPUT_LOAD='(1.0,-1.0)';
      PINUSE='BI';
    'GPP_K2_LAN_NCSI_TXD1':
      PIN_NUMBER='(0,0,0,0,0,0,0,AK2,0,0,0,0,0,0)';
      BIDIRECTIONAL='TRUE';
      INPUT_LOAD='(-0.01,0.01)';
      OUTPUT_LOAD='(1.0,-1.0)';
      PINUSE='BI';
    'GPP_K3_LAN_NCSI_TX_EN':
      PIN_NUMBER='(0,0,0,0,0,0,0,AL3,0,0,0,0,0,0)';
      BIDIRECTIONAL='TRUE';
      INPUT_LOAD='(-0.01,0.01)';
      OUTPUT_LOAD='(1.0,-1.0)';
      PINUSE='BI';
    'GPP_K4_LAN_NCSI_CRS_DV':
      PIN_NUMBER='(0,0,0,0,0,0,0,AN3,0,0,0,0,0,0)';
      BIDIRECTIONAL='TRUE';
      INPUT_LOAD='(-0.01,0.01)';
      OUTPUT_LOAD='(1.0,-1.0)';
      PINUSE='BI';
    'GPP_K5_LAN_NCSI_RXD0':
      PIN_NUMBER='(0,0,0,0,0,0,0,AL1,0,0,0,0,0,0)';
      BIDIRECTIONAL='TRUE';
      INPUT_LOAD='(-0.01,0.01)';
      OUTPUT_LOAD='(1.0,-1.0)';
      PINUSE='BI';
    'GPP_K6_LAN_NCSI_RXD1':
      PIN_NUMBER='(0,0,0,0,0,0,0,AN1,0,0,0,0,0,0)';
      BIDIRECTIONAL='TRUE';
      INPUT_LOAD='(-0.01,0.01)';
      OUTPUT_LOAD='(1.0,-1.0)';
      PINUSE='BI';
    'GPP_K7':
      PIN_NUMBER='(0,0,0,0,0,0,0,AH2,0,0,0,0,0,0)';
      BIDIRECTIONAL='TRUE';
      INPUT_LOAD='(-0.01,0.01)';
      OUTPUT_LOAD='(1.0,-1.0)';
      PINUSE='BI';
    'GPP_K8_LAN_NCSI_ARB_IN':
      PIN_NUMBER='(0,0,0,0,0,0,0,AJ3,0,0,0,0,0,0)';
      BIDIRECTIONAL='TRUE';
      INPUT_LOAD='(-0.01,0.01)';
      OUTPUT_LOAD='(1.0,-1.0)';
      PINUSE='BI';
    'GPP_K9_LAN_NCSI_ARB_OUT':
      PIN_NUMBER='(0,0,0,0,0,0,0,AK4,0,0,0,0,0,0)';
      BIDIRECTIONAL='TRUE';
      INPUT_LOAD='(-0.01,0.01)';
      OUTPUT_LOAD='(1.0,-1.0)';
      PINUSE='BI';
    'GPP_L10_TESTCH0_CLK':
      PIN_NUMBER='(0,0,0,0,0,0,0,AF20,0,0,0,0,0,0)';
      BIDIRECTIONAL='TRUE';
      INPUT_LOAD='(-0.01,0.01)';
      OUTPUT_LOAD='(1.0,-1.0)';
      PINUSE='BI';
    'GPP_L11_TESTCH1_D0':
      PIN_NUMBER='(0,0,0,0,0,0,0,AD20,0,0,0,0,0,0)';
      BIDIRECTIONAL='TRUE';
      INPUT_LOAD='(-0.01,0.01)';
      OUTPUT_LOAD='(1.0,-1.0)';
      PINUSE='BI';
    'GPP_L12_TESTCH1_D1':
      PIN_NUMBER='(0,0,0,0,0,0,0,Y15,0,0,0,0,0,0)';
      BIDIRECTIONAL='TRUE';
      INPUT_LOAD='(-0.01,0.01)';
      OUTPUT_LOAD='(1.0,-1.0)';
      PINUSE='BI';
    'GPP_L13_TESTCH1_D2':
      PIN_NUMBER='(0,0,0,0,0,0,0,AD13,0,0,0,0,0,0)';
      BIDIRECTIONAL='TRUE';
      INPUT_LOAD='(-0.01,0.01)';
      OUTPUT_LOAD='(1.0,-1.0)';
      PINUSE='BI';
    'GPP_L14_TESTCH1_D3':
      PIN_NUMBER='(0,0,0,0,0,0,0,AA13,0,0,0,0,0,0)';
      BIDIRECTIONAL='TRUE';
      INPUT_LOAD='(-0.01,0.01)';
      OUTPUT_LOAD='(1.0,-1.0)';
      PINUSE='BI';
    'GPP_L15_TESTCH1_D4':
      PIN_NUMBER='(0,0,0,0,0,0,0,Y11,0,0,0,0,0,0)';
      BIDIRECTIONAL='TRUE';
      INPUT_LOAD='(-0.01,0.01)';
      OUTPUT_LOAD='(1.0,-1.0)';
      PINUSE='BI';
    'GPP_L16_TESTCH1_D5':
      PIN_NUMBER='(0,0,0,0,0,0,0,Y7,0,0,0,0,0,0)';
      BIDIRECTIONAL='TRUE';
      INPUT_LOAD='(-0.01,0.01)';
      OUTPUT_LOAD='(1.0,-1.0)';
      PINUSE='BI';
    'GPP_L17_TESTCH1_D6':
      PIN_NUMBER='(0,0,0,0,0,0,0,AA9,0,0,0,0,0,0)';
      BIDIRECTIONAL='TRUE';
      INPUT_LOAD='(-0.01,0.01)';
      OUTPUT_LOAD='(1.0,-1.0)';
      PINUSE='BI';
    'GPP_L18_TESTCH1_D7':
      PIN_NUMBER='(0,0,0,0,0,0,0,AE7,0,0,0,0,0,0)';
      BIDIRECTIONAL='TRUE';
      INPUT_LOAD='(-0.01,0.01)';
      OUTPUT_LOAD='(1.0,-1.0)';
      PINUSE='BI';
    'GPP_L19_TESTCH1_CLK':
      PIN_NUMBER='(0,0,0,0,0,0,0,AG11,0,0,0,0,0,0)';
      BIDIRECTIONAL='TRUE';
      INPUT_LOAD='(-0.01,0.01)';
      OUTPUT_LOAD='(1.0,-1.0)';
      PINUSE='BI';
    'GPP_L2_TESTCH0_D0':
      PIN_NUMBER='(0,0,0,0,0,0,0,AE18,0,0,0,0,0,0)';
      BIDIRECTIONAL='TRUE';
      INPUT_LOAD='(-0.01,0.01)';
      OUTPUT_LOAD='(1.0,-1.0)';
      PINUSE='BI';
    'GPP_L3_TESTCH0_D1':
      PIN_NUMBER='(0,0,0,0,0,0,0,AE15,0,0,0,0,0,0)';
      BIDIRECTIONAL='TRUE';
      INPUT_LOAD='(-0.01,0.01)';
      OUTPUT_LOAD='(1.0,-1.0)';
      PINUSE='BI';
    'GPP_L4_TESTCH0_D2':
      PIN_NUMBER='(0,0,0,0,0,0,0,AE11,0,0,0,0,0,0)';
      BIDIRECTIONAL='TRUE';
      INPUT_LOAD='(-0.01,0.01)';
      OUTPUT_LOAD='(1.0,-1.0)';
      PINUSE='BI';
    'GPP_L5_TESTCH0_D3':
      PIN_NUMBER='(0,0,0,0,0,0,0,Y18,0,0,0,0,0,0)';
      BIDIRECTIONAL='TRUE';
      INPUT_LOAD='(-0.01,0.01)';
      OUTPUT_LOAD='(1.0,-1.0)';
      PINUSE='BI';
    'GPP_L6_TESTCH0_D4':
      PIN_NUMBER='(0,0,0,0,0,0,0,AA20,0,0,0,0,0,0)';
      BIDIRECTIONAL='TRUE';
      INPUT_LOAD='(-0.01,0.01)';
      OUTPUT_LOAD='(1.0,-1.0)';
      PINUSE='BI';
    'GPP_L7_TESTCH0_D5':
      PIN_NUMBER='(0,0,0,0,0,0,0,AA17,0,0,0,0,0,0)';
      BIDIRECTIONAL='TRUE';
      INPUT_LOAD='(-0.01,0.01)';
      OUTPUT_LOAD='(1.0,-1.0)';
      PINUSE='BI';
    'GPP_L8_TESTCH0_D6':
      PIN_NUMBER='(0,0,0,0,0,0,0,AD9,0,0,0,0,0,0)';
      BIDIRECTIONAL='TRUE';
      INPUT_LOAD='(-0.01,0.01)';
      OUTPUT_LOAD='(1.0,-1.0)';
      PINUSE='BI';
    'GPP_L9_TESTCH0_D7':
      PIN_NUMBER='(0,0,0,0,0,0,0,AD17,0,0,0,0,0,0)';
      BIDIRECTIONAL='TRUE';
      INPUT_LOAD='(-0.01,0.01)';
      OUTPUT_LOAD='(1.0,-1.0)';
      PINUSE='BI';
    'HDA_BCLK':
      PIN_NUMBER='(0,0,0,0,0,0,0,P18,0,0,0,0,0,0)';
      BIDIRECTIONAL='TRUE';
      INPUT_LOAD='(-0.01,0.01)';
      OUTPUT_LOAD='(1.0,-1.0)';
      PINUSE='BI';
    'HDA_RST_N':
      PIN_NUMBER='(0,0,0,0,0,0,0,M18,0,0,0,0,0,0)';
      BIDIRECTIONAL='TRUE';
      INPUT_LOAD='(-0.01,0.01)';
      OUTPUT_LOAD='(1.0,-1.0)';
      PINUSE='BI';
    'HDA_SDI_0':
      PIN_NUMBER='(0,0,0,0,0,0,0,K20,0,0,0,0,0,0)';
      BIDIRECTIONAL='TRUE';
      INPUT_LOAD='(-0.01,0.01)';
      OUTPUT_LOAD='(1.0,-1.0)';
      PINUSE='BI';
    'HDA_SDI_1':
      PIN_NUMBER='(0,0,0,0,0,0,0,V18,0,0,0,0,0,0)';
      BIDIRECTIONAL='TRUE';
      INPUT_LOAD='(-0.01,0.01)';
      OUTPUT_LOAD='(1.0,-1.0)';
      PINUSE='BI';
    'HDA_SDO':
      PIN_NUMBER='(0,0,0,0,0,0,0,U24,0,0,0,0,0,0)';
      BIDIRECTIONAL='TRUE';
      INPUT_LOAD='(-0.01,0.01)';
      OUTPUT_LOAD='(1.0,-1.0)';
      PINUSE='BI';
    'HDA_SYNC':
      PIN_NUMBER='(0,0,0,0,0,0,0,H20,0,0,0,0,0,0)';
      BIDIRECTIONAL='TRUE';
      INPUT_LOAD='(-0.01,0.01)';
      OUTPUT_LOAD='(1.0,-1.0)';
      PINUSE='BI';
    'INTRUDER_N':
      PIN_NUMBER='(0,0,0,0,0,0,0,AG18,0,0,0,0,0,0)';
      BIDIRECTIONAL='TRUE';
      INPUT_LOAD='(-0.01,0.01)';
      OUTPUT_LOAD='(1.0,-1.0)';
      PINUSE='BI';
    'ITP_PMODE':
      PIN_NUMBER='(0,0,0,0,AR54,0,0,0,0,0,0,0,0,0)';
      BIDIRECTIONAL='TRUE';
      INPUT_LOAD='(-0.01,0.01)';
      OUTPUT_LOAD='(1.0,-1.0)';
      PINUSE='BI';
    'JTAGX':
      PIN_NUMBER='(0,0,0,0,AF54,0,0,0,0,0,0,0,0,0)';
      BIDIRECTIONAL='TRUE';
      INPUT_LOAD='(-0.01,0.01)';
      OUTPUT_LOAD='(1.0,-1.0)';
      PINUSE='BI';
    'JTAG_TCK':
      PIN_NUMBER='(0,0,0,0,AL56,0,0,0,0,0,0,0,0,0)';
      BIDIRECTIONAL='TRUE';
      INPUT_LOAD='(-0.01,0.01)';
      OUTPUT_LOAD='(1.0,-1.0)';
      PINUSE='BI';
    'JTAG_TDI':
      PIN_NUMBER='(0,0,0,0,AN54,0,0,0,0,0,0,0,0,0)';
      BIDIRECTIONAL='TRUE';
      INPUT_LOAD='(-0.01,0.01)';
      OUTPUT_LOAD='(1.0,-1.0)';
      PINUSE='BI';
    'JTAG_TDO':
      PIN_NUMBER='(0,0,0,0,AP56,0,0,0,0,0,0,0,0,0)';
      BIDIRECTIONAL='TRUE';
      INPUT_LOAD='(-0.01,0.01)';
      OUTPUT_LOAD='(1.0,-1.0)';
      PINUSE='BI';
    'JTAG_TMS':
      PIN_NUMBER='(0,0,0,0,AH54,0,0,0,0,0,0,0,0,0)';
      BIDIRECTIONAL='TRUE';
      INPUT_LOAD='(-0.01,0.01)';
      OUTPUT_LOAD='(1.0,-1.0)';
      PINUSE='BI';
    'LAN_RBIAS_0':
      PIN_NUMBER='(0,0,0,0,BB29,0,0,0,0,0,0,0,0,0)';
      BIDIRECTIONAL='TRUE';
      INPUT_LOAD='(-0.01,0.01)';
      OUTPUT_LOAD='(1.0,-1.0)';
      PINUSE='BI';
    'LAN_RBIAS_1':
      PIN_NUMBER='(0,0,0,0,BD42,0,0,0,0,0,0,0,0,0)';
      BIDIRECTIONAL='TRUE';
      INPUT_LOAD='(-0.01,0.01)';
      OUTPUT_LOAD='(1.0,-1.0)';
      PINUSE='BI';
    'LAN_RX_P0N':
      PIN_NUMBER='(0,0,0,0,BH31,0,0,0,0,0,0,0,0,0)';
      BIDIRECTIONAL='TRUE';
      INPUT_LOAD='(-0.01,0.01)';
      OUTPUT_LOAD='(1.0,-1.0)';
      PINUSE='BI';
    'LAN_RX_P0P':
      PIN_NUMBER='(0,0,0,0,BF31,0,0,0,0,0,0,0,0,0)';
      BIDIRECTIONAL='TRUE';
      INPUT_LOAD='(-0.01,0.01)';
      OUTPUT_LOAD='(1.0,-1.0)';
      PINUSE='BI';
    'LAN_RX_P1N':
      PIN_NUMBER='(0,0,0,0,BG29,0,0,0,0,0,0,0,0,0)';
      BIDIRECTIONAL='TRUE';
      INPUT_LOAD='(-0.01,0.01)';
      OUTPUT_LOAD='(1.0,-1.0)';
      PINUSE='BI';
    'LAN_RX_P1P':
      PIN_NUMBER='(0,0,0,0,BJ29,0,0,0,0,0,0,0,0,0)';
      BIDIRECTIONAL='TRUE';
      INPUT_LOAD='(-0.01,0.01)';
      OUTPUT_LOAD='(1.0,-1.0)';
      PINUSE='BI';
    'LAN_RX_P2N':
      PIN_NUMBER='(0,0,0,0,BJ37,0,0,0,0,0,0,0,0,0)';
      BIDIRECTIONAL='TRUE';
      INPUT_LOAD='(-0.01,0.01)';
      OUTPUT_LOAD='(1.0,-1.0)';
      PINUSE='BI';
    'LAN_RX_P2P':
      PIN_NUMBER='(0,0,0,0,BG37,0,0,0,0,0,0,0,0,0)';
      BIDIRECTIONAL='TRUE';
      INPUT_LOAD='(-0.01,0.01)';
      OUTPUT_LOAD='(1.0,-1.0)';
      PINUSE='BI';
    'LAN_RX_P3N':
      PIN_NUMBER='(0,0,0,0,BF35,0,0,0,0,0,0,0,0,0)';
      BIDIRECTIONAL='TRUE';
      INPUT_LOAD='(-0.01,0.01)';
      OUTPUT_LOAD='(1.0,-1.0)';
      PINUSE='BI';
    'LAN_RX_P3P':
      PIN_NUMBER='(0,0,0,0,BH35,0,0,0,0,0,0,0,0,0)';
      BIDIRECTIONAL='TRUE';
      INPUT_LOAD='(-0.01,0.01)';
      OUTPUT_LOAD='(1.0,-1.0)';
      PINUSE='BI';
    'LAN_TX_P0N':
      PIN_NUMBER='(0,0,0,0,BM27,0,0,0,0,0,0,0,0,0)';
      BIDIRECTIONAL='TRUE';
      INPUT_LOAD='(-0.01,0.01)';
      OUTPUT_LOAD='(1.0,-1.0)';
      PINUSE='BI';
    'LAN_TX_P0P':
      PIN_NUMBER='(0,0,0,0,BR27,0,0,0,0,0,0,0,0,0)';
      BIDIRECTIONAL='TRUE';
      INPUT_LOAD='(-0.01,0.01)';
      OUTPUT_LOAD='(1.0,-1.0)';
      PINUSE='BI';
    'LAN_TX_P1N':
      PIN_NUMBER='(0,0,0,0,BM24,0,0,0,0,0,0,0,0,0)';
      BIDIRECTIONAL='TRUE';
      INPUT_LOAD='(-0.01,0.01)';
      OUTPUT_LOAD='(1.0,-1.0)';
      PINUSE='BI';
    'LAN_TX_P1P':
      PIN_NUMBER='(0,0,0,0,BR24,0,0,0,0,0,0,0,0,0)';
      BIDIRECTIONAL='TRUE';
      INPUT_LOAD='(-0.01,0.01)';
      OUTPUT_LOAD='(1.0,-1.0)';
      PINUSE='BI';
    'LAN_TX_P2N':
      PIN_NUMBER='(0,0,0,0,BM35,0,0,0,0,0,0,0,0,0)';
      BIDIRECTIONAL='TRUE';
      INPUT_LOAD='(-0.01,0.01)';
      OUTPUT_LOAD='(1.0,-1.0)';
      PINUSE='BI';
    'LAN_TX_P2P':
      PIN_NUMBER='(0,0,0,0,BR35,0,0,0,0,0,0,0,0,0)';
      BIDIRECTIONAL='TRUE';
      INPUT_LOAD='(-0.01,0.01)';
      OUTPUT_LOAD='(1.0,-1.0)';
      PINUSE='BI';
    'LAN_TX_P3N':
      PIN_NUMBER='(0,0,0,0,BR31,0,0,0,0,0,0,0,0,0)';
      BIDIRECTIONAL='TRUE';
      INPUT_LOAD='(-0.01,0.01)';
      OUTPUT_LOAD='(1.0,-1.0)';
      PINUSE='BI';
    'LAN_TX_P3P':
      PIN_NUMBER='(0,0,0,0,BM31,0,0,0,0,0,0,0,0,0)';
      BIDIRECTIONAL='TRUE';
      INPUT_LOAD='(-0.01,0.01)';
      OUTPUT_LOAD='(1.0,-1.0)';
      PINUSE='BI';
    'LAN_XTAL_IN':
      PIN_NUMBER='(0,0,0,0,BV16,0,0,0,0,0,0,0,0,0)';
      BIDIRECTIONAL='TRUE';
      INPUT_LOAD='(-0.01,0.01)';
      OUTPUT_LOAD='(1.0,-1.0)';
      PINUSE='BI';
    'LAN_XTAL_OUT':
      PIN_NUMBER='(0,0,0,0,BY16,0,0,0,0,0,0,0,0,0)';
      BIDIRECTIONAL='TRUE';
      INPUT_LOAD='(-0.01,0.01)';
      OUTPUT_LOAD='(1.0,-1.0)';
      PINUSE='BI';
    'PCH_PWROK':
      PIN_NUMBER='(0,0,0,0,R17,0,0,0,0,0,0,0,0,0)';
      BIDIRECTIONAL='TRUE';
      INPUT_LOAD='(-0.01,0.01)';
      OUTPUT_LOAD='(1.0,-1.0)';
      PINUSE='BI';
    'PCIE10_SSATA4_RXN':
      PIN_NUMBER='(0,0,AV63,0,0,0,0,0,0,0,0,0,0,0)';
      BIDIRECTIONAL='TRUE';
      INPUT_LOAD='(-0.01,0.01)';
      OUTPUT_LOAD='(1.0,-1.0)';
      PINUSE='BI';
    'PCIE10_SSATA4_RXP':
      PIN_NUMBER='(0,0,AU65,0,0,0,0,0,0,0,0,0,0,0)';
      BIDIRECTIONAL='TRUE';
      INPUT_LOAD='(-0.01,0.01)';
      OUTPUT_LOAD='(1.0,-1.0)';
      PINUSE='BI';
    'PCIE10_SSATA4_TXN':
      PIN_NUMBER='(0,0,AD70,0,0,0,0,0,0,0,0,0,0,0)';
      BIDIRECTIONAL='TRUE';
      INPUT_LOAD='(-0.01,0.01)';
      OUTPUT_LOAD='(1.0,-1.0)';
      PINUSE='BI';
    'PCIE10_SSATA4_TXP':
      PIN_NUMBER='(0,0,AD72,0,0,0,0,0,0,0,0,0,0,0)';
      BIDIRECTIONAL='TRUE';
      INPUT_LOAD='(-0.01,0.01)';
      OUTPUT_LOAD='(1.0,-1.0)';
      PINUSE='BI';
    'PCIE11_SSATA5_GBE_RXN':
      PIN_NUMBER='(0,0,AT66,0,0,0,0,0,0,0,0,0,0,0)';
      BIDIRECTIONAL='TRUE';
      INPUT_LOAD='(-0.01,0.01)';
      OUTPUT_LOAD='(1.0,-1.0)';
      PINUSE='BI';
    'PCIE11_SSATA5_GBE_RXP':
      PIN_NUMBER='(0,0,AV66,0,0,0,0,0,0,0,0,0,0,0)';
      BIDIRECTIONAL='TRUE';
      INPUT_LOAD='(-0.01,0.01)';
      OUTPUT_LOAD='(1.0,-1.0)';
      PINUSE='BI';
    'PCIE11_SSATA5_GBE_TXN':
      PIN_NUMBER='(0,0,AC69,0,0,0,0,0,0,0,0,0,0,0)';
      BIDIRECTIONAL='TRUE';
      INPUT_LOAD='(-0.01,0.01)';
      OUTPUT_LOAD='(1.0,-1.0)';
      PINUSE='BI';
    'PCIE11_SSATA5_GBE_TXP':
      PIN_NUMBER='(0,0,AC71,0,0,0,0,0,0,0,0,0,0,0)';
      BIDIRECTIONAL='TRUE';
      INPUT_LOAD='(-0.01,0.01)';
      OUTPUT_LOAD='(1.0,-1.0)';
      PINUSE='BI';
    'PCIE12_UP0_SATA0_RXN':
      PIN_NUMBER='(0,0,AR61,0,0,0,0,0,0,0,0,0,0,0)';
      BIDIRECTIONAL='TRUE';
      INPUT_LOAD='(-0.01,0.01)';
      OUTPUT_LOAD='(1.0,-1.0)';
      PINUSE='BI';
    'PCIE12_UP0_SATA0_RXP':
      PIN_NUMBER='(0,0,AT63,0,0,0,0,0,0,0,0,0,0,0)';
      BIDIRECTIONAL='TRUE';
      INPUT_LOAD='(-0.01,0.01)';
      OUTPUT_LOAD='(1.0,-1.0)';
      PINUSE='BI';
    'PCIE12_UP0_SATA0_TXN':
      PIN_NUMBER='(0,0,W69,0,0,0,0,0,0,0,0,0,0,0)';
      BIDIRECTIONAL='TRUE';
      INPUT_LOAD='(-0.01,0.01)';
      OUTPUT_LOAD='(1.0,-1.0)';
      PINUSE='BI';
    'PCIE12_UP0_SATA0_TXP':
      PIN_NUMBER='(0,0,W71,0,0,0,0,0,0,0,0,0,0,0)';
      BIDIRECTIONAL='TRUE';
      INPUT_LOAD='(-0.01,0.01)';
      OUTPUT_LOAD='(1.0,-1.0)';
      PINUSE='BI';
    'PCIE13_UP1_SATA1_RXN':
      PIN_NUMBER='(0,0,AL66,0,0,0,0,0,0,0,0,0,0,0)';
      BIDIRECTIONAL='TRUE';
      INPUT_LOAD='(-0.01,0.01)';
      OUTPUT_LOAD='(1.0,-1.0)';
      PINUSE='BI';
    'PCIE13_UP1_SATA1_RXP':
      PIN_NUMBER='(0,0,AN65,0,0,0,0,0,0,0,0,0,0,0)';
      BIDIRECTIONAL='TRUE';
      INPUT_LOAD='(-0.01,0.01)';
      OUTPUT_LOAD='(1.0,-1.0)';
      PINUSE='BI';
    'PCIE13_UP1_SATA1_TXN':
      PIN_NUMBER='(0,0,V70,0,0,0,0,0,0,0,0,0,0,0)';
      BIDIRECTIONAL='TRUE';
      INPUT_LOAD='(-0.01,0.01)';
      OUTPUT_LOAD='(1.0,-1.0)';
      PINUSE='BI';
    'PCIE13_UP1_SATA1_TXP':
      PIN_NUMBER='(0,0,V72,0,0,0,0,0,0,0,0,0,0,0)';
      BIDIRECTIONAL='TRUE';
      INPUT_LOAD='(-0.01,0.01)';
      OUTPUT_LOAD='(1.0,-1.0)';
      PINUSE='BI';
    'PCIE14_UP2_SATA2_RXN':
      PIN_NUMBER='(0,0,AK65,0,0,0,0,0,0,0,0,0,0,0)';
      BIDIRECTIONAL='TRUE';
      INPUT_LOAD='(-0.01,0.01)';
      OUTPUT_LOAD='(1.0,-1.0)';
      PINUSE='BI';
    'PCIE14_UP2_SATA2_RXP':
      PIN_NUMBER='(0,0,AJ63,0,0,0,0,0,0,0,0,0,0,0)';
      BIDIRECTIONAL='TRUE';
      INPUT_LOAD='(-0.01,0.01)';
      OUTPUT_LOAD='(1.0,-1.0)';
      PINUSE='BI';
    'PCIE14_UP2_SATA2_TXN':
      PIN_NUMBER='(0,0,T69,0,0,0,0,0,0,0,0,0,0,0)';
      BIDIRECTIONAL='TRUE';
      INPUT_LOAD='(-0.01,0.01)';
      OUTPUT_LOAD='(1.0,-1.0)';
      PINUSE='BI';
    'PCIE14_UP2_SATA2_TXP':
      PIN_NUMBER='(0,0,T71,0,0,0,0,0,0,0,0,0,0,0)';
      BIDIRECTIONAL='TRUE';
      INPUT_LOAD='(-0.01,0.01)';
      OUTPUT_LOAD='(1.0,-1.0)';
      PINUSE='BI';
    'PCIE15_UP3_SATA3_RXN':
      PIN_NUMBER='(0,0,AP63,0,0,0,0,0,0,0,0,0,0,0)';
      BIDIRECTIONAL='TRUE';
      INPUT_LOAD='(-0.01,0.01)';
      OUTPUT_LOAD='(1.0,-1.0)';
      PINUSE='BI';
    'PCIE15_UP3_SATA3_RXP':
      PIN_NUMBER='(0,0,AL63,0,0,0,0,0,0,0,0,0,0,0)';
      BIDIRECTIONAL='TRUE';
      INPUT_LOAD='(-0.01,0.01)';
      OUTPUT_LOAD='(1.0,-1.0)';
      PINUSE='BI';
    'PCIE15_UP3_SATA3_TXN':
      PIN_NUMBER='(0,0,R70,0,0,0,0,0,0,0,0,0,0,0)';
      BIDIRECTIONAL='TRUE';
      INPUT_LOAD='(-0.01,0.01)';
      OUTPUT_LOAD='(1.0,-1.0)';
      PINUSE='BI';
    'PCIE15_UP3_SATA3_TXP':
      PIN_NUMBER='(0,0,R72,0,0,0,0,0,0,0,0,0,0,0)';
      BIDIRECTIONAL='TRUE';
      INPUT_LOAD='(-0.01,0.01)';
      OUTPUT_LOAD='(1.0,-1.0)';
      PINUSE='BI';
    'PCIE16_UP4_SATA4_RXN':
      PIN_NUMBER='(0,0,AF65,0,0,0,0,0,0,0,0,0,0,0)';
      BIDIRECTIONAL='TRUE';
      INPUT_LOAD='(-0.01,0.01)';
      OUTPUT_LOAD='(1.0,-1.0)';
      PINUSE='BI';
    'PCIE16_UP4_SATA4_RXP':
      PIN_NUMBER='(0,0,AH65,0,0,0,0,0,0,0,0,0,0,0)';
      BIDIRECTIONAL='TRUE';
      INPUT_LOAD='(-0.01,0.01)';
      OUTPUT_LOAD='(1.0,-1.0)';
      PINUSE='BI';
    'PCIE16_UP4_SATA4_TXN':
      PIN_NUMBER='(0,0,P69,0,0,0,0,0,0,0,0,0,0,0)';
      BIDIRECTIONAL='TRUE';
      INPUT_LOAD='(-0.01,0.01)';
      OUTPUT_LOAD='(1.0,-1.0)';
      PINUSE='BI';
    'PCIE16_UP4_SATA4_TXP':
      PIN_NUMBER='(0,0,P71,0,0,0,0,0,0,0,0,0,0,0)';
      BIDIRECTIONAL='TRUE';
      INPUT_LOAD='(-0.01,0.01)';
      OUTPUT_LOAD='(1.0,-1.0)';
      PINUSE='BI';
    'PCIE17_UP5_SATA5_RXN':
      PIN_NUMBER='(0,0,AH61,0,0,0,0,0,0,0,0,0,0,0)';
      BIDIRECTIONAL='TRUE';
      INPUT_LOAD='(-0.01,0.01)';
      OUTPUT_LOAD='(1.0,-1.0)';
      PINUSE='BI';
    'PCIE17_UP5_SATA5_RXP':
      PIN_NUMBER='(0,0,AG63,0,0,0,0,0,0,0,0,0,0,0)';
      BIDIRECTIONAL='TRUE';
      INPUT_LOAD='(-0.01,0.01)';
      OUTPUT_LOAD='(1.0,-1.0)';
      PINUSE='BI';
    'PCIE17_UP5_SATA5_TXN':
      PIN_NUMBER='(0,0,N70,0,0,0,0,0,0,0,0,0,0,0)';
      BIDIRECTIONAL='TRUE';
      INPUT_LOAD='(-0.01,0.01)';
      OUTPUT_LOAD='(1.0,-1.0)';
      PINUSE='BI';
    'PCIE17_UP5_SATA5_TXP':
      PIN_NUMBER='(0,0,N72,0,0,0,0,0,0,0,0,0,0,0)';
      BIDIRECTIONAL='TRUE';
      INPUT_LOAD='(-0.01,0.01)';
      OUTPUT_LOAD='(1.0,-1.0)';
      PINUSE='BI';
    'PCIE18_UP6_SATA6_RXN':
      PIN_NUMBER='(0,0,AP59,0,0,0,0,0,0,0,0,0,0,0)';
      BIDIRECTIONAL='TRUE';
      INPUT_LOAD='(-0.01,0.01)';
      OUTPUT_LOAD='(1.0,-1.0)';
      PINUSE='BI';
    'PCIE18_UP6_SATA6_RXP':
      PIN_NUMBER='(0,0,AN61,0,0,0,0,0,0,0,0,0,0,0)';
      BIDIRECTIONAL='TRUE';
      INPUT_LOAD='(-0.01,0.01)';
      OUTPUT_LOAD='(1.0,-1.0)';
      PINUSE='BI';
    'PCIE18_UP6_SATA6_TXN':
      PIN_NUMBER='(0,0,M69,0,0,0,0,0,0,0,0,0,0,0)';
      BIDIRECTIONAL='TRUE';
      INPUT_LOAD='(-0.01,0.01)';
      OUTPUT_LOAD='(1.0,-1.0)';
      PINUSE='BI';
    'PCIE18_UP6_SATA6_TXP':
      PIN_NUMBER='(0,0,M71,0,0,0,0,0,0,0,0,0,0,0)';
      BIDIRECTIONAL='TRUE';
      INPUT_LOAD='(-0.01,0.01)';
      OUTPUT_LOAD='(1.0,-1.0)';
      PINUSE='BI';
    'PCIE19_UP7_SATA7_RXN':
      PIN_NUMBER='(0,0,AA61,0,0,0,0,0,0,0,0,0,0,0)';
      BIDIRECTIONAL='TRUE';
      INPUT_LOAD='(-0.01,0.01)';
      OUTPUT_LOAD='(1.0,-1.0)';
      PINUSE='BI';
    'PCIE19_UP7_SATA7_RXP':
      PIN_NUMBER='(0,0,AD61,0,0,0,0,0,0,0,0,0,0,0)';
      BIDIRECTIONAL='TRUE';
      INPUT_LOAD='(-0.01,0.01)';
      OUTPUT_LOAD='(1.0,-1.0)';
      PINUSE='BI';
    'PCIE19_UP7_SATA7_TXN':
      PIN_NUMBER='(0,0,L70,0,0,0,0,0,0,0,0,0,0,0)';
      BIDIRECTIONAL='TRUE';
      INPUT_LOAD='(-0.01,0.01)';
      OUTPUT_LOAD='(1.0,-1.0)';
      PINUSE='BI';
    'PCIE19_UP7_SATA7_TXP':
      PIN_NUMBER='(0,0,L72,0,0,0,0,0,0,0,0,0,0,0)';
      BIDIRECTIONAL='TRUE';
      INPUT_LOAD='(-0.01,0.01)';
      OUTPUT_LOAD='(1.0,-1.0)';
      PINUSE='BI';
    'PCIE4_GBE_RXN':
      PIN_NUMBER='(0,0,AN70,0,0,0,0,0,0,0,0,0,0,0)';
      BIDIRECTIONAL='TRUE';
      INPUT_LOAD='(-0.01,0.01)';
      OUTPUT_LOAD='(1.0,-1.0)';
      PINUSE='BI';
    'PCIE4_GBE_RXP':
      PIN_NUMBER='(0,0,AN72,0,0,0,0,0,0,0,0,0,0,0)';
      BIDIRECTIONAL='TRUE';
      INPUT_LOAD='(-0.01,0.01)';
      OUTPUT_LOAD='(1.0,-1.0)';
      PINUSE='BI';
    'PCIE4_GBE_TXN':
      PIN_NUMBER='(0,0,BG66,0,0,0,0,0,0,0,0,0,0,0)';
      BIDIRECTIONAL='TRUE';
      INPUT_LOAD='(-0.01,0.01)';
      OUTPUT_LOAD='(1.0,-1.0)';
      PINUSE='BI';
    'PCIE4_GBE_TXP':
      PIN_NUMBER='(0,0,BJ66,0,0,0,0,0,0,0,0,0,0,0)';
      BIDIRECTIONAL='TRUE';
      INPUT_LOAD='(-0.01,0.01)';
      OUTPUT_LOAD='(1.0,-1.0)';
      PINUSE='BI';
    'PCIE5_GBE_RXN':
      PIN_NUMBER='(0,0,AM69,0,0,0,0,0,0,0,0,0,0,0)';
      BIDIRECTIONAL='TRUE';
      INPUT_LOAD='(-0.01,0.01)';
      OUTPUT_LOAD='(1.0,-1.0)';
      PINUSE='BI';
    'PCIE5_GBE_RXP':
      PIN_NUMBER='(0,0,AM71,0,0,0,0,0,0,0,0,0,0,0)';
      BIDIRECTIONAL='TRUE';
      INPUT_LOAD='(-0.01,0.01)';
      OUTPUT_LOAD='(1.0,-1.0)';
      PINUSE='BI';
    'PCIE5_GBE_TXN':
      PIN_NUMBER='(0,0,BH65,0,0,0,0,0,0,0,0,0,0,0)';
      BIDIRECTIONAL='TRUE';
      INPUT_LOAD='(-0.01,0.01)';
      OUTPUT_LOAD='(1.0,-1.0)';
      PINUSE='BI';
    'PCIE5_GBE_TXP':
      PIN_NUMBER='(0,0,BJ63,0,0,0,0,0,0,0,0,0,0,0)';
      BIDIRECTIONAL='TRUE';
      INPUT_LOAD='(-0.01,0.01)';
      OUTPUT_LOAD='(1.0,-1.0)';
      PINUSE='BI';
    'PCIE6_SSATA0_RXN':
      PIN_NUMBER='(0,0,BB63,0,0,0,0,0,0,0,0,0,0,0)';
      BIDIRECTIONAL='TRUE';
      INPUT_LOAD='(-0.01,0.01)';
      OUTPUT_LOAD='(1.0,-1.0)';
      PINUSE='BI';
    'PCIE6_SSATA0_RXP':
      PIN_NUMBER='(0,0,BD61,0,0,0,0,0,0,0,0,0,0,0)';
      BIDIRECTIONAL='TRUE';
      INPUT_LOAD='(-0.01,0.01)';
      OUTPUT_LOAD='(1.0,-1.0)';
      PINUSE='BI';
    'PCIE6_SSATA0_TXN':
      PIN_NUMBER='(0,0,AJ70,0,0,0,0,0,0,0,0,0,0,0)';
      BIDIRECTIONAL='TRUE';
      INPUT_LOAD='(-0.01,0.01)';
      OUTPUT_LOAD='(1.0,-1.0)';
      PINUSE='BI';
    'PCIE6_SSATA0_TXP':
      PIN_NUMBER='(0,0,AJ72,0,0,0,0,0,0,0,0,0,0,0)';
      BIDIRECTIONAL='TRUE';
      INPUT_LOAD='(-0.01,0.01)';
      OUTPUT_LOAD='(1.0,-1.0)';
      PINUSE='BI';
    'PCIE7_SSATA1_RXN':
      PIN_NUMBER='(0,0,AY59,0,0,0,0,0,0,0,0,0,0,0)';
      BIDIRECTIONAL='TRUE';
      INPUT_LOAD='(-0.01,0.01)';
      OUTPUT_LOAD='(1.0,-1.0)';
      PINUSE='BI';
    'PCIE7_SSATA1_RXP':
      PIN_NUMBER='(0,0,BA61,0,0,0,0,0,0,0,0,0,0,0)';
      BIDIRECTIONAL='TRUE';
      INPUT_LOAD='(-0.01,0.01)';
      OUTPUT_LOAD='(1.0,-1.0)';
      PINUSE='BI';
    'PCIE7_SSATA1_TXN':
      PIN_NUMBER='(0,0,AH69,0,0,0,0,0,0,0,0,0,0,0)';
      BIDIRECTIONAL='TRUE';
      INPUT_LOAD='(-0.01,0.01)';
      OUTPUT_LOAD='(1.0,-1.0)';
      PINUSE='BI';
    'PCIE7_SSATA1_TXP':
      PIN_NUMBER='(0,0,AH71,0,0,0,0,0,0,0,0,0,0,0)';
      BIDIRECTIONAL='TRUE';
      INPUT_LOAD='(-0.01,0.01)';
      OUTPUT_LOAD='(1.0,-1.0)';
      PINUSE='BI';
    'PCIE8_SSATA2_GBE_RXN':
      PIN_NUMBER='(0,0,BA65,0,0,0,0,0,0,0,0,0,0,0)';
      BIDIRECTIONAL='TRUE';
      INPUT_LOAD='(-0.01,0.01)';
      OUTPUT_LOAD='(1.0,-1.0)';
      PINUSE='BI';
    'PCIE8_SSATA2_GBE_RXP':
      PIN_NUMBER='(0,0,BD65,0,0,0,0,0,0,0,0,0,0,0)';
      BIDIRECTIONAL='TRUE';
      INPUT_LOAD='(-0.01,0.01)';
      OUTPUT_LOAD='(1.0,-1.0)';
      PINUSE='BI';
    'PCIE8_SSATA2_GBE_TXN':
      PIN_NUMBER='(0,0,AF70,0,0,0,0,0,0,0,0,0,0,0)';
      BIDIRECTIONAL='TRUE';
      INPUT_LOAD='(-0.01,0.01)';
      OUTPUT_LOAD='(1.0,-1.0)';
      PINUSE='BI';
    'PCIE8_SSATA2_GBE_TXP':
      PIN_NUMBER='(0,0,AF72,0,0,0,0,0,0,0,0,0,0,0)';
      BIDIRECTIONAL='TRUE';
      INPUT_LOAD='(-0.01,0.01)';
      OUTPUT_LOAD='(1.0,-1.0)';
      PINUSE='BI';
    'PCIE9_SSATA3_RXN':
      PIN_NUMBER='(0,0,AW65,0,0,0,0,0,0,0,0,0,0,0)';
      BIDIRECTIONAL='TRUE';
      INPUT_LOAD='(-0.01,0.01)';
      OUTPUT_LOAD='(1.0,-1.0)';
      PINUSE='BI';
    'PCIE9_SSATA3_RXP':
      PIN_NUMBER='(0,0,AY66,0,0,0,0,0,0,0,0,0,0,0)';
      BIDIRECTIONAL='TRUE';
      INPUT_LOAD='(-0.01,0.01)';
      OUTPUT_LOAD='(1.0,-1.0)';
      PINUSE='BI';
    'PCIE9_SSATA3_TXN':
      PIN_NUMBER='(0,0,AE69,0,0,0,0,0,0,0,0,0,0,0)';
      BIDIRECTIONAL='TRUE';
      INPUT_LOAD='(-0.01,0.01)';
      OUTPUT_LOAD='(1.0,-1.0)';
      PINUSE='BI';
    'PCIE9_SSATA3_TXP':
      PIN_NUMBER='(0,0,AE71,0,0,0,0,0,0,0,0,0,0,0)';
      BIDIRECTIONAL='TRUE';
      INPUT_LOAD='(-0.01,0.01)';
      OUTPUT_LOAD='(1.0,-1.0)';
      PINUSE='BI';
    'PCIEUP_0_RXN':
      PIN_NUMBER='(0,0,0,C48,0,0,0,0,0,0,0,0,0,0)';
      BIDIRECTIONAL='TRUE';
      INPUT_LOAD='(-0.01,0.01)';
      OUTPUT_LOAD='(1.0,-1.0)';
      PINUSE='BI';
    'PCIEUP_0_RXP':
      PIN_NUMBER='(0,0,0,A48,0,0,0,0,0,0,0,0,0,0)';
      BIDIRECTIONAL='TRUE';
      INPUT_LOAD='(-0.01,0.01)';
      OUTPUT_LOAD='(1.0,-1.0)';
      PINUSE='BI';
    'PCIEUP_0_TXN':
      PIN_NUMBER='(0,0,0,J52,0,0,0,0,0,0,0,0,0,0)';
      BIDIRECTIONAL='TRUE';
      INPUT_LOAD='(-0.01,0.01)';
      OUTPUT_LOAD='(1.0,-1.0)';
      PINUSE='BI';
    'PCIEUP_0_TXP':
      PIN_NUMBER='(0,0,0,G52,0,0,0,0,0,0,0,0,0,0)';
      BIDIRECTIONAL='TRUE';
      INPUT_LOAD='(-0.01,0.01)';
      OUTPUT_LOAD='(1.0,-1.0)';
      PINUSE='BI';
    'PCIEUP_10_RXN':
      PIN_NUMBER='(0,0,0,C59,0,0,0,0,0,0,0,0,0,0)';
      BIDIRECTIONAL='TRUE';
      INPUT_LOAD='(-0.01,0.01)';
      OUTPUT_LOAD='(1.0,-1.0)';
      PINUSE='BI';
    'PCIEUP_10_RXP':
      PIN_NUMBER='(0,0,0,A59,0,0,0,0,0,0,0,0,0,0)';
      BIDIRECTIONAL='TRUE';
      INPUT_LOAD='(-0.01,0.01)';
      OUTPUT_LOAD='(1.0,-1.0)';
      PINUSE='BI';
    'PCIEUP_10_TXN':
      PIN_NUMBER='(0,0,0,N65,0,0,0,0,0,0,0,0,0,0)';
      BIDIRECTIONAL='TRUE';
      INPUT_LOAD='(-0.01,0.01)';
      OUTPUT_LOAD='(1.0,-1.0)';
      PINUSE='BI';
    'PCIEUP_10_TXP':
      PIN_NUMBER='(0,0,0,P66,0,0,0,0,0,0,0,0,0,0)';
      BIDIRECTIONAL='TRUE';
      INPUT_LOAD='(-0.01,0.01)';
      OUTPUT_LOAD='(1.0,-1.0)';
      PINUSE='BI';
    'PCIEUP_11_RXN':
      PIN_NUMBER='(0,0,0,D60,0,0,0,0,0,0,0,0,0,0)';
      BIDIRECTIONAL='TRUE';
      INPUT_LOAD='(-0.01,0.01)';
      OUTPUT_LOAD='(1.0,-1.0)';
      PINUSE='BI';
    'PCIEUP_11_RXP':
      PIN_NUMBER='(0,0,0,B60,0,0,0,0,0,0,0,0,0,0)';
      BIDIRECTIONAL='TRUE';
      INPUT_LOAD='(-0.01,0.01)';
      OUTPUT_LOAD='(1.0,-1.0)';
      PINUSE='BI';
    'PCIEUP_11_TXN':
      PIN_NUMBER='(0,0,0,T59,0,0,0,0,0,0,0,0,0,0)';
      BIDIRECTIONAL='TRUE';
      INPUT_LOAD='(-0.01,0.01)';
      OUTPUT_LOAD='(1.0,-1.0)';
      PINUSE='BI';
    'PCIEUP_11_TXP':
      PIN_NUMBER='(0,0,0,V59,0,0,0,0,0,0,0,0,0,0)';
      BIDIRECTIONAL='TRUE';
      INPUT_LOAD='(-0.01,0.01)';
      OUTPUT_LOAD='(1.0,-1.0)';
      PINUSE='BI';
    'PCIEUP_12_RXN':
      PIN_NUMBER='(0,0,0,C61,0,0,0,0,0,0,0,0,0,0)';
      BIDIRECTIONAL='TRUE';
      INPUT_LOAD='(-0.01,0.01)';
      OUTPUT_LOAD='(1.0,-1.0)';
      PINUSE='BI';
    'PCIEUP_12_RXP':
      PIN_NUMBER='(0,0,0,A61,0,0,0,0,0,0,0,0,0,0)';
      BIDIRECTIONAL='TRUE';
      INPUT_LOAD='(-0.01,0.01)';
      OUTPUT_LOAD='(1.0,-1.0)';
      PINUSE='BI';
    'PCIEUP_12_TXN':
      PIN_NUMBER='(0,0,0,R65,0,0,0,0,0,0,0,0,0,0)';
      BIDIRECTIONAL='TRUE';
      INPUT_LOAD='(-0.01,0.01)';
      OUTPUT_LOAD='(1.0,-1.0)';
      PINUSE='BI';
    'PCIEUP_12_TXP':
      PIN_NUMBER='(0,0,0,U65,0,0,0,0,0,0,0,0,0,0)';
      BIDIRECTIONAL='TRUE';
      INPUT_LOAD='(-0.01,0.01)';
      OUTPUT_LOAD='(1.0,-1.0)';
      PINUSE='BI';
    'PCIEUP_13_RXN':
      PIN_NUMBER='(0,0,0,D62,0,0,0,0,0,0,0,0,0,0)';
      BIDIRECTIONAL='TRUE';
      INPUT_LOAD='(-0.01,0.01)';
      OUTPUT_LOAD='(1.0,-1.0)';
      PINUSE='BI';
    'PCIEUP_13_RXP':
      PIN_NUMBER='(0,0,0,B62,0,0,0,0,0,0,0,0,0,0)';
      BIDIRECTIONAL='TRUE';
      INPUT_LOAD='(-0.01,0.01)';
      OUTPUT_LOAD='(1.0,-1.0)';
      PINUSE='BI';
    'PCIEUP_13_TXN':
      PIN_NUMBER='(0,0,0,T63,0,0,0,0,0,0,0,0,0,0)';
      BIDIRECTIONAL='TRUE';
      INPUT_LOAD='(-0.01,0.01)';
      OUTPUT_LOAD='(1.0,-1.0)';
      PINUSE='BI';
    'PCIEUP_13_TXP':
      PIN_NUMBER='(0,0,0,U61,0,0,0,0,0,0,0,0,0,0)';
      BIDIRECTIONAL='TRUE';
      INPUT_LOAD='(-0.01,0.01)';
      OUTPUT_LOAD='(1.0,-1.0)';
      PINUSE='BI';
    'PCIEUP_14_RXN':
      PIN_NUMBER='(0,0,0,C63,0,0,0,0,0,0,0,0,0,0)';
      BIDIRECTIONAL='TRUE';
      INPUT_LOAD='(-0.01,0.01)';
      OUTPUT_LOAD='(1.0,-1.0)';
      PINUSE='BI';
    'PCIEUP_14_RXP':
      PIN_NUMBER='(0,0,0,A63,0,0,0,0,0,0,0,0,0,0)';
      BIDIRECTIONAL='TRUE';
      INPUT_LOAD='(-0.01,0.01)';
      OUTPUT_LOAD='(1.0,-1.0)';
      PINUSE='BI';
    'PCIEUP_14_TXN':
      PIN_NUMBER='(0,0,0,W65,0,0,0,0,0,0,0,0,0,0)';
      BIDIRECTIONAL='TRUE';
      INPUT_LOAD='(-0.01,0.01)';
      OUTPUT_LOAD='(1.0,-1.0)';
      PINUSE='BI';
    'PCIEUP_14_TXP':
      PIN_NUMBER='(0,0,0,V63,0,0,0,0,0,0,0,0,0,0)';
      BIDIRECTIONAL='TRUE';
      INPUT_LOAD='(-0.01,0.01)';
      OUTPUT_LOAD='(1.0,-1.0)';
      PINUSE='BI';
    'PCIEUP_15_RXN':
      PIN_NUMBER='(0,0,0,D64,0,0,0,0,0,0,0,0,0,0)';
      BIDIRECTIONAL='TRUE';
      INPUT_LOAD='(-0.01,0.01)';
      OUTPUT_LOAD='(1.0,-1.0)';
      PINUSE='BI';
    'PCIEUP_15_RXP':
      PIN_NUMBER='(0,0,0,B64,0,0,0,0,0,0,0,0,0,0)';
      BIDIRECTIONAL='TRUE';
      INPUT_LOAD='(-0.01,0.01)';
      OUTPUT_LOAD='(1.0,-1.0)';
      PINUSE='BI';
    'PCIEUP_15_TXN':
      PIN_NUMBER='(0,0,0,Y66,0,0,0,0,0,0,0,0,0,0)';
      BIDIRECTIONAL='TRUE';
      INPUT_LOAD='(-0.01,0.01)';
      OUTPUT_LOAD='(1.0,-1.0)';
      PINUSE='BI';
    'PCIEUP_15_TXP':
      PIN_NUMBER='(0,0,0,AA65,0,0,0,0,0,0,0,0,0,0)';
      BIDIRECTIONAL='TRUE';
      INPUT_LOAD='(-0.01,0.01)';
      OUTPUT_LOAD='(1.0,-1.0)';
      PINUSE='BI';
    'PCIEUP_1_RXN':
      PIN_NUMBER='(0,0,0,D49,0,0,0,0,0,0,0,0,0,0)';
      BIDIRECTIONAL='TRUE';
      INPUT_LOAD='(-0.01,0.01)';
      OUTPUT_LOAD='(1.0,-1.0)';
      PINUSE='BI';
    'PCIEUP_1_RXP':
      PIN_NUMBER='(0,0,0,B49,0,0,0,0,0,0,0,0,0,0)';
      BIDIRECTIONAL='TRUE';
      INPUT_LOAD='(-0.01,0.01)';
      OUTPUT_LOAD='(1.0,-1.0)';
      PINUSE='BI';
    'PCIEUP_1_TXN':
      PIN_NUMBER='(0,0,0,P56,0,0,0,0,0,0,0,0,0,0)';
      BIDIRECTIONAL='TRUE';
      INPUT_LOAD='(-0.01,0.01)';
      OUTPUT_LOAD='(1.0,-1.0)';
      PINUSE='BI';
    'PCIEUP_1_TXP':
      PIN_NUMBER='(0,0,0,M56,0,0,0,0,0,0,0,0,0,0)';
      BIDIRECTIONAL='TRUE';
      INPUT_LOAD='(-0.01,0.01)';
      OUTPUT_LOAD='(1.0,-1.0)';
      PINUSE='BI';
    'PCIEUP_2_RXN':
      PIN_NUMBER='(0,0,0,C50,0,0,0,0,0,0,0,0,0,0)';
      BIDIRECTIONAL='TRUE';
      INPUT_LOAD='(-0.01,0.01)';
      OUTPUT_LOAD='(1.0,-1.0)';
      PINUSE='BI';
    'PCIEUP_2_RXP':
      PIN_NUMBER='(0,0,0,A50,0,0,0,0,0,0,0,0,0,0)';
      BIDIRECTIONAL='TRUE';
      INPUT_LOAD='(-0.01,0.01)';
      OUTPUT_LOAD='(1.0,-1.0)';
      PINUSE='BI';
    'PCIEUP_2_TXN':
      PIN_NUMBER='(0,0,0,H54,0,0,0,0,0,0,0,0,0,0)';
      BIDIRECTIONAL='TRUE';
      INPUT_LOAD='(-0.01,0.01)';
      OUTPUT_LOAD='(1.0,-1.0)';
      PINUSE='BI';
    'PCIEUP_2_TXP':
      PIN_NUMBER='(0,0,0,G56,0,0,0,0,0,0,0,0,0,0)';
      BIDIRECTIONAL='TRUE';
      INPUT_LOAD='(-0.01,0.01)';
      OUTPUT_LOAD='(1.0,-1.0)';
      PINUSE='BI';
    'PCIEUP_3_RXN':
      PIN_NUMBER='(0,0,0,D51,0,0,0,0,0,0,0,0,0,0)';
      BIDIRECTIONAL='TRUE';
      INPUT_LOAD='(-0.01,0.01)';
      OUTPUT_LOAD='(1.0,-1.0)';
      PINUSE='BI';
    'PCIEUP_3_RXP':
      PIN_NUMBER='(0,0,0,B51,0,0,0,0,0,0,0,0,0,0)';
      BIDIRECTIONAL='TRUE';
      INPUT_LOAD='(-0.01,0.01)';
      OUTPUT_LOAD='(1.0,-1.0)';
      PINUSE='BI';
    'PCIEUP_3_TXN':
      PIN_NUMBER='(0,0,0,J56,0,0,0,0,0,0,0,0,0,0)';
      BIDIRECTIONAL='TRUE';
      INPUT_LOAD='(-0.01,0.01)';
      OUTPUT_LOAD='(1.0,-1.0)';
      PINUSE='BI';
    'PCIEUP_3_TXP':
      PIN_NUMBER='(0,0,0,K58,0,0,0,0,0,0,0,0,0,0)';
      BIDIRECTIONAL='TRUE';
      INPUT_LOAD='(-0.01,0.01)';
      OUTPUT_LOAD='(1.0,-1.0)';
      PINUSE='BI';
    'PCIEUP_4_RXN':
      PIN_NUMBER='(0,0,0,C52,0,0,0,0,0,0,0,0,0,0)';
      BIDIRECTIONAL='TRUE';
      INPUT_LOAD='(-0.01,0.01)';
      OUTPUT_LOAD='(1.0,-1.0)';
      PINUSE='BI';
    'PCIEUP_4_RXP':
      PIN_NUMBER='(0,0,0,A52,0,0,0,0,0,0,0,0,0,0)';
      BIDIRECTIONAL='TRUE';
      INPUT_LOAD='(-0.01,0.01)';
      OUTPUT_LOAD='(1.0,-1.0)';
      PINUSE='BI';
    'PCIEUP_4_TXN':
      PIN_NUMBER='(0,0,0,N58,0,0,0,0,0,0,0,0,0,0)';
      BIDIRECTIONAL='TRUE';
      INPUT_LOAD='(-0.01,0.01)';
      OUTPUT_LOAD='(1.0,-1.0)';
      PINUSE='BI';
    'PCIEUP_4_TXP':
      PIN_NUMBER='(0,0,0,M59,0,0,0,0,0,0,0,0,0,0)';
      BIDIRECTIONAL='TRUE';
      INPUT_LOAD='(-0.01,0.01)';
      OUTPUT_LOAD='(1.0,-1.0)';
      PINUSE='BI';
    'PCIEUP_5_RXN':
      PIN_NUMBER='(0,0,0,D53,0,0,0,0,0,0,0,0,0,0)';
      BIDIRECTIONAL='TRUE';
      INPUT_LOAD='(-0.01,0.01)';
      OUTPUT_LOAD='(1.0,-1.0)';
      PINUSE='BI';
    'PCIEUP_5_RXP':
      PIN_NUMBER='(0,0,0,B53,0,0,0,0,0,0,0,0,0,0)';
      BIDIRECTIONAL='TRUE';
      INPUT_LOAD='(-0.01,0.01)';
      OUTPUT_LOAD='(1.0,-1.0)';
      PINUSE='BI';
    'PCIEUP_5_TXN':
      PIN_NUMBER='(0,0,0,N61,0,0,0,0,0,0,0,0,0,0)';
      BIDIRECTIONAL='TRUE';
      INPUT_LOAD='(-0.01,0.01)';
      OUTPUT_LOAD='(1.0,-1.0)';
      PINUSE='BI';
    'PCIEUP_5_TXP':
      PIN_NUMBER='(0,0,0,K61,0,0,0,0,0,0,0,0,0,0)';
      BIDIRECTIONAL='TRUE';
      INPUT_LOAD='(-0.01,0.01)';
      OUTPUT_LOAD='(1.0,-1.0)';
      PINUSE='BI';
    'PCIEUP_6_RXN':
      PIN_NUMBER='(0,0,0,C54,0,0,0,0,0,0,0,0,0,0)';
      BIDIRECTIONAL='TRUE';
      INPUT_LOAD='(-0.01,0.01)';
      OUTPUT_LOAD='(1.0,-1.0)';
      PINUSE='BI';
    'PCIEUP_6_RXP':
      PIN_NUMBER='(0,0,0,A54,0,0,0,0,0,0,0,0,0,0)';
      BIDIRECTIONAL='TRUE';
      INPUT_LOAD='(-0.01,0.01)';
      OUTPUT_LOAD='(1.0,-1.0)';
      PINUSE='BI';
    'PCIEUP_6_TXN':
      PIN_NUMBER='(0,0,0,H61,0,0,0,0,0,0,0,0,0,0)';
      BIDIRECTIONAL='TRUE';
      INPUT_LOAD='(-0.01,0.01)';
      OUTPUT_LOAD='(1.0,-1.0)';
      PINUSE='BI';
    'PCIEUP_6_TXP':
      PIN_NUMBER='(0,0,0,J63,0,0,0,0,0,0,0,0,0,0)';
      BIDIRECTIONAL='TRUE';
      INPUT_LOAD='(-0.01,0.01)';
      OUTPUT_LOAD='(1.0,-1.0)';
      PINUSE='BI';
    'PCIEUP_7_RXN':
      PIN_NUMBER='(0,0,0,D55,0,0,0,0,0,0,0,0,0,0)';
      BIDIRECTIONAL='TRUE';
      INPUT_LOAD='(-0.01,0.01)';
      OUTPUT_LOAD='(1.0,-1.0)';
      PINUSE='BI';
    'PCIEUP_7_RXP':
      PIN_NUMBER='(0,0,0,B55,0,0,0,0,0,0,0,0,0,0)';
      BIDIRECTIONAL='TRUE';
      INPUT_LOAD='(-0.01,0.01)';
      OUTPUT_LOAD='(1.0,-1.0)';
      PINUSE='BI';
    'PCIEUP_7_TXN':
      PIN_NUMBER='(0,0,0,P59,0,0,0,0,0,0,0,0,0,0)';
      BIDIRECTIONAL='TRUE';
      INPUT_LOAD='(-0.01,0.01)';
      OUTPUT_LOAD='(1.0,-1.0)';
      PINUSE='BI';
    'PCIEUP_7_TXP':
      PIN_NUMBER='(0,0,0,R61,0,0,0,0,0,0,0,0,0,0)';
      BIDIRECTIONAL='TRUE';
      INPUT_LOAD='(-0.01,0.01)';
      OUTPUT_LOAD='(1.0,-1.0)';
      PINUSE='BI';
    'PCIEUP_8_RXN':
      PIN_NUMBER='(0,0,0,C57,0,0,0,0,0,0,0,0,0,0)';
      BIDIRECTIONAL='TRUE';
      INPUT_LOAD='(-0.01,0.01)';
      OUTPUT_LOAD='(1.0,-1.0)';
      PINUSE='BI';
    'PCIEUP_8_RXP':
      PIN_NUMBER='(0,0,0,A57,0,0,0,0,0,0,0,0,0,0)';
      BIDIRECTIONAL='TRUE';
      INPUT_LOAD='(-0.01,0.01)';
      OUTPUT_LOAD='(1.0,-1.0)';
      PINUSE='BI';
    'PCIEUP_8_TXN':
      PIN_NUMBER='(0,0,0,K65,0,0,0,0,0,0,0,0,0,0)';
      BIDIRECTIONAL='TRUE';
      INPUT_LOAD='(-0.01,0.01)';
      OUTPUT_LOAD='(1.0,-1.0)';
      PINUSE='BI';
    'PCIEUP_8_TXP':
      PIN_NUMBER='(0,0,0,M63,0,0,0,0,0,0,0,0,0,0)';
      BIDIRECTIONAL='TRUE';
      INPUT_LOAD='(-0.01,0.01)';
      OUTPUT_LOAD='(1.0,-1.0)';
      PINUSE='BI';
    'PCIEUP_9_RXN':
      PIN_NUMBER='(0,0,0,D58,0,0,0,0,0,0,0,0,0,0)';
      BIDIRECTIONAL='TRUE';
      INPUT_LOAD='(-0.01,0.01)';
      OUTPUT_LOAD='(1.0,-1.0)';
      PINUSE='BI';
    'PCIEUP_9_RXP':
      PIN_NUMBER='(0,0,0,B58,0,0,0,0,0,0,0,0,0,0)';
      BIDIRECTIONAL='TRUE';
      INPUT_LOAD='(-0.01,0.01)';
      OUTPUT_LOAD='(1.0,-1.0)';
      PINUSE='BI';
    'PCIEUP_9_TXN':
      PIN_NUMBER='(0,0,0,J66,0,0,0,0,0,0,0,0,0,0)';
      BIDIRECTIONAL='TRUE';
      INPUT_LOAD='(-0.01,0.01)';
      OUTPUT_LOAD='(1.0,-1.0)';
      PINUSE='BI';
    'PCIEUP_9_TXP':
      PIN_NUMBER='(0,0,0,M66,0,0,0,0,0,0,0,0,0,0)';
      BIDIRECTIONAL='TRUE';
      INPUT_LOAD='(-0.01,0.01)';
      OUTPUT_LOAD='(1.0,-1.0)';
      PINUSE='BI';
    'PCIEUP_RCOMPN':
      PIN_NUMBER='(0,0,AF58,0,0,0,0,0,0,0,0,0,0,0)';
      BIDIRECTIONAL='TRUE';
      INPUT_LOAD='(-0.01,0.01)';
      OUTPUT_LOAD='(1.0,-1.0)';
      PINUSE='BI';
    'PCIEUP_RCOMPP':
      PIN_NUMBER='(0,0,AH58,0,0,0,0,0,0,0,0,0,0,0)';
      BIDIRECTIONAL='TRUE';
      INPUT_LOAD='(-0.01,0.01)';
      OUTPUT_LOAD='(1.0,-1.0)';
      PINUSE='BI';
    'PCIE_RCOMPN':
      PIN_NUMBER='(0,0,BD58,0,0,0,0,0,0,0,0,0,0,0)';
      BIDIRECTIONAL='TRUE';
      INPUT_LOAD='(-0.01,0.01)';
      OUTPUT_LOAD='(1.0,-1.0)';
      PINUSE='BI';
    'PCIE_RCOMPP':
      PIN_NUMBER='(0,0,BB56,0,0,0,0,0,0,0,0,0,0,0)';
      BIDIRECTIONAL='TRUE';
      INPUT_LOAD='(-0.01,0.01)';
      OUTPUT_LOAD='(1.0,-1.0)';
      PINUSE='BI';
    'PECI':
      PIN_NUMBER='(0,0,0,0,U9,0,0,0,0,0,0,0,0,0)';
      BIDIRECTIONAL='TRUE';
      INPUT_LOAD='(-0.01,0.01)';
      OUTPUT_LOAD='(1.0,-1.0)';
      PINUSE='BI';
    'PLTRST_CPU_N':
      PIN_NUMBER='(0,0,0,0,U17,0,0,0,0,0,0,0,0,0)';
      BIDIRECTIONAL='TRUE';
      INPUT_LOAD='(-0.01,0.01)';
      OUTPUT_LOAD='(1.0,-1.0)';
      PINUSE='BI';
    'PM_SYNC':
      PIN_NUMBER='(0,0,0,0,U13,0,0,0,0,0,0,0,0,0)';
      BIDIRECTIONAL='TRUE';
      INPUT_LOAD='(-0.01,0.01)';
      OUTPUT_LOAD='(1.0,-1.0)';
      PINUSE='BI';
    'PM_SYNC2':
      PIN_NUMBER='(0,0,0,0,V7,0,0,0,0,0,0,0,0,0)';
      BIDIRECTIONAL='TRUE';
      INPUT_LOAD='(-0.01,0.01)';
      OUTPUT_LOAD='(1.0,-1.0)';
      PINUSE='BI';
    'PRDY_N':
      PIN_NUMBER='(0,0,0,0,AD54,0,0,0,0,0,0,0,0,0)';
      BIDIRECTIONAL='TRUE';
      INPUT_LOAD='(-0.01,0.01)';
      OUTPUT_LOAD='(1.0,-1.0)';
      PINUSE='BI';
    'PREQ_N':
      PIN_NUMBER='(0,0,0,0,U54,0,0,0,0,0,0,0,0,0)';
      BIDIRECTIONAL='TRUE';
      INPUT_LOAD='(-0.01,0.01)';
      OUTPUT_LOAD='(1.0,-1.0)';
      PINUSE='BI';
    'PROC_PWRGD':
      PIN_NUMBER='(0,0,0,0,R9,0,0,0,0,0,0,0,0,0)';
      BIDIRECTIONAL='TRUE';
      INPUT_LOAD='(-0.01,0.01)';
      OUTPUT_LOAD='(1.0,-1.0)';
      PINUSE='BI';
    'RSMRST_N':
      PIN_NUMBER='(0,0,0,0,P15,0,0,0,0,0,0,0,0,0)';
      BIDIRECTIONAL='TRUE';
      INPUT_LOAD='(-0.01,0.01)';
      OUTPUT_LOAD='(1.0,-1.0)';
      PINUSE='BI';
    'RSVD'<68>:
      PIN_NUMBER='(0,0,0,0,0,0,0,V22,0,0,0,0,0,0)';
      BIDIRECTIONAL='TRUE';
      INPUT_LOAD='(-0.01,0.01)';
      OUTPUT_LOAD='(1.0,-1.0)';
      PINUSE='BI';
    'RSVD'<67>:
      PIN_NUMBER='(0,0,0,0,0,0,0,R20,0,0,0,0,0,0)';
      BIDIRECTIONAL='TRUE';
      INPUT_LOAD='(-0.01,0.01)';
      OUTPUT_LOAD='(1.0,-1.0)';
      PINUSE='BI';
    'RSVD'<66>:
      PIN_NUMBER='(0,0,0,0,0,0,0,U20,0,0,0,0,0,0)';
      BIDIRECTIONAL='TRUE';
      INPUT_LOAD='(-0.01,0.01)';
      OUTPUT_LOAD='(1.0,-1.0)';
      PINUSE='BI';
    'RSVD'<65>:
      PIN_NUMBER='(A26,0,0,0,0,0,0,0,0,0,0,0,0,0)';
      PINUSE='UNSPEC';
      NO_LOAD_CHECK='Both';
      NO_IO_CHECK='Both';
      NO_ASSERT_CHECK='TRUE';
      NO_DIR_CHECK='TRUE';
      ALLOW_CONNECT='TRUE';
    'RSVD'<64>:
      PIN_NUMBER='(C26,0,0,0,0,0,0,0,0,0,0,0,0,0)';
      PINUSE='UNSPEC';
      NO_LOAD_CHECK='Both';
      NO_IO_CHECK='Both';
      NO_ASSERT_CHECK='TRUE';
      NO_DIR_CHECK='TRUE';
      ALLOW_CONNECT='TRUE';
    'RSVD'<59>:
      PIN_NUMBER='(0,0,0,0,0,0,0,0,AT27,0,0,0,0,0)';
      PINUSE='UNSPEC';
      NO_LOAD_CHECK='Both';
      NO_IO_CHECK='Both';
      NO_ASSERT_CHECK='TRUE';
      NO_DIR_CHECK='TRUE';
      ALLOW_CONNECT='TRUE';
    'RSVD'<58>:
      PIN_NUMBER='(0,0,0,0,0,0,0,0,AP27,0,0,0,0,0)';
      PINUSE='UNSPEC';
      NO_LOAD_CHECK='Both';
      NO_IO_CHECK='Both';
      NO_ASSERT_CHECK='TRUE';
      NO_DIR_CHECK='TRUE';
      ALLOW_CONNECT='TRUE';
    'RSVD'<55>:
      PIN_NUMBER='(0,BN68,0,0,0,0,0,0,0,0,0,0,0,0)';
      PINUSE='UNSPEC';
      NO_LOAD_CHECK='Both';
      NO_IO_CHECK='Both';
      NO_ASSERT_CHECK='TRUE';
      NO_DIR_CHECK='TRUE';
      ALLOW_CONNECT='TRUE';
    'RSVD'<54>:
      PIN_NUMBER='(0,0,0,0,R24,0,0,0,0,0,0,0,0,0)';
      PINUSE='UNSPEC';
      NO_LOAD_CHECK='Both';
      NO_IO_CHECK='Both';
      NO_ASSERT_CHECK='TRUE';
      NO_DIR_CHECK='TRUE';
      ALLOW_CONNECT='TRUE';
    'RSVD'<53>:
      PIN_NUMBER='(0,0,0,0,P26,0,0,0,0,0,0,0,0,0)';
      PINUSE='UNSPEC';
      NO_LOAD_CHECK='Both';
      NO_IO_CHECK='Both';
      NO_ASSERT_CHECK='TRUE';
      NO_DIR_CHECK='TRUE';
      ALLOW_CONNECT='TRUE';
    'RSVD'<52>:
      PIN_NUMBER='(0,0,AA71,0,0,0,0,0,0,0,0,0,0,0)';
      PINUSE='UNSPEC';
      NO_LOAD_CHECK='Both';
      NO_IO_CHECK='Both';
      NO_ASSERT_CHECK='TRUE';
      NO_DIR_CHECK='TRUE';
      ALLOW_CONNECT='TRUE';
    'RSVD'<51>:
      PIN_NUMBER='(0,0,AA69,0,0,0,0,0,0,0,0,0,0,0)';
      PINUSE='UNSPEC';
      NO_LOAD_CHECK='Both';
      NO_IO_CHECK='Both';
      NO_ASSERT_CHECK='TRUE';
      NO_DIR_CHECK='TRUE';
      ALLOW_CONNECT='TRUE';
    'RSVD'<50>:
      PIN_NUMBER='(0,0,H69,0,0,0,0,0,0,0,0,0,0,0)';
      PINUSE='UNSPEC';
      NO_LOAD_CHECK='Both';
      NO_IO_CHECK='Both';
      NO_ASSERT_CHECK='TRUE';
      NO_DIR_CHECK='TRUE';
      ALLOW_CONNECT='TRUE';
    'RSVD'<49>:
      PIN_NUMBER='(0,0,G67,0,0,0,0,0,0,0,0,0,0,0)';
      PINUSE='UNSPEC';
      NO_LOAD_CHECK='Both';
      NO_IO_CHECK='Both';
      NO_ASSERT_CHECK='TRUE';
      NO_DIR_CHECK='TRUE';
      ALLOW_CONNECT='TRUE';
    'RSVD'<48>:
      PIN_NUMBER='(0,0,AP71,0,0,0,0,0,0,0,0,0,0,0)';
      PINUSE='UNSPEC';
      NO_LOAD_CHECK='Both';
      NO_IO_CHECK='Both';
      NO_ASSERT_CHECK='TRUE';
      NO_DIR_CHECK='TRUE';
      ALLOW_CONNECT='TRUE';
    'RSVD'<47>:
      PIN_NUMBER='(0,0,AP69,0,0,0,0,0,0,0,0,0,0,0)';
      PINUSE='UNSPEC';
      NO_LOAD_CHECK='Both';
      NO_IO_CHECK='Both';
      NO_ASSERT_CHECK='TRUE';
      NO_DIR_CHECK='TRUE';
      ALLOW_CONNECT='TRUE';
    'RSVD'<46>:
      PIN_NUMBER='(0,0,0,0,0,0,0,BW3,0,0,0,0,0,0)';
      PINUSE='UNSPEC';
      NO_LOAD_CHECK='Both';
      NO_IO_CHECK='Both';
      NO_ASSERT_CHECK='TRUE';
      NO_DIR_CHECK='TRUE';
      ALLOW_CONNECT='TRUE';
    'RSVD'<45>:
      PIN_NUMBER='(0,0,0,0,P22,0,0,0,0,0,0,0,0,0)';
      PINUSE='UNSPEC';
      NO_LOAD_CHECK='Both';
      NO_IO_CHECK='Both';
      NO_ASSERT_CHECK='TRUE';
      NO_DIR_CHECK='TRUE';
      ALLOW_CONNECT='TRUE';
    'RSVD'<44>:
      PIN_NUMBER='(0,0,0,0,BN33,0,0,0,0,0,0,0,0,0)';
      PINUSE='UNSPEC';
      NO_LOAD_CHECK='Both';
      NO_IO_CHECK='Both';
      NO_ASSERT_CHECK='TRUE';
      NO_DIR_CHECK='TRUE';
      ALLOW_CONNECT='TRUE';
    'RSVD'<43>:
      PIN_NUMBER='(0,0,0,0,BL33,0,0,0,0,0,0,0,0,0)';
      PINUSE='UNSPEC';
      NO_LOAD_CHECK='Both';
      NO_IO_CHECK='Both';
      NO_ASSERT_CHECK='TRUE';
      NO_DIR_CHECK='TRUE';
      ALLOW_CONNECT='TRUE';
    'RSVD'<42>:
      PIN_NUMBER='(0,0,0,0,BG40,0,0,0,0,0,0,0,0,0)';
      PINUSE='UNSPEC';
      NO_LOAD_CHECK='Both';
      NO_IO_CHECK='Both';
      NO_ASSERT_CHECK='TRUE';
      NO_DIR_CHECK='TRUE';
      ALLOW_CONNECT='TRUE';
    'RSVD'<41>:
      PIN_NUMBER='(0,0,0,0,BJ40,0,0,0,0,0,0,0,0,0)';
      PINUSE='UNSPEC';
      NO_LOAD_CHECK='Both';
      NO_IO_CHECK='Both';
      NO_ASSERT_CHECK='TRUE';
      NO_DIR_CHECK='TRUE';
      ALLOW_CONNECT='TRUE';
    'RSVD'<40>:
      PIN_NUMBER='(0,0,0,0,BN26,0,0,0,0,0,0,0,0,0)';
      PINUSE='UNSPEC';
      NO_LOAD_CHECK='Both';
      NO_IO_CHECK='Both';
      NO_ASSERT_CHECK='TRUE';
      NO_DIR_CHECK='TRUE';
      ALLOW_CONNECT='TRUE';
    'RSVD'<39>:
      PIN_NUMBER='(0,0,0,0,BL26,0,0,0,0,0,0,0,0,0)';
      PINUSE='UNSPEC';
      NO_LOAD_CHECK='Both';
      NO_IO_CHECK='Both';
      NO_ASSERT_CHECK='TRUE';
      NO_DIR_CHECK='TRUE';
      ALLOW_CONNECT='TRUE';
    'RSVD'<38>:
      PIN_NUMBER='(0,0,0,0,BL29,0,0,0,0,0,0,0,0,0)';
      PINUSE='UNSPEC';
      NO_LOAD_CHECK='Both';
      NO_IO_CHECK='Both';
      NO_ASSERT_CHECK='TRUE';
      NO_DIR_CHECK='TRUE';
      ALLOW_CONNECT='TRUE';
    'RSVD'<37>:
      PIN_NUMBER='(0,0,0,0,BN29,0,0,0,0,0,0,0,0,0)';
      PINUSE='UNSPEC';
      NO_LOAD_CHECK='Both';
      NO_IO_CHECK='Both';
      NO_ASSERT_CHECK='TRUE';
      NO_DIR_CHECK='TRUE';
      ALLOW_CONNECT='TRUE';
    'RSVD'<36>:
      PIN_NUMBER='(0,0,0,0,AK54,0,0,0,0,0,0,0,0,0)';
      PINUSE='UNSPEC';
      NO_LOAD_CHECK='Both';
      NO_IO_CHECK='Both';
      NO_ASSERT_CHECK='TRUE';
      NO_DIR_CHECK='TRUE';
      ALLOW_CONNECT='TRUE';
    'RSVD'<35>:
      PIN_NUMBER='(0,0,0,0,W54,0,0,0,0,0,0,0,0,0)';
      PINUSE='UNSPEC';
      NO_LOAD_CHECK='Both';
      NO_IO_CHECK='Both';
      NO_ASSERT_CHECK='TRUE';
      NO_DIR_CHECK='TRUE';
      ALLOW_CONNECT='TRUE';
    'RSVD'<34>:
      PIN_NUMBER='(0,0,0,0,Y56,0,0,0,0,0,0,0,0,0)';
      PINUSE='UNSPEC';
      NO_LOAD_CHECK='Both';
      NO_IO_CHECK='Both';
      NO_ASSERT_CHECK='TRUE';
      NO_DIR_CHECK='TRUE';
      ALLOW_CONNECT='TRUE';
    'RSVD'<33>:
      PIN_NUMBER='(0,0,0,0,V56,0,0,0,0,0,0,0,0,0)';
      PINUSE='UNSPEC';
      NO_LOAD_CHECK='Both';
      NO_IO_CHECK='Both';
      NO_ASSERT_CHECK='TRUE';
      NO_DIR_CHECK='TRUE';
      ALLOW_CONNECT='TRUE';
    'RSVD'<32>:
      PIN_NUMBER='(0,0,0,0,AA54,0,0,0,0,0,0,0,0,0)';
      PINUSE='UNSPEC';
      NO_LOAD_CHECK='Both';
      NO_IO_CHECK='Both';
      NO_ASSERT_CHECK='TRUE';
      NO_DIR_CHECK='TRUE';
      ALLOW_CONNECT='TRUE';
    'RSVD'<31>:
      PIN_NUMBER='(0,0,0,0,0,0,0,0,P29,0,0,0,0,0)';
      PINUSE='UNSPEC';
      NO_LOAD_CHECK='Both';
      NO_IO_CHECK='Both';
      NO_ASSERT_CHECK='TRUE';
      NO_DIR_CHECK='TRUE';
      ALLOW_CONNECT='TRUE';
    'RSVD'<30>:
      PIN_NUMBER='(0,0,0,0,0,0,0,0,R31,0,0,0,0,0)';
      PINUSE='UNSPEC';
      NO_LOAD_CHECK='Both';
      NO_IO_CHECK='Both';
      NO_ASSERT_CHECK='TRUE';
      NO_DIR_CHECK='TRUE';
      ALLOW_CONNECT='TRUE';
    'RSVD'<29>:
      PIN_NUMBER='(0,0,0,0,0,0,0,0,P33,0,0,0,0,0)';
      PINUSE='UNSPEC';
      NO_LOAD_CHECK='Both';
      NO_IO_CHECK='Both';
      NO_ASSERT_CHECK='TRUE';
      NO_DIR_CHECK='TRUE';
      ALLOW_CONNECT='TRUE';
    'RSVD'<28>:
      PIN_NUMBER='(0,0,0,0,0,0,0,0,R35,0,0,0,0,0)';
      PINUSE='UNSPEC';
      NO_LOAD_CHECK='Both';
      NO_IO_CHECK='Both';
      NO_ASSERT_CHECK='TRUE';
      NO_DIR_CHECK='TRUE';
      ALLOW_CONNECT='TRUE';
    'RSVD'<27>:
      PIN_NUMBER='(0,0,0,0,0,0,0,BG26,0,0,0,0,0,0)';
      PINUSE='UNSPEC';
      NO_LOAD_CHECK='Both';
      NO_IO_CHECK='Both';
      NO_ASSERT_CHECK='TRUE';
      NO_DIR_CHECK='TRUE';
      ALLOW_CONNECT='TRUE';
    'RSVD'<26>:
      PIN_NUMBER='(0,0,0,0,0,0,0,BH24,0,0,0,0,0,0)';
      PINUSE='UNSPEC';
      NO_LOAD_CHECK='Both';
      NO_IO_CHECK='Both';
      NO_ASSERT_CHECK='TRUE';
      NO_DIR_CHECK='TRUE';
      ALLOW_CONNECT='TRUE';
    'RSVD'<25>:
      PIN_NUMBER='(0,0,0,0,0,0,0,P48,0,0,0,0,0,0)';
      PINUSE='UNSPEC';
      NO_LOAD_CHECK='Both';
      NO_IO_CHECK='Both';
      NO_ASSERT_CHECK='TRUE';
      NO_DIR_CHECK='TRUE';
      ALLOW_CONNECT='TRUE';
    'RSVD'<24>:
      PIN_NUMBER='(0,0,0,0,0,0,0,P44,0,0,0,0,0,0)';
      PINUSE='UNSPEC';
      NO_LOAD_CHECK='Both';
      NO_IO_CHECK='Both';
      NO_ASSERT_CHECK='TRUE';
      NO_DIR_CHECK='TRUE';
      ALLOW_CONNECT='TRUE';
    'RSVD'<23>:
      PIN_NUMBER='(0,0,0,0,0,0,0,P40,0,0,0,0,0,0)';
      PINUSE='UNSPEC';
      NO_LOAD_CHECK='Both';
      NO_IO_CHECK='Both';
      NO_ASSERT_CHECK='TRUE';
      NO_DIR_CHECK='TRUE';
      ALLOW_CONNECT='TRUE';
    'RSVD'<22>:
      PIN_NUMBER='(0,0,0,0,0,0,0,AT71,0,0,0,0,0,0)';
      PINUSE='UNSPEC';
      NO_LOAD_CHECK='Both';
      NO_IO_CHECK='Both';
      NO_ASSERT_CHECK='TRUE';
      NO_DIR_CHECK='TRUE';
      ALLOW_CONNECT='TRUE';
    'RSVD'<21>:
      PIN_NUMBER='(0,0,0,0,0,0,0,A11,0,0,0,0,0,0)';
      PINUSE='UNSPEC';
      NO_LOAD_CHECK='Both';
      NO_IO_CHECK='Both';
      NO_ASSERT_CHECK='TRUE';
      NO_DIR_CHECK='TRUE';
      ALLOW_CONNECT='TRUE';
    'RSVD'<20>:
      PIN_NUMBER='(0,0,0,0,0,0,0,D10,0,0,0,0,0,0)';
      PINUSE='UNSPEC';
      NO_LOAD_CHECK='Both';
      NO_IO_CHECK='Both';
      NO_ASSERT_CHECK='TRUE';
      NO_DIR_CHECK='TRUE';
      ALLOW_CONNECT='TRUE';
    'RSVD'<19>:
      PIN_NUMBER='(0,0,0,0,0,0,0,C9,0,0,0,0,0,0)';
      PINUSE='UNSPEC';
      NO_LOAD_CHECK='Both';
      NO_IO_CHECK='Both';
      NO_ASSERT_CHECK='TRUE';
      NO_DIR_CHECK='TRUE';
      ALLOW_CONNECT='TRUE';
    'RSVD'<18>:
      PIN_NUMBER='(0,0,0,0,0,0,0,C11,0,0,0,0,0,0)';
      PINUSE='UNSPEC';
      NO_LOAD_CHECK='Both';
      NO_IO_CHECK='Both';
      NO_ASSERT_CHECK='TRUE';
      NO_DIR_CHECK='TRUE';
      ALLOW_CONNECT='TRUE';
    'RSVD'<17>:
      PIN_NUMBER='(0,0,0,0,0,0,0,B10,0,0,0,0,0,0)';
      PINUSE='UNSPEC';
      NO_LOAD_CHECK='Both';
      NO_IO_CHECK='Both';
      NO_ASSERT_CHECK='TRUE';
      NO_DIR_CHECK='TRUE';
      ALLOW_CONNECT='TRUE';
    'RSVD'<16>:
      PIN_NUMBER='(0,0,0,0,0,0,0,C5,0,0,0,0,0,0)';
      PINUSE='UNSPEC';
      NO_LOAD_CHECK='Both';
      NO_IO_CHECK='Both';
      NO_ASSERT_CHECK='TRUE';
      NO_DIR_CHECK='TRUE';
      ALLOW_CONNECT='TRUE';
    'RSVD'<15>:
      PIN_NUMBER='(0,0,0,0,0,0,0,C6,0,0,0,0,0,0)';
      PINUSE='UNSPEC';
      NO_LOAD_CHECK='Both';
      NO_IO_CHECK='Both';
      NO_ASSERT_CHECK='TRUE';
      NO_DIR_CHECK='TRUE';
      ALLOW_CONNECT='TRUE';
    'RSVD'<14>:
      PIN_NUMBER='(0,0,0,0,0,0,0,E18,0,0,0,0,0,0)';
      PINUSE='UNSPEC';
      NO_LOAD_CHECK='Both';
      NO_IO_CHECK='Both';
      NO_ASSERT_CHECK='TRUE';
      NO_DIR_CHECK='TRUE';
      ALLOW_CONNECT='TRUE';
    'RSVD'<13>:
      PIN_NUMBER='(0,0,0,0,0,0,0,C67,0,0,0,0,0,0)';
      PINUSE='UNSPEC';
      NO_LOAD_CHECK='Both';
      NO_IO_CHECK='Both';
      NO_ASSERT_CHECK='TRUE';
      NO_DIR_CHECK='TRUE';
      ALLOW_CONNECT='TRUE';
    'RSVD'<12>:
      PIN_NUMBER='(0,0,0,0,0,0,0,C68,0,0,0,0,0,0)';
      PINUSE='UNSPEC';
      NO_LOAD_CHECK='Both';
      NO_IO_CHECK='Both';
      NO_ASSERT_CHECK='TRUE';
      NO_DIR_CHECK='TRUE';
      ALLOW_CONNECT='TRUE';
    'RSVD'<11>:
      PIN_NUMBER='(0,0,0,0,0,0,0,C18,0,0,0,0,0,0)';
      PINUSE='UNSPEC';
      NO_LOAD_CHECK='Both';
      NO_IO_CHECK='Both';
      NO_ASSERT_CHECK='TRUE';
      NO_DIR_CHECK='TRUE';
      ALLOW_CONNECT='TRUE';
    'RSVD'<10>:
      PIN_NUMBER='(0,0,0,0,0,0,0,D8,0,0,0,0,0,0)';
      PINUSE='UNSPEC';
      NO_LOAD_CHECK='Both';
      NO_IO_CHECK='Both';
      NO_ASSERT_CHECK='TRUE';
      NO_DIR_CHECK='TRUE';
      ALLOW_CONNECT='TRUE';
    'RSVD'<9>:
      PIN_NUMBER='(0,0,0,0,0,0,0,F66,0,0,0,0,0,0)';
      PINUSE='UNSPEC';
      NO_LOAD_CHECK='Both';
      NO_IO_CHECK='Both';
      NO_ASSERT_CHECK='TRUE';
      NO_DIR_CHECK='TRUE';
      ALLOW_CONNECT='TRUE';
    'RSVD'<8>:
      PIN_NUMBER='(0,0,0,0,0,0,0,F69,0,0,0,0,0,0)';
      PINUSE='UNSPEC';
      NO_LOAD_CHECK='Both';
      NO_IO_CHECK='Both';
      NO_ASSERT_CHECK='TRUE';
      NO_DIR_CHECK='TRUE';
      ALLOW_CONNECT='TRUE';
    'RSVD'<7>:
      PIN_NUMBER='(0,0,0,0,0,0,0,F8,0,0,0,0,0,0)';
      PINUSE='UNSPEC';
      NO_LOAD_CHECK='Both';
      NO_IO_CHECK='Both';
      NO_ASSERT_CHECK='TRUE';
      NO_DIR_CHECK='TRUE';
      ALLOW_CONNECT='TRUE';
    'RSVD'<6>:
      PIN_NUMBER='(0,0,0,0,0,0,0,AT69,0,0,0,0,0,0)';
      PINUSE='UNSPEC';
      NO_LOAD_CHECK='Both';
      NO_IO_CHECK='Both';
      NO_ASSERT_CHECK='TRUE';
      NO_DIR_CHECK='TRUE';
      ALLOW_CONNECT='TRUE';
    'RSVD'<5>:
      PIN_NUMBER='(0,0,0,0,0,0,0,AG15,0,0,0,0,0,0)';
      PINUSE='UNSPEC';
      NO_LOAD_CHECK='Both';
      NO_IO_CHECK='Both';
      NO_ASSERT_CHECK='TRUE';
      NO_DIR_CHECK='TRUE';
      ALLOW_CONNECT='TRUE';
    'RSVD'<4>:
      PIN_NUMBER='(0,0,0,0,0,0,0,P37,0,0,0,0,0,0)';
      PINUSE='UNSPEC';
      NO_LOAD_CHECK='Both';
      NO_IO_CHECK='Both';
      NO_ASSERT_CHECK='TRUE';
      NO_DIR_CHECK='TRUE';
      ALLOW_CONNECT='TRUE';
    'RSVD'<3>:
      PIN_NUMBER='(0,0,0,0,0,0,0,V11,0,0,0,0,0,0)';
      PINUSE='UNSPEC';
      NO_LOAD_CHECK='Both';
      NO_IO_CHECK='Both';
      NO_ASSERT_CHECK='TRUE';
      NO_DIR_CHECK='TRUE';
      ALLOW_CONNECT='TRUE';
    'RSVD'<2>:
      PIN_NUMBER='(0,0,0,0,0,0,0,AA58,0,0,0,0,0,0)';
      PINUSE='UNSPEC';
      NO_LOAD_CHECK='Both';
      NO_IO_CHECK='Both';
      NO_ASSERT_CHECK='TRUE';
      NO_DIR_CHECK='TRUE';
      ALLOW_CONNECT='TRUE';
    'RSVD'<1>:
      PIN_NUMBER='(0,0,0,0,0,0,0,AC56,0,0,0,0,0,0)';
      PINUSE='UNSPEC';
      NO_LOAD_CHECK='Both';
      NO_IO_CHECK='Both';
      NO_ASSERT_CHECK='TRUE';
      NO_DIR_CHECK='TRUE';
      ALLOW_CONNECT='TRUE';
    'RSVD'<0>:
      PIN_NUMBER='(0,0,0,0,0,0,0,AF61,0,0,0,0,0,0)';
      PINUSE='UNSPEC';
      NO_LOAD_CHECK='Both';
      NO_IO_CHECK='Both';
      NO_ASSERT_CHECK='TRUE';
      NO_DIR_CHECK='TRUE';
      ALLOW_CONNECT='TRUE';
    'RTCRST_N':
      PIN_NUMBER='(0,0,0,0,0,0,0,P11,0,0,0,0,0,0)';
      BIDIRECTIONAL='TRUE';
      INPUT_LOAD='(-0.01,0.01)';
      OUTPUT_LOAD='(1.0,-1.0)';
      PINUSE='BI';
    'RTCX1':
      PIN_NUMBER='(K17,0,0,0,0,0,0,0,0,0,0,0,0,0)';
      BIDIRECTIONAL='TRUE';
      INPUT_LOAD='(-0.01,0.01)';
      OUTPUT_LOAD='(1.0,-1.0)';
      PINUSE='BI';
    'RTCX2':
      PIN_NUMBER='(H17,0,0,0,0,0,0,0,0,0,0,0,0,0)';
      BIDIRECTIONAL='TRUE';
      INPUT_LOAD='(-0.01,0.01)';
      OUTPUT_LOAD='(1.0,-1.0)';
      PINUSE='BI';
    'SLP_GBE_N':
      PIN_NUMBER='(0,0,0,0,M15,0,0,0,0,0,0,0,0,0)';
      BIDIRECTIONAL='TRUE';
      INPUT_LOAD='(-0.01,0.01)';
      OUTPUT_LOAD='(1.0,-1.0)';
      PINUSE='BI';
    'SLP_SUS_N':
      PIN_NUMBER='(0,0,0,0,P7,0,0,0,0,0,0,0,0,0)';
      BIDIRECTIONAL='TRUE';
      INPUT_LOAD='(-0.01,0.01)';
      OUTPUT_LOAD='(1.0,-1.0)';
      PINUSE='BI';
    'SPI0_CLK':
      PIN_NUMBER='(0,0,0,0,0,0,0,K2,0,0,0,0,0,0)';
      BIDIRECTIONAL='TRUE';
      INPUT_LOAD='(-0.01,0.01)';
      OUTPUT_LOAD='(1.0,-1.0)';
      PINUSE='BI';
    'SPI0_FLASH_CS0_N':
      PIN_NUMBER='(0,0,0,0,0,0,0,J3,0,0,0,0,0,0)';
      BIDIRECTIONAL='TRUE';
      INPUT_LOAD='(-0.01,0.01)';
      OUTPUT_LOAD='(1.0,-1.0)';
      PINUSE='BI';
    'SPI0_FLASH_CS1_N':
      PIN_NUMBER='(0,0,0,0,0,0,0,G7,0,0,0,0,0,0)';
      BIDIRECTIONAL='TRUE';
      INPUT_LOAD='(-0.01,0.01)';
      OUTPUT_LOAD='(1.0,-1.0)';
      PINUSE='BI';
    'SPI0_IO2':
      PIN_NUMBER='(0,0,0,0,0,0,0,F5,0,0,0,0,0,0)';
      BIDIRECTIONAL='TRUE';
      INPUT_LOAD='(-0.01,0.01)';
      OUTPUT_LOAD='(1.0,-1.0)';
      PINUSE='BI';
    'SPI0_IO3':
      PIN_NUMBER='(0,0,0,0,0,0,0,L1,0,0,0,0,0,0)';
      BIDIRECTIONAL='TRUE';
      INPUT_LOAD='(-0.01,0.01)';
      OUTPUT_LOAD='(1.0,-1.0)';
      PINUSE='BI';
    'SPI0_MISO_IO1':
      PIN_NUMBER='(0,0,0,0,0,0,0,L3,0,0,0,0,0,0)';
      BIDIRECTIONAL='TRUE';
      INPUT_LOAD='(-0.01,0.01)';
      OUTPUT_LOAD='(1.0,-1.0)';
      PINUSE='BI';
    'SPI0_MOSI_IO0':
      PIN_NUMBER='(0,0,0,0,0,0,0,H4,0,0,0,0,0,0)';
      BIDIRECTIONAL='TRUE';
      INPUT_LOAD='(-0.01,0.01)';
      OUTPUT_LOAD='(1.0,-1.0)';
      PINUSE='BI';
    'SPI0_TPM_CS_N':
      PIN_NUMBER='(0,0,0,0,0,0,0,K4,0,0,0,0,0,0)';
      BIDIRECTIONAL='TRUE';
      INPUT_LOAD='(-0.01,0.01)';
      OUTPUT_LOAD='(1.0,-1.0)';
      PINUSE='BI';
    'SRTCRST_N':
      PIN_NUMBER='(0,0,0,0,0,0,0,G18,0,0,0,0,0,0)';
      BIDIRECTIONAL='TRUE';
      INPUT_LOAD='(-0.01,0.01)';
      OUTPUT_LOAD='(1.0,-1.0)';
      PINUSE='BI';
    'SYS_PWROK':
      PIN_NUMBER='(0,0,0,0,BY19,0,0,0,0,0,0,0,0,0)';
      BIDIRECTIONAL='TRUE';
      INPUT_LOAD='(-0.01,0.01)';
      OUTPUT_LOAD='(1.0,-1.0)';
      PINUSE='BI';
    'SYS_RESET_N':
      PIN_NUMBER='(0,0,0,0,BV19,0,0,0,0,0,0,0,0,0)';
      BIDIRECTIONAL='TRUE';
      INPUT_LOAD='(-0.01,0.01)';
      OUTPUT_LOAD='(1.0,-1.0)';
      PINUSE='BI';
    'THRMTRIP_N':
      PIN_NUMBER='(0,0,0,0,V15,0,0,0,0,0,0,0,0,0)';
      BIDIRECTIONAL='TRUE';
      INPUT_LOAD='(-0.01,0.01)';
      OUTPUT_LOAD='(1.0,-1.0)';
      PINUSE='BI';
    'TRIGGER_IN':
      PIN_NUMBER='(0,0,0,0,M7,0,0,0,0,0,0,0,0,0)';
      BIDIRECTIONAL='TRUE';
      INPUT_LOAD='(-0.01,0.01)';
      OUTPUT_LOAD='(1.0,-1.0)';
      PINUSE='BI';
    'TRIGGER_OUT':
      PIN_NUMBER='(0,0,0,0,R13,0,0,0,0,0,0,0,0,0)';
      BIDIRECTIONAL='TRUE';
      INPUT_LOAD='(-0.01,0.01)';
      OUTPUT_LOAD='(1.0,-1.0)';
      PINUSE='BI';
    'USB2N_1':
      PIN_NUMBER='(0,BY60,0,0,0,0,0,0,0,0,0,0,0,0)';
      BIDIRECTIONAL='TRUE';
      INPUT_LOAD='(-0.01,0.01)';
      OUTPUT_LOAD='(1.0,-1.0)';
      PINUSE='BI';
    'USB2N_10':
      PIN_NUMBER='(0,BW65,0,0,0,0,0,0,0,0,0,0,0,0)';
      BIDIRECTIONAL='TRUE';
      INPUT_LOAD='(-0.01,0.01)';
      OUTPUT_LOAD='(1.0,-1.0)';
      PINUSE='BI';
    'USB2N_11':
      PIN_NUMBER='(0,CA54,0,0,0,0,0,0,0,0,0,0,0,0)';
      BIDIRECTIONAL='TRUE';
      INPUT_LOAD='(-0.01,0.01)';
      OUTPUT_LOAD='(1.0,-1.0)';
      PINUSE='BI';
    'USB2N_12':
      PIN_NUMBER='(0,BW67,0,0,0,0,0,0,0,0,0,0,0,0)';
      BIDIRECTIONAL='TRUE';
      INPUT_LOAD='(-0.01,0.01)';
      OUTPUT_LOAD='(1.0,-1.0)';
      PINUSE='BI';
    'USB2N_13':
      PIN_NUMBER='(0,BY53,0,0,0,0,0,0,0,0,0,0,0,0)';
      BIDIRECTIONAL='TRUE';
      INPUT_LOAD='(-0.01,0.01)';
      OUTPUT_LOAD='(1.0,-1.0)';
      PINUSE='BI';
    'USB2N_14':
      PIN_NUMBER='(0,BW68,0,0,0,0,0,0,0,0,0,0,0,0)';
      BIDIRECTIONAL='TRUE';
      INPUT_LOAD='(-0.01,0.01)';
      OUTPUT_LOAD='(1.0,-1.0)';
      PINUSE='BI';
    'USB2N_2':
      PIN_NUMBER='(0,CA61,0,0,0,0,0,0,0,0,0,0,0,0)';
      BIDIRECTIONAL='TRUE';
      INPUT_LOAD='(-0.01,0.01)';
      OUTPUT_LOAD='(1.0,-1.0)';
      PINUSE='BI';
    'USB2N_3':
      PIN_NUMBER='(0,CA59,0,0,0,0,0,0,0,0,0,0,0,0)';
      BIDIRECTIONAL='TRUE';
      INPUT_LOAD='(-0.01,0.01)';
      OUTPUT_LOAD='(1.0,-1.0)';
      PINUSE='BI';
    'USB2N_4':
      PIN_NUMBER='(0,BY62,0,0,0,0,0,0,0,0,0,0,0,0)';
      BIDIRECTIONAL='TRUE';
      INPUT_LOAD='(-0.01,0.01)';
      OUTPUT_LOAD='(1.0,-1.0)';
      PINUSE='BI';
    'USB2N_5':
      PIN_NUMBER='(0,BY58,0,0,0,0,0,0,0,0,0,0,0,0)';
      BIDIRECTIONAL='TRUE';
      INPUT_LOAD='(-0.01,0.01)';
      OUTPUT_LOAD='(1.0,-1.0)';
      PINUSE='BI';
    'USB2N_6':
      PIN_NUMBER='(0,CA63,0,0,0,0,0,0,0,0,0,0,0,0)';
      BIDIRECTIONAL='TRUE';
      INPUT_LOAD='(-0.01,0.01)';
      OUTPUT_LOAD='(1.0,-1.0)';
      PINUSE='BI';
    'USB2N_7':
      PIN_NUMBER='(0,CA57,0,0,0,0,0,0,0,0,0,0,0,0)';
      BIDIRECTIONAL='TRUE';
      INPUT_LOAD='(-0.01,0.01)';
      OUTPUT_LOAD='(1.0,-1.0)';
      PINUSE='BI';
    'USB2N_8':
      PIN_NUMBER='(0,BY64,0,0,0,0,0,0,0,0,0,0,0,0)';
      BIDIRECTIONAL='TRUE';
      INPUT_LOAD='(-0.01,0.01)';
      OUTPUT_LOAD='(1.0,-1.0)';
      PINUSE='BI';
    'USB2N_9':
      PIN_NUMBER='(0,BY55,0,0,0,0,0,0,0,0,0,0,0,0)';
      BIDIRECTIONAL='TRUE';
      INPUT_LOAD='(-0.01,0.01)';
      OUTPUT_LOAD='(1.0,-1.0)';
      PINUSE='BI';
    'USB2P_1':
      PIN_NUMBER='(0,BV60,0,0,0,0,0,0,0,0,0,0,0,0)';
      BIDIRECTIONAL='TRUE';
      INPUT_LOAD='(-0.01,0.01)';
      OUTPUT_LOAD='(1.0,-1.0)';
      PINUSE='BI';
    'USB2P_10':
      PIN_NUMBER='(0,BU65,0,0,0,0,0,0,0,0,0,0,0,0)';
      BIDIRECTIONAL='TRUE';
      INPUT_LOAD='(-0.01,0.01)';
      OUTPUT_LOAD='(1.0,-1.0)';
      PINUSE='BI';
    'USB2P_11':
      PIN_NUMBER='(0,BW54,0,0,0,0,0,0,0,0,0,0,0,0)';
      BIDIRECTIONAL='TRUE';
      INPUT_LOAD='(-0.01,0.01)';
      OUTPUT_LOAD='(1.0,-1.0)';
      PINUSE='BI';
    'USB2P_12':
      PIN_NUMBER='(0,BV66,0,0,0,0,0,0,0,0,0,0,0,0)';
      BIDIRECTIONAL='TRUE';
      INPUT_LOAD='(-0.01,0.01)';
      OUTPUT_LOAD='(1.0,-1.0)';
      PINUSE='BI';
    'USB2P_13':
      PIN_NUMBER='(0,BV53,0,0,0,0,0,0,0,0,0,0,0,0)';
      BIDIRECTIONAL='TRUE';
      INPUT_LOAD='(-0.01,0.01)';
      OUTPUT_LOAD='(1.0,-1.0)';
      PINUSE='BI';
    'USB2P_14':
      PIN_NUMBER='(0,BU67,0,0,0,0,0,0,0,0,0,0,0,0)';
      BIDIRECTIONAL='TRUE';
      INPUT_LOAD='(-0.01,0.01)';
      OUTPUT_LOAD='(1.0,-1.0)';
      PINUSE='BI';
    'USB2P_2':
      PIN_NUMBER='(0,BW61,0,0,0,0,0,0,0,0,0,0,0,0)';
      BIDIRECTIONAL='TRUE';
      INPUT_LOAD='(-0.01,0.01)';
      OUTPUT_LOAD='(1.0,-1.0)';
      PINUSE='BI';
    'USB2P_3':
      PIN_NUMBER='(0,BW59,0,0,0,0,0,0,0,0,0,0,0,0)';
      BIDIRECTIONAL='TRUE';
      INPUT_LOAD='(-0.01,0.01)';
      OUTPUT_LOAD='(1.0,-1.0)';
      PINUSE='BI';
    'USB2P_4':
      PIN_NUMBER='(0,BV62,0,0,0,0,0,0,0,0,0,0,0,0)';
      BIDIRECTIONAL='TRUE';
      INPUT_LOAD='(-0.01,0.01)';
      OUTPUT_LOAD='(1.0,-1.0)';
      PINUSE='BI';
    'USB2P_5':
      PIN_NUMBER='(0,BV58,0,0,0,0,0,0,0,0,0,0,0,0)';
      BIDIRECTIONAL='TRUE';
      INPUT_LOAD='(-0.01,0.01)';
      OUTPUT_LOAD='(1.0,-1.0)';
      PINUSE='BI';
    'USB2P_6':
      PIN_NUMBER='(0,BW63,0,0,0,0,0,0,0,0,0,0,0,0)';
      BIDIRECTIONAL='TRUE';
      INPUT_LOAD='(-0.01,0.01)';
      OUTPUT_LOAD='(1.0,-1.0)';
      PINUSE='BI';
    'USB2P_7':
      PIN_NUMBER='(0,BW57,0,0,0,0,0,0,0,0,0,0,0,0)';
      BIDIRECTIONAL='TRUE';
      INPUT_LOAD='(-0.01,0.01)';
      OUTPUT_LOAD='(1.0,-1.0)';
      PINUSE='BI';
    'USB2P_8':
      PIN_NUMBER='(0,BV64,0,0,0,0,0,0,0,0,0,0,0,0)';
      BIDIRECTIONAL='TRUE';
      INPUT_LOAD='(-0.01,0.01)';
      OUTPUT_LOAD='(1.0,-1.0)';
      PINUSE='BI';
    'USB2P_9':
      PIN_NUMBER='(0,BV55,0,0,0,0,0,0,0,0,0,0,0,0)';
      BIDIRECTIONAL='TRUE';
      INPUT_LOAD='(-0.01,0.01)';
      OUTPUT_LOAD='(1.0,-1.0)';
      PINUSE='BI';
    'USB2_COMP':
      PIN_NUMBER='(0,BN70,0,0,0,0,0,0,0,0,0,0,0,0)';
      BIDIRECTIONAL='TRUE';
      INPUT_LOAD='(-0.01,0.01)';
      OUTPUT_LOAD='(1.0,-1.0)';
      PINUSE='BI';
    'USB2_VBUS':
      PIN_NUMBER='(0,BR67,0,0,0,0,0,0,0,0,0,0,0,0)';
      BIDIRECTIONAL='TRUE';
      INPUT_LOAD='(-0.01,0.01)';
      OUTPUT_LOAD='(1.0,-1.0)';
      PINUSE='BI';
    'USB3_10_PCIE3_GBE_RXN':
      PIN_NUMBER='(0,0,AV72,0,0,0,0,0,0,0,0,0,0,0)';
      BIDIRECTIONAL='TRUE';
      INPUT_LOAD='(-0.01,0.01)';
      OUTPUT_LOAD='(1.0,-1.0)';
      PINUSE='BI';
    'USB3_10_PCIE3_GBE_RXP':
      PIN_NUMBER='(0,0,AV70,0,0,0,0,0,0,0,0,0,0,0)';
      BIDIRECTIONAL='TRUE';
      INPUT_LOAD='(-0.01,0.01)';
      OUTPUT_LOAD='(1.0,-1.0)';
      PINUSE='BI';
    'USB3_10_PCIE3_GBE_TXN':
      PIN_NUMBER='(0,0,BH61,0,0,0,0,0,0,0,0,0,0,0)';
      BIDIRECTIONAL='TRUE';
      INPUT_LOAD='(-0.01,0.01)';
      OUTPUT_LOAD='(1.0,-1.0)';
      PINUSE='BI';
    'USB3_10_PCIE3_GBE_TXP':
      PIN_NUMBER='(0,0,BK61,0,0,0,0,0,0,0,0,0,0,0)';
      BIDIRECTIONAL='TRUE';
      INPUT_LOAD='(-0.01,0.01)';
      OUTPUT_LOAD='(1.0,-1.0)';
      PINUSE='BI';
    'USB3_1_RXN':
      PIN_NUMBER='(0,BK71,0,0,0,0,0,0,0,0,0,0,0,0)';
      BIDIRECTIONAL='TRUE';
      INPUT_LOAD='(-0.01,0.01)';
      OUTPUT_LOAD='(1.0,-1.0)';
      PINUSE='BI';
    'USB3_1_RXP':
      PIN_NUMBER='(0,BK69,0,0,0,0,0,0,0,0,0,0,0,0)';
      BIDIRECTIONAL='TRUE';
      INPUT_LOAD='(-0.01,0.01)';
      OUTPUT_LOAD='(1.0,-1.0)';
      PINUSE='BI';
    'USB3_1_TXN':
      PIN_NUMBER='(0,BL52,0,0,0,0,0,0,0,0,0,0,0,0)';
      BIDIRECTIONAL='TRUE';
      INPUT_LOAD='(-0.01,0.01)';
      OUTPUT_LOAD='(1.0,-1.0)';
      PINUSE='BI';
    'USB3_1_TXP':
      PIN_NUMBER='(0,BK54,0,0,0,0,0,0,0,0,0,0,0,0)';
      BIDIRECTIONAL='TRUE';
      INPUT_LOAD='(-0.01,0.01)';
      OUTPUT_LOAD='(1.0,-1.0)';
      PINUSE='BI';
    'USB3_2_RXN':
      PIN_NUMBER='(0,BJ72,0,0,0,0,0,0,0,0,0,0,0,0)';
      BIDIRECTIONAL='TRUE';
      INPUT_LOAD='(-0.01,0.01)';
      OUTPUT_LOAD='(1.0,-1.0)';
      PINUSE='BI';
    'USB3_2_RXP':
      PIN_NUMBER='(0,BJ70,0,0,0,0,0,0,0,0,0,0,0,0)';
      BIDIRECTIONAL='TRUE';
      INPUT_LOAD='(-0.01,0.01)';
      OUTPUT_LOAD='(1.0,-1.0)';
      PINUSE='BI';
    'USB3_2_TXN':
      PIN_NUMBER='(0,BL56,0,0,0,0,0,0,0,0,0,0,0,0)';
      BIDIRECTIONAL='TRUE';
      INPUT_LOAD='(-0.01,0.01)';
      OUTPUT_LOAD='(1.0,-1.0)';
      PINUSE='BI';
    'USB3_2_TXP':
      PIN_NUMBER='(0,BJ56,0,0,0,0,0,0,0,0,0,0,0,0)';
      BIDIRECTIONAL='TRUE';
      INPUT_LOAD='(-0.01,0.01)';
      OUTPUT_LOAD='(1.0,-1.0)';
      PINUSE='BI';
    'USB3_3_RXN':
      PIN_NUMBER='(0,BH71,0,0,0,0,0,0,0,0,0,0,0,0)';
      BIDIRECTIONAL='TRUE';
      INPUT_LOAD='(-0.01,0.01)';
      OUTPUT_LOAD='(1.0,-1.0)';
      PINUSE='BI';
    'USB3_3_RXP':
      PIN_NUMBER='(0,BH69,0,0,0,0,0,0,0,0,0,0,0,0)';
      BIDIRECTIONAL='TRUE';
      INPUT_LOAD='(-0.01,0.01)';
      OUTPUT_LOAD='(1.0,-1.0)';
      PINUSE='BI';
    'USB3_3_TXN':
      PIN_NUMBER='(0,BM54,0,0,0,0,0,0,0,0,0,0,0,0)';
      BIDIRECTIONAL='TRUE';
      INPUT_LOAD='(-0.01,0.01)';
      OUTPUT_LOAD='(1.0,-1.0)';
      PINUSE='BI';
    'USB3_3_TXP':
      PIN_NUMBER='(0,BN56,0,0,0,0,0,0,0,0,0,0,0,0)';
      BIDIRECTIONAL='TRUE';
      INPUT_LOAD='(-0.01,0.01)';
      OUTPUT_LOAD='(1.0,-1.0)';
      PINUSE='BI';
    'USB3_4_RXN':
      PIN_NUMBER='(0,BF72,0,0,0,0,0,0,0,0,0,0,0,0)';
      BIDIRECTIONAL='TRUE';
      INPUT_LOAD='(-0.01,0.01)';
      OUTPUT_LOAD='(1.0,-1.0)';
      PINUSE='BI';
    'USB3_4_RXP':
      PIN_NUMBER='(0,BF70,0,0,0,0,0,0,0,0,0,0,0,0)';
      BIDIRECTIONAL='TRUE';
      INPUT_LOAD='(-0.01,0.01)';
      OUTPUT_LOAD='(1.0,-1.0)';
      PINUSE='BI';
    'USB3_4_TXN':
      PIN_NUMBER='(0,BH58,0,0,0,0,0,0,0,0,0,0,0,0)';
      BIDIRECTIONAL='TRUE';
      INPUT_LOAD='(-0.01,0.01)';
      OUTPUT_LOAD='(1.0,-1.0)';
      PINUSE='BI';
    'USB3_4_TXP':
      PIN_NUMBER='(0,BG56,0,0,0,0,0,0,0,0,0,0,0,0)';
      BIDIRECTIONAL='TRUE';
      INPUT_LOAD='(-0.01,0.01)';
      OUTPUT_LOAD='(1.0,-1.0)';
      PINUSE='BI';
    'USB3_5_RXN':
      PIN_NUMBER='(0,BE71,0,0,0,0,0,0,0,0,0,0,0,0)';
      BIDIRECTIONAL='TRUE';
      INPUT_LOAD='(-0.01,0.01)';
      OUTPUT_LOAD='(1.0,-1.0)';
      PINUSE='BI';
    'USB3_5_RXP':
      PIN_NUMBER='(0,BE69,0,0,0,0,0,0,0,0,0,0,0,0)';
      BIDIRECTIONAL='TRUE';
      INPUT_LOAD='(-0.01,0.01)';
      OUTPUT_LOAD='(1.0,-1.0)';
      PINUSE='BI';
    'USB3_5_TXN':
      PIN_NUMBER='(0,BK58,0,0,0,0,0,0,0,0,0,0,0,0)';
      BIDIRECTIONAL='TRUE';
      INPUT_LOAD='(-0.01,0.01)';
      OUTPUT_LOAD='(1.0,-1.0)';
      PINUSE='BI';
    'USB3_5_TXP':
      PIN_NUMBER='(0,BJ59,0,0,0,0,0,0,0,0,0,0,0,0)';
      BIDIRECTIONAL='TRUE';
      INPUT_LOAD='(-0.01,0.01)';
      OUTPUT_LOAD='(1.0,-1.0)';
      PINUSE='BI';
    'USB3_6_RXN':
      PIN_NUMBER='(0,BD72,0,0,0,0,0,0,0,0,0,0,0,0)';
      BIDIRECTIONAL='TRUE';
      INPUT_LOAD='(-0.01,0.01)';
      OUTPUT_LOAD='(1.0,-1.0)';
      PINUSE='BI';
    'USB3_6_RXP':
      PIN_NUMBER='(0,BD70,0,0,0,0,0,0,0,0,0,0,0,0)';
      BIDIRECTIONAL='TRUE';
      INPUT_LOAD='(-0.01,0.01)';
      OUTPUT_LOAD='(1.0,-1.0)';
      PINUSE='BI';
    'USB3_6_TXN':
      PIN_NUMBER='(0,BL59,0,0,0,0,0,0,0,0,0,0,0,0)';
      BIDIRECTIONAL='TRUE';
      INPUT_LOAD='(-0.01,0.01)';
      OUTPUT_LOAD='(1.0,-1.0)';
      PINUSE='BI';
    'USB3_6_TXP':
      PIN_NUMBER='(0,BM61,0,0,0,0,0,0,0,0,0,0,0,0)';
      BIDIRECTIONAL='TRUE';
      INPUT_LOAD='(-0.01,0.01)';
      OUTPUT_LOAD='(1.0,-1.0)';
      PINUSE='BI';
    'USB3_7_PCIE0_RXN':
      PIN_NUMBER='(0,0,BA71,0,0,0,0,0,0,0,0,0,0,0)';
      BIDIRECTIONAL='TRUE';
      INPUT_LOAD='(-0.01,0.01)';
      OUTPUT_LOAD='(1.0,-1.0)';
      PINUSE='BI';
    'USB3_7_PCIE0_RXP':
      PIN_NUMBER='(0,0,BA69,0,0,0,0,0,0,0,0,0,0,0)';
      BIDIRECTIONAL='TRUE';
      INPUT_LOAD='(-0.01,0.01)';
      OUTPUT_LOAD='(1.0,-1.0)';
      PINUSE='BI';
    'USB3_7_PCIE0_TXN':
      PIN_NUMBER='(0,0,BR61,0,0,0,0,0,0,0,0,0,0,0)';
      BIDIRECTIONAL='TRUE';
      INPUT_LOAD='(-0.01,0.01)';
      OUTPUT_LOAD='(1.0,-1.0)';
      PINUSE='BI';
    'USB3_7_PCIE0_TXP':
      PIN_NUMBER='(0,0,BN63,0,0,0,0,0,0,0,0,0,0,0)';
      BIDIRECTIONAL='TRUE';
      INPUT_LOAD='(-0.01,0.01)';
      OUTPUT_LOAD='(1.0,-1.0)';
      PINUSE='BI';
    'USB3_8_PCIE1_RXN':
      PIN_NUMBER='(0,0,AY72,0,0,0,0,0,0,0,0,0,0,0)';
      BIDIRECTIONAL='TRUE';
      INPUT_LOAD='(-0.01,0.01)';
      OUTPUT_LOAD='(1.0,-1.0)';
      PINUSE='BI';
    'USB3_8_PCIE1_RXP':
      PIN_NUMBER='(0,0,AY70,0,0,0,0,0,0,0,0,0,0,0)';
      BIDIRECTIONAL='TRUE';
      INPUT_LOAD='(-0.01,0.01)';
      OUTPUT_LOAD='(1.0,-1.0)';
      PINUSE='BI';
    'USB3_8_PCIE1_TXN':
      PIN_NUMBER='(0,0,BM65,0,0,0,0,0,0,0,0,0,0,0)';
      BIDIRECTIONAL='TRUE';
      INPUT_LOAD='(-0.01,0.01)';
      OUTPUT_LOAD='(1.0,-1.0)';
      PINUSE='BI';
    'USB3_8_PCIE1_TXP':
      PIN_NUMBER='(0,0,BR65,0,0,0,0,0,0,0,0,0,0,0)';
      BIDIRECTIONAL='TRUE';
      INPUT_LOAD='(-0.01,0.01)';
      OUTPUT_LOAD='(1.0,-1.0)';
      PINUSE='BI';
    'USB3_9_PCIE2_RXN':
      PIN_NUMBER='(0,0,AW71,0,0,0,0,0,0,0,0,0,0,0)';
      BIDIRECTIONAL='TRUE';
      INPUT_LOAD='(-0.01,0.01)';
      OUTPUT_LOAD='(1.0,-1.0)';
      PINUSE='BI';
    'USB3_9_PCIE2_RXP':
      PIN_NUMBER='(0,0,AW69,0,0,0,0,0,0,0,0,0,0,0)';
      BIDIRECTIONAL='TRUE';
      INPUT_LOAD='(-0.01,0.01)';
      OUTPUT_LOAD='(1.0,-1.0)';
      PINUSE='BI';
    'USB3_9_PCIE2_TXN':
      PIN_NUMBER='(0,0,BK65,0,0,0,0,0,0,0,0,0,0,0)';
      BIDIRECTIONAL='TRUE';
      INPUT_LOAD='(-0.01,0.01)';
      OUTPUT_LOAD='(1.0,-1.0)';
      PINUSE='BI';
    'USB3_9_PCIE2_TXP':
      PIN_NUMBER='(0,0,BL66,0,0,0,0,0,0,0,0,0,0,0)';
      BIDIRECTIONAL='TRUE';
      INPUT_LOAD='(-0.01,0.01)';
      OUTPUT_LOAD='(1.0,-1.0)';
      PINUSE='BI';
    'VCCA_CLKFILT_1P05'<4>:
      PIN_NUMBER='(0,0,0,0,0,0,0,0,AE46,0,0,0,0,0)';
      PINUSE='POWER';
      NO_LOAD_CHECK='Both';
      NO_IO_CHECK='Both';
      NO_ASSERT_CHECK='TRUE';
      NO_DIR_CHECK='TRUE';
      ALLOW_CONNECT='TRUE';
    'VCCA_CLKFILT_1P05'<3>:
      PIN_NUMBER='(0,0,0,0,0,0,0,0,AJ48,0,0,0,0,0)';
      PINUSE='POWER';
      NO_LOAD_CHECK='Both';
      NO_IO_CHECK='Both';
      NO_ASSERT_CHECK='TRUE';
      NO_DIR_CHECK='TRUE';
      ALLOW_CONNECT='TRUE';
    'VCCA_CLKFILT_1P05'<2>:
      PIN_NUMBER='(0,0,0,0,0,0,0,0,AJ46,0,0,0,0,0)';
      PINUSE='POWER';
      NO_LOAD_CHECK='Both';
      NO_IO_CHECK='Both';
      NO_ASSERT_CHECK='TRUE';
      NO_DIR_CHECK='TRUE';
      ALLOW_CONNECT='TRUE';
    'VCCA_CLKFILT_1P05'<1>:
      PIN_NUMBER='(0,0,0,0,0,0,0,0,AG45,0,0,0,0,0)';
      PINUSE='POWER';
      NO_LOAD_CHECK='Both';
      NO_IO_CHECK='Both';
      NO_ASSERT_CHECK='TRUE';
      NO_DIR_CHECK='TRUE';
      ALLOW_CONNECT='TRUE';
    'VCCA_CLKFILT_1P05'<0>:
      PIN_NUMBER='(0,0,0,0,0,0,0,0,W50,0,0,0,0,0)';
      PINUSE='POWER';
      NO_LOAD_CHECK='Both';
      NO_IO_CHECK='Both';
      NO_ASSERT_CHECK='TRUE';
      NO_DIR_CHECK='TRUE';
      ALLOW_CONNECT='TRUE';
    'VCCA_CLKUNF_1P05'<1>:
      PIN_NUMBER='(0,0,0,0,0,0,0,0,U50,0,0,0,0,0)';
      PINUSE='POWER';
      NO_LOAD_CHECK='Both';
      NO_IO_CHECK='Both';
      NO_ASSERT_CHECK='TRUE';
      NO_DIR_CHECK='TRUE';
      ALLOW_CONNECT='TRUE';
    'VCCA_CLKUNF_1P05'<0>:
      PIN_NUMBER='(0,0,0,0,0,0,0,0,AH50,0,0,0,0,0)';
      PINUSE='POWER';
      NO_LOAD_CHECK='Both';
      NO_IO_CHECK='Both';
      NO_ASSERT_CHECK='TRUE';
      NO_DIR_CHECK='TRUE';
      ALLOW_CONNECT='TRUE';
    'VCCA_CLKXTAL_1P05':
      PIN_NUMBER='(0,0,0,0,0,0,0,0,AD50,0,0,0,0,0)';
      PINUSE='POWER';
      NO_LOAD_CHECK='Both';
      NO_IO_CHECK='Both';
      NO_ASSERT_CHECK='TRUE';
      NO_DIR_CHECK='TRUE';
      ALLOW_CONNECT='TRUE';
    'VCCA_PLL0_1P05':
      PIN_NUMBER='(0,0,0,0,0,0,0,0,AG48,0,0,0,0,0)';
      PINUSE='POWER';
      NO_LOAD_CHECK='Both';
      NO_IO_CHECK='Both';
      NO_ASSERT_CHECK='TRUE';
      NO_DIR_CHECK='TRUE';
      ALLOW_CONNECT='TRUE';
    'VCCA_PLL1_1P05':
      PIN_NUMBER='(0,0,0,0,0,0,0,0,AE45,0,0,0,0,0)';
      PINUSE='POWER';
      NO_LOAD_CHECK='Both';
      NO_IO_CHECK='Both';
      NO_ASSERT_CHECK='TRUE';
      NO_DIR_CHECK='TRUE';
      ALLOW_CONNECT='TRUE';
    'VCCMPHY_1P05'<13>:
      PIN_NUMBER='(0,0,0,0,0,0,0,0,0,AE27,0,0,0,0)';
      PINUSE='POWER';
      NO_LOAD_CHECK='Both';
      NO_IO_CHECK='Both';
      NO_ASSERT_CHECK='TRUE';
      NO_DIR_CHECK='TRUE';
      ALLOW_CONNECT='TRUE';
    'VCCMPHY_1P05'<12>:
      PIN_NUMBER='(0,0,0,0,0,0,0,0,AK43,0,0,0,0,0)';
      PINUSE='POWER';
      NO_LOAD_CHECK='Both';
      NO_IO_CHECK='Both';
      NO_ASSERT_CHECK='TRUE';
      NO_DIR_CHECK='TRUE';
      ALLOW_CONNECT='TRUE';
    'VCCMPHY_1P05'<11>:
      PIN_NUMBER='(0,0,0,0,0,0,0,0,AK45,0,0,0,0,0)';
      PINUSE='POWER';
      NO_LOAD_CHECK='Both';
      NO_IO_CHECK='Both';
      NO_ASSERT_CHECK='TRUE';
      NO_DIR_CHECK='TRUE';
      ALLOW_CONNECT='TRUE';
    'VCCMPHY_1P05'<10>:
      PIN_NUMBER='(0,0,0,0,0,0,0,0,AM43,0,0,0,0,0)';
      PINUSE='POWER';
      NO_LOAD_CHECK='Both';
      NO_IO_CHECK='Both';
      NO_ASSERT_CHECK='TRUE';
      NO_DIR_CHECK='TRUE';
      ALLOW_CONNECT='TRUE';
    'VCCMPHY_1P05'<9>:
      PIN_NUMBER='(0,0,0,0,0,0,0,0,AM45,0,0,0,0,0)';
      PINUSE='POWER';
      NO_LOAD_CHECK='Both';
      NO_IO_CHECK='Both';
      NO_ASSERT_CHECK='TRUE';
      NO_DIR_CHECK='TRUE';
      ALLOW_CONNECT='TRUE';
    'VCCMPHY_1P05'<8>:
      PIN_NUMBER='(0,0,0,0,0,0,0,0,AP43,0,0,0,0,0)';
      PINUSE='POWER';
      NO_LOAD_CHECK='Both';
      NO_IO_CHECK='Both';
      NO_ASSERT_CHECK='TRUE';
      NO_DIR_CHECK='TRUE';
      ALLOW_CONNECT='TRUE';
    'VCCMPHY_1P05'<7>:
      PIN_NUMBER='(0,0,0,0,0,0,0,0,AP45,0,0,0,0,0)';
      PINUSE='POWER';
      NO_LOAD_CHECK='Both';
      NO_IO_CHECK='Both';
      NO_ASSERT_CHECK='TRUE';
      NO_DIR_CHECK='TRUE';
      ALLOW_CONNECT='TRUE';
    'VCCMPHY_1P05'<6>:
      PIN_NUMBER='(0,0,0,0,0,0,0,0,AT43,0,0,0,0,0)';
      PINUSE='POWER';
      NO_LOAD_CHECK='Both';
      NO_IO_CHECK='Both';
      NO_ASSERT_CHECK='TRUE';
      NO_DIR_CHECK='TRUE';
      ALLOW_CONNECT='TRUE';
    'VCCMPHY_1P05'<5>:
      PIN_NUMBER='(0,0,0,0,0,0,0,0,AT45,0,0,0,0,0)';
      PINUSE='POWER';
      NO_LOAD_CHECK='Both';
      NO_IO_CHECK='Both';
      NO_ASSERT_CHECK='TRUE';
      NO_DIR_CHECK='TRUE';
      ALLOW_CONNECT='TRUE';
    'VCCMPHY_1P05'<4>:
      PIN_NUMBER='(0,0,0,0,0,0,0,0,AU43,0,0,0,0,0)';
      PINUSE='POWER';
      NO_LOAD_CHECK='Both';
      NO_IO_CHECK='Both';
      NO_ASSERT_CHECK='TRUE';
      NO_DIR_CHECK='TRUE';
      ALLOW_CONNECT='TRUE';
    'VCCMPHY_1P05'<3>:
      PIN_NUMBER='(0,0,0,0,0,0,0,0,AU45,0,0,0,0,0)';
      PINUSE='POWER';
      NO_LOAD_CHECK='Both';
      NO_IO_CHECK='Both';
      NO_ASSERT_CHECK='TRUE';
      NO_DIR_CHECK='TRUE';
      ALLOW_CONNECT='TRUE';
    'VCCMPHY_1P05'<2>:
      PIN_NUMBER='(0,0,0,0,0,0,0,0,AJ43,0,0,0,0,0)';
      PINUSE='POWER';
      NO_LOAD_CHECK='Both';
      NO_IO_CHECK='Both';
      NO_ASSERT_CHECK='TRUE';
      NO_DIR_CHECK='TRUE';
      ALLOW_CONNECT='TRUE';
    'VCCMPHY_1P05'<1>:
      PIN_NUMBER='(0,0,0,0,0,0,0,0,AW43,0,0,0,0,0)';
      PINUSE='POWER';
      NO_LOAD_CHECK='Both';
      NO_IO_CHECK='Both';
      NO_ASSERT_CHECK='TRUE';
      NO_DIR_CHECK='TRUE';
      ALLOW_CONNECT='TRUE';
    'VCCMPHY_1P05'<0>:
      PIN_NUMBER='(0,0,0,0,0,0,0,0,AW45,0,0,0,0,0)';
      PINUSE='POWER';
      NO_LOAD_CHECK='Both';
      NO_IO_CHECK='Both';
      NO_ASSERT_CHECK='TRUE';
      NO_DIR_CHECK='TRUE';
      ALLOW_CONNECT='TRUE';
    'VCCP10GBEPLL_1P05'<3>:
      PIN_NUMBER='(0,0,0,0,0,0,0,0,BA39,0,0,0,0,0)';
      PINUSE='POWER';
      NO_LOAD_CHECK='Both';
      NO_IO_CHECK='Both';
      NO_ASSERT_CHECK='TRUE';
      NO_DIR_CHECK='TRUE';
      ALLOW_CONNECT='TRUE';
    'VCCP10GBEPLL_1P05'<2>:
      PIN_NUMBER='(0,0,0,0,0,0,0,0,BA41,0,0,0,0,0)';
      PINUSE='POWER';
      NO_LOAD_CHECK='Both';
      NO_IO_CHECK='Both';
      NO_ASSERT_CHECK='TRUE';
      NO_DIR_CHECK='TRUE';
      ALLOW_CONNECT='TRUE';
    'VCCP10GBEPLL_1P05'<1>:
      PIN_NUMBER='(0,0,0,0,0,0,0,0,BB40,0,0,0,0,0)';
      PINUSE='POWER';
      NO_LOAD_CHECK='Both';
      NO_IO_CHECK='Both';
      NO_ASSERT_CHECK='TRUE';
      NO_DIR_CHECK='TRUE';
      ALLOW_CONNECT='TRUE';
    'VCCP10GBEPLL_1P05'<0>:
      PIN_NUMBER='(0,0,0,0,0,0,0,0,BD38,0,0,0,0,0)';
      PINUSE='POWER';
      NO_LOAD_CHECK='Both';
      NO_IO_CHECK='Both';
      NO_ASSERT_CHECK='TRUE';
      NO_DIR_CHECK='TRUE';
      ALLOW_CONNECT='TRUE';
    'VCCP10GBE_HV_1P8'<1>:
      PIN_NUMBER='(0,0,0,0,0,0,0,0,BA27,0,0,0,0,0)';
      PINUSE='POWER';
      NO_LOAD_CHECK='Both';
      NO_IO_CHECK='Both';
      NO_ASSERT_CHECK='TRUE';
      NO_DIR_CHECK='TRUE';
      ALLOW_CONNECT='TRUE';
    'VCCP10GBE_HV_1P8'<0>:
      PIN_NUMBER='(0,0,0,0,0,0,0,0,BA29,0,0,0,0,0)';
      PINUSE='POWER';
      NO_LOAD_CHECK='Both';
      NO_IO_CHECK='Both';
      NO_ASSERT_CHECK='TRUE';
      NO_DIR_CHECK='TRUE';
      ALLOW_CONNECT='TRUE';
    'VCCP10GBE_LV_1P05'<6>:
      PIN_NUMBER='(0,0,0,0,0,0,0,0,BA30,0,0,0,0,0)';
      PINUSE='POWER';
      NO_LOAD_CHECK='Both';
      NO_IO_CHECK='Both';
      NO_ASSERT_CHECK='TRUE';
      NO_DIR_CHECK='TRUE';
      ALLOW_CONNECT='TRUE';
    'VCCP10GBE_LV_1P05'<5>:
      PIN_NUMBER='(0,0,0,0,0,0,0,0,BA32,0,0,0,0,0)';
      PINUSE='POWER';
      NO_LOAD_CHECK='Both';
      NO_IO_CHECK='Both';
      NO_ASSERT_CHECK='TRUE';
      NO_DIR_CHECK='TRUE';
      ALLOW_CONNECT='TRUE';
    'VCCP10GBE_LV_1P05'<4>:
      PIN_NUMBER='(0,0,0,0,0,0,0,0,BA34,0,0,0,0,0)';
      PINUSE='POWER';
      NO_LOAD_CHECK='Both';
      NO_IO_CHECK='Both';
      NO_ASSERT_CHECK='TRUE';
      NO_DIR_CHECK='TRUE';
      ALLOW_CONNECT='TRUE';
    'VCCP10GBE_LV_1P05'<3>:
      PIN_NUMBER='(0,0,0,0,0,0,0,0,BA36,0,0,0,0,0)';
      PINUSE='POWER';
      NO_LOAD_CHECK='Both';
      NO_IO_CHECK='Both';
      NO_ASSERT_CHECK='TRUE';
      NO_DIR_CHECK='TRUE';
      ALLOW_CONNECT='TRUE';
    'VCCP10GBE_LV_1P05'<2>:
      PIN_NUMBER='(0,0,0,0,0,0,0,0,BA37,0,0,0,0,0)';
      PINUSE='POWER';
      NO_LOAD_CHECK='Both';
      NO_IO_CHECK='Both';
      NO_ASSERT_CHECK='TRUE';
      NO_DIR_CHECK='TRUE';
      ALLOW_CONNECT='TRUE';
    'VCCP10GBE_LV_1P05'<1>:
      PIN_NUMBER='(0,0,0,0,0,0,0,0,BB33,0,0,0,0,0)';
      PINUSE='POWER';
      NO_LOAD_CHECK='Both';
      NO_IO_CHECK='Both';
      NO_ASSERT_CHECK='TRUE';
      NO_DIR_CHECK='TRUE';
      ALLOW_CONNECT='TRUE';
    'VCCP10GBE_LV_1P05'<0>:
      PIN_NUMBER='(0,0,0,0,0,0,0,0,BB37,0,0,0,0,0)';
      PINUSE='POWER';
      NO_LOAD_CHECK='Both';
      NO_IO_CHECK='Both';
      NO_ASSERT_CHECK='TRUE';
      NO_DIR_CHECK='TRUE';
      ALLOW_CONNECT='TRUE';
    'VCCPDSW_3P3':
      PIN_NUMBER='(0,0,0,0,0,0,0,0,AH24,0,0,0,0,0)';
      PINUSE='POWER';
      NO_LOAD_CHECK='Both';
      NO_IO_CHECK='Both';
      NO_ASSERT_CHECK='TRUE';
      NO_DIR_CHECK='TRUE';
      ALLOW_CONNECT='TRUE';
    'VCCPGPPA':
      PIN_NUMBER='(0,0,0,0,0,0,0,0,AW24,0,0,0,0,0)';
      PINUSE='POWER';
      NO_LOAD_CHECK='Both';
      NO_IO_CHECK='Both';
      NO_ASSERT_CHECK='TRUE';
      NO_DIR_CHECK='TRUE';
      ALLOW_CONNECT='TRUE';
    'VCCPGPPB':
      PIN_NUMBER='(0,0,0,0,0,0,0,0,BE26,0,0,0,0,0)';
      PINUSE='POWER';
      NO_LOAD_CHECK='Both';
      NO_IO_CHECK='Both';
      NO_ASSERT_CHECK='TRUE';
      NO_DIR_CHECK='TRUE';
      ALLOW_CONNECT='TRUE';
    'VCCPGPPC':
      PIN_NUMBER='(0,0,0,0,0,0,0,0,BE40,0,0,0,0,0)';
      PINUSE='POWER';
      NO_LOAD_CHECK='Both';
      NO_IO_CHECK='Both';
      NO_ASSERT_CHECK='TRUE';
      NO_DIR_CHECK='TRUE';
      ALLOW_CONNECT='TRUE';
    'VCCPGPPD':
      PIN_NUMBER='(0,0,0,0,0,0,0,0,BA43,0,0,0,0,0)';
      PINUSE='POWER';
      NO_LOAD_CHECK='Both';
      NO_IO_CHECK='Both';
      NO_ASSERT_CHECK='TRUE';
      NO_DIR_CHECK='TRUE';
      ALLOW_CONNECT='TRUE';
    'VCCPGPPE':
      PIN_NUMBER='(0,0,0,0,0,0,0,0,BE44,0,0,0,0,0)';
      PINUSE='POWER';
      NO_LOAD_CHECK='Both';
      NO_IO_CHECK='Both';
      NO_ASSERT_CHECK='TRUE';
      NO_DIR_CHECK='TRUE';
      ALLOW_CONNECT='TRUE';
    'VCCPGPPF':
      PIN_NUMBER='(0,0,0,0,0,0,0,0,AU27,0,0,0,0,0)';
      PINUSE='POWER';
      NO_LOAD_CHECK='Both';
      NO_IO_CHECK='Both';
      NO_ASSERT_CHECK='TRUE';
      NO_DIR_CHECK='TRUE';
      ALLOW_CONNECT='TRUE';
    'VCCPGPPG':
      PIN_NUMBER='(0,0,0,0,0,0,0,0,BA26,0,0,0,0,0)';
      PINUSE='POWER';
      NO_LOAD_CHECK='Both';
      NO_IO_CHECK='Both';
      NO_ASSERT_CHECK='TRUE';
      NO_DIR_CHECK='TRUE';
      ALLOW_CONNECT='TRUE';
    'VCCPGPPH':
      PIN_NUMBER='(0,0,0,0,0,0,0,0,BA24,0,0,0,0,0)';
      PINUSE='POWER';
      NO_LOAD_CHECK='Both';
      NO_IO_CHECK='Both';
      NO_ASSERT_CHECK='TRUE';
      NO_DIR_CHECK='TRUE';
      ALLOW_CONNECT='TRUE';
    'VCCPGPPJ':
      PIN_NUMBER='(0,0,0,0,0,0,0,0,BB26,0,0,0,0,0)';
      PINUSE='POWER';
      NO_LOAD_CHECK='Both';
      NO_IO_CHECK='Both';
      NO_ASSERT_CHECK='TRUE';
      NO_DIR_CHECK='TRUE';
      ALLOW_CONNECT='TRUE';
    'VCCPGPPK':
      PIN_NUMBER='(0,0,0,0,0,0,0,0,AU24,0,0,0,0,0)';
      PINUSE='POWER';
      NO_LOAD_CHECK='Both';
      NO_IO_CHECK='Both';
      NO_ASSERT_CHECK='TRUE';
      NO_DIR_CHECK='TRUE';
      ALLOW_CONNECT='TRUE';
    'VCCPGPP_1P8'<6>:
      PIN_NUMBER='(0,0,0,0,0,0,0,0,AK24,0,0,0,0,0)';
      PINUSE='POWER';
      NO_LOAD_CHECK='Both';
      NO_IO_CHECK='Both';
      NO_ASSERT_CHECK='TRUE';
      NO_DIR_CHECK='TRUE';
      ALLOW_CONNECT='TRUE';
    'VCCPGPP_1P8'<5>:
      PIN_NUMBER='(0,0,0,0,0,0,0,0,AW27,0,0,0,0,0)';
      PINUSE='POWER';
      NO_LOAD_CHECK='Both';
      NO_IO_CHECK='Both';
      NO_ASSERT_CHECK='TRUE';
      NO_DIR_CHECK='TRUE';
      ALLOW_CONNECT='TRUE';
    'VCCPGPP_1P8'<4>:
      PIN_NUMBER='(0,0,0,0,0,0,0,0,AP29,0,0,0,0,0)';
      PINUSE='POWER';
      NO_LOAD_CHECK='Both';
      NO_IO_CHECK='Both';
      NO_ASSERT_CHECK='TRUE';
      NO_DIR_CHECK='TRUE';
      ALLOW_CONNECT='TRUE';
    'VCCPGPP_1P8'<3>:
      PIN_NUMBER='(0,0,0,0,0,0,0,0,AM29,0,0,0,0,0)';
      PINUSE='POWER';
      NO_LOAD_CHECK='Both';
      NO_IO_CHECK='Both';
      NO_ASSERT_CHECK='TRUE';
      NO_DIR_CHECK='TRUE';
      ALLOW_CONNECT='TRUE';
    'VCCPGPP_1P8'<2>:
      PIN_NUMBER='(0,0,0,0,0,0,0,0,AT29,0,0,0,0,0)';
      PINUSE='POWER';
      NO_LOAD_CHECK='Both';
      NO_IO_CHECK='Both';
      NO_ASSERT_CHECK='TRUE';
      NO_DIR_CHECK='TRUE';
      ALLOW_CONNECT='TRUE';
    'VCCPGPP_1P8'<1>:
      PIN_NUMBER='(0,0,0,0,0,0,0,0,AW29,0,0,0,0,0)';
      PINUSE='POWER';
      NO_LOAD_CHECK='Both';
      NO_IO_CHECK='Both';
      NO_ASSERT_CHECK='TRUE';
      NO_DIR_CHECK='TRUE';
      ALLOW_CONNECT='TRUE';
    'VCCPGPP_1P8'<0>:
      PIN_NUMBER='(0,0,0,0,0,0,0,0,AU29,0,0,0,0,0)';
      PINUSE='POWER';
      NO_LOAD_CHECK='Both';
      NO_IO_CHECK='Both';
      NO_ASSERT_CHECK='TRUE';
      NO_DIR_CHECK='TRUE';
      ALLOW_CONNECT='TRUE';
    'VCCPHDA_1P8':
      PIN_NUMBER='(0,0,0,0,0,0,0,0,AG27,0,0,0,0,0)';
      PINUSE='POWER';
      NO_LOAD_CHECK='Both';
      NO_IO_CHECK='Both';
      NO_ASSERT_CHECK='TRUE';
      NO_DIR_CHECK='TRUE';
      ALLOW_CONNECT='TRUE';
    'VCCPRIM_1P05'<19>:
      PIN_NUMBER='(0,0,0,0,0,0,0,0,Y26,0,0,0,0,0)';
      PINUSE='POWER';
      NO_LOAD_CHECK='Both';
      NO_IO_CHECK='Both';
      NO_ASSERT_CHECK='TRUE';
      NO_DIR_CHECK='TRUE';
      ALLOW_CONNECT='TRUE';
    'VCCPRIM_1P05'<18>:
      PIN_NUMBER='(0,0,0,0,0,0,0,0,AA24,0,0,0,0,0)';
      PINUSE='POWER';
      NO_LOAD_CHECK='Both';
      NO_IO_CHECK='Both';
      NO_ASSERT_CHECK='TRUE';
      NO_DIR_CHECK='TRUE';
      ALLOW_CONNECT='TRUE';
    'VCCPRIM_1P05'<17>:
      PIN_NUMBER='(0,0,0,0,0,0,0,0,AK27,0,0,0,0,0)';
      PINUSE='UNSPEC';
      NO_LOAD_CHECK='Both';
      NO_IO_CHECK='Both';
      NO_ASSERT_CHECK='TRUE';
      NO_DIR_CHECK='TRUE';
      ALLOW_CONNECT='TRUE';
    'VCCPRIM_1P05'<16>:
      PIN_NUMBER='(0,0,0,0,0,0,0,0,R42,0,0,0,0,0)';
      PINUSE='POWER';
      NO_LOAD_CHECK='Both';
      NO_IO_CHECK='Both';
      NO_ASSERT_CHECK='TRUE';
      NO_DIR_CHECK='TRUE';
      ALLOW_CONNECT='TRUE';
    'VCCPRIM_1P05'<15>:
      PIN_NUMBER='(0,0,0,0,0,0,0,0,R46,0,0,0,0,0)';
      PINUSE='POWER';
      NO_LOAD_CHECK='Both';
      NO_IO_CHECK='Both';
      NO_ASSERT_CHECK='TRUE';
      NO_DIR_CHECK='TRUE';
      ALLOW_CONNECT='TRUE';
    'VCCPRIM_1P05'<14>:
      PIN_NUMBER='(0,0,0,0,0,0,0,0,T44,0,0,0,0,0)';
      PINUSE='POWER';
      NO_LOAD_CHECK='Both';
      NO_IO_CHECK='Both';
      NO_ASSERT_CHECK='TRUE';
      NO_DIR_CHECK='TRUE';
      ALLOW_CONNECT='TRUE';
    'VCCPRIM_1P05'<13>:
      PIN_NUMBER='(0,0,0,0,0,0,0,0,U46,0,0,0,0,0)';
      PINUSE='POWER';
      NO_LOAD_CHECK='Both';
      NO_IO_CHECK='Both';
      NO_ASSERT_CHECK='TRUE';
      NO_DIR_CHECK='TRUE';
      ALLOW_CONNECT='TRUE';
    'VCCPRIM_1P05'<12>:
      PIN_NUMBER='(0,0,0,0,0,0,0,0,V44,0,0,0,0,0)';
      PINUSE='POWER';
      NO_LOAD_CHECK='Both';
      NO_IO_CHECK='Both';
      NO_ASSERT_CHECK='TRUE';
      NO_DIR_CHECK='TRUE';
      ALLOW_CONNECT='TRUE';
    'VCCPRIM_1P05'<11>:
      PIN_NUMBER='(0,0,0,0,0,0,0,0,Y45,0,0,0,0,0)';
      PINUSE='POWER';
      NO_LOAD_CHECK='Both';
      NO_IO_CHECK='Both';
      NO_ASSERT_CHECK='TRUE';
      NO_DIR_CHECK='TRUE';
      ALLOW_CONNECT='TRUE';
    'VCCPRIM_1P05'<10>:
      PIN_NUMBER='(0,0,0,0,0,0,0,0,Y46,0,0,0,0,0)';
      PINUSE='POWER';
      NO_LOAD_CHECK='Both';
      NO_IO_CHECK='Both';
      NO_ASSERT_CHECK='TRUE';
      NO_DIR_CHECK='TRUE';
      ALLOW_CONNECT='TRUE';
    'VCCPRIM_1P05'<9>:
      PIN_NUMBER='(0,0,0,0,0,0,0,0,AA45,0,0,0,0,0)';
      PINUSE='POWER';
      NO_LOAD_CHECK='Both';
      NO_IO_CHECK='Both';
      NO_ASSERT_CHECK='TRUE';
      NO_DIR_CHECK='TRUE';
      ALLOW_CONNECT='TRUE';
    'VCCPRIM_1P05'<8>:
      PIN_NUMBER='(0,0,0,0,0,0,0,0,AA46,0,0,0,0,0)';
      PINUSE='POWER';
      NO_LOAD_CHECK='Both';
      NO_IO_CHECK='Both';
      NO_ASSERT_CHECK='TRUE';
      NO_DIR_CHECK='TRUE';
      ALLOW_CONNECT='TRUE';
    'VCCPRIM_1P05'<7>:
      PIN_NUMBER='(0,0,0,0,0,0,0,0,AC26,0,0,0,0,0)';
      PINUSE='POWER';
      NO_LOAD_CHECK='Both';
      NO_IO_CHECK='Both';
      NO_ASSERT_CHECK='TRUE';
      NO_DIR_CHECK='TRUE';
      ALLOW_CONNECT='TRUE';
    'VCCPRIM_1P05'<6>:
      PIN_NUMBER='(0,0,0,0,0,0,0,0,AJ29,0,0,0,0,0)';
      PINUSE='POWER';
      NO_LOAD_CHECK='Both';
      NO_IO_CHECK='Both';
      NO_ASSERT_CHECK='TRUE';
      NO_DIR_CHECK='TRUE';
      ALLOW_CONNECT='TRUE';
    'VCCPRIM_1P05'<5>:
      PIN_NUMBER='(0,0,0,0,0,0,0,0,AM27,0,0,0,0,0)';
      PINUSE='POWER';
      NO_LOAD_CHECK='Both';
      NO_IO_CHECK='Both';
      NO_ASSERT_CHECK='TRUE';
      NO_DIR_CHECK='TRUE';
      ALLOW_CONNECT='TRUE';
    'VCCPRIM_1P05'<4>:
      PIN_NUMBER='(0,0,0,0,0,0,0,0,AT39,0,0,0,0,0)';
      PINUSE='POWER';
      NO_LOAD_CHECK='Both';
      NO_IO_CHECK='Both';
      NO_ASSERT_CHECK='TRUE';
      NO_DIR_CHECK='TRUE';
      ALLOW_CONNECT='TRUE';
    'VCCPRIM_1P05'<3>:
      PIN_NUMBER='(0,0,0,0,0,0,0,0,AU37,0,0,0,0,0)';
      PINUSE='POWER';
      NO_LOAD_CHECK='Both';
      NO_IO_CHECK='Both';
      NO_ASSERT_CHECK='TRUE';
      NO_DIR_CHECK='TRUE';
      ALLOW_CONNECT='TRUE';
    'VCCPRIM_1P05'<2>:
      PIN_NUMBER='(0,0,0,0,0,0,0,0,AU39,0,0,0,0,0)';
      PINUSE='POWER';
      NO_LOAD_CHECK='Both';
      NO_IO_CHECK='Both';
      NO_ASSERT_CHECK='TRUE';
      NO_DIR_CHECK='TRUE';
      ALLOW_CONNECT='TRUE';
    'VCCPRIM_1P05'<1>:
      PIN_NUMBER='(0,0,0,0,0,0,0,0,BE48,0,0,0,0,0)';
      PINUSE='POWER';
      NO_LOAD_CHECK='Both';
      NO_IO_CHECK='Both';
      NO_ASSERT_CHECK='TRUE';
      NO_DIR_CHECK='TRUE';
      ALLOW_CONNECT='TRUE';
    'VCCPRIM_1P05'<0>:
      PIN_NUMBER='(0,0,0,0,0,0,0,0,BF46,0,0,0,0,0)';
      PINUSE='POWER';
      NO_LOAD_CHECK='Both';
      NO_IO_CHECK='Both';
      NO_ASSERT_CHECK='TRUE';
      NO_DIR_CHECK='TRUE';
      ALLOW_CONNECT='TRUE';
    'VCCPRIM_AVID'<62>:
      PIN_NUMBER='(0,0,0,0,0,0,0,0,0,AK32,0,0,0,0)';
      PINUSE='UNSPEC';
      NO_LOAD_CHECK='Both';
      NO_IO_CHECK='Both';
      NO_ASSERT_CHECK='TRUE';
      NO_DIR_CHECK='TRUE';
      ALLOW_CONNECT='TRUE';
    'VCCPRIM_AVID'<61>:
      PIN_NUMBER='(0,0,0,0,0,0,0,0,0,U31,0,0,0,0)';
      PINUSE='POWER';
      NO_LOAD_CHECK='Both';
      NO_IO_CHECK='Both';
      NO_ASSERT_CHECK='TRUE';
      NO_DIR_CHECK='TRUE';
      ALLOW_CONNECT='TRUE';
    'VCCPRIM_AVID'<60>:
      PIN_NUMBER='(0,0,0,0,0,0,0,0,0,U35,0,0,0,0)';
      PINUSE='POWER';
      NO_LOAD_CHECK='Both';
      NO_IO_CHECK='Both';
      NO_ASSERT_CHECK='TRUE';
      NO_DIR_CHECK='TRUE';
      ALLOW_CONNECT='TRUE';
    'VCCPRIM_AVID'<59>:
      PIN_NUMBER='(0,0,0,0,0,0,0,0,0,U38,0,0,0,0)';
      PINUSE='POWER';
      NO_LOAD_CHECK='Both';
      NO_IO_CHECK='Both';
      NO_ASSERT_CHECK='TRUE';
      NO_DIR_CHECK='TRUE';
      ALLOW_CONNECT='TRUE';
    'VCCPRIM_AVID'<58>:
      PIN_NUMBER='(0,0,0,0,0,0,0,0,0,V29,0,0,0,0)';
      PINUSE='POWER';
      NO_LOAD_CHECK='Both';
      NO_IO_CHECK='Both';
      NO_ASSERT_CHECK='TRUE';
      NO_DIR_CHECK='TRUE';
      ALLOW_CONNECT='TRUE';
    'VCCPRIM_AVID'<57>:
      PIN_NUMBER='(0,0,0,0,0,0,0,0,0,V33,0,0,0,0)';
      PINUSE='POWER';
      NO_LOAD_CHECK='Both';
      NO_IO_CHECK='Both';
      NO_ASSERT_CHECK='TRUE';
      NO_DIR_CHECK='TRUE';
      ALLOW_CONNECT='TRUE';
    'VCCPRIM_AVID'<56>:
      PIN_NUMBER='(0,0,0,0,0,0,0,0,0,V40,0,0,0,0)';
      PINUSE='POWER';
      NO_LOAD_CHECK='Both';
      NO_IO_CHECK='Both';
      NO_ASSERT_CHECK='TRUE';
      NO_DIR_CHECK='TRUE';
      ALLOW_CONNECT='TRUE';
    'VCCPRIM_AVID'<55>:
      PIN_NUMBER='(0,0,0,0,0,0,0,0,0,Y29,0,0,0,0)';
      PINUSE='POWER';
      NO_LOAD_CHECK='Both';
      NO_IO_CHECK='Both';
      NO_ASSERT_CHECK='TRUE';
      NO_DIR_CHECK='TRUE';
      ALLOW_CONNECT='TRUE';
    'VCCPRIM_AVID'<54>:
      PIN_NUMBER='(0,0,0,0,0,0,0,0,0,Y30,0,0,0,0)';
      PINUSE='POWER';
      NO_LOAD_CHECK='Both';
      NO_IO_CHECK='Both';
      NO_ASSERT_CHECK='TRUE';
      NO_DIR_CHECK='TRUE';
      ALLOW_CONNECT='TRUE';
    'VCCPRIM_AVID'<53>:
      PIN_NUMBER='(0,0,0,0,0,0,0,0,0,Y32,0,0,0,0)';
      PINUSE='POWER';
      NO_LOAD_CHECK='Both';
      NO_IO_CHECK='Both';
      NO_ASSERT_CHECK='TRUE';
      NO_DIR_CHECK='TRUE';
      ALLOW_CONNECT='TRUE';
    'VCCPRIM_AVID'<52>:
      PIN_NUMBER='(0,0,0,0,0,0,0,0,0,Y34,0,0,0,0)';
      PINUSE='POWER';
      NO_LOAD_CHECK='Both';
      NO_IO_CHECK='Both';
      NO_ASSERT_CHECK='TRUE';
      NO_DIR_CHECK='TRUE';
      ALLOW_CONNECT='TRUE';
    'VCCPRIM_AVID'<51>:
      PIN_NUMBER='(0,0,0,0,0,0,0,0,0,Y36,0,0,0,0)';
      PINUSE='POWER';
      NO_LOAD_CHECK='Both';
      NO_IO_CHECK='Both';
      NO_ASSERT_CHECK='TRUE';
      NO_DIR_CHECK='TRUE';
      ALLOW_CONNECT='TRUE';
    'VCCPRIM_AVID'<50>:
      PIN_NUMBER='(0,0,0,0,0,0,0,0,0,Y37,0,0,0,0)';
      PINUSE='POWER';
      NO_LOAD_CHECK='Both';
      NO_IO_CHECK='Both';
      NO_ASSERT_CHECK='TRUE';
      NO_DIR_CHECK='TRUE';
      ALLOW_CONNECT='TRUE';
    'VCCPRIM_AVID'<49>:
      PIN_NUMBER='(0,0,0,0,0,0,0,0,0,Y39,0,0,0,0)';
      PINUSE='POWER';
      NO_LOAD_CHECK='Both';
      NO_IO_CHECK='Both';
      NO_ASSERT_CHECK='TRUE';
      NO_DIR_CHECK='TRUE';
      ALLOW_CONNECT='TRUE';
    'VCCPRIM_AVID'<48>:
      PIN_NUMBER='(0,0,0,0,0,0,0,0,0,Y41,0,0,0,0)';
      PINUSE='POWER';
      NO_LOAD_CHECK='Both';
      NO_IO_CHECK='Both';
      NO_ASSERT_CHECK='TRUE';
      NO_DIR_CHECK='TRUE';
      ALLOW_CONNECT='TRUE';
    'VCCPRIM_AVID'<47>:
      PIN_NUMBER='(0,0,0,0,0,0,0,0,0,AA29,0,0,0,0)';
      PINUSE='POWER';
      NO_LOAD_CHECK='Both';
      NO_IO_CHECK='Both';
      NO_ASSERT_CHECK='TRUE';
      NO_DIR_CHECK='TRUE';
      ALLOW_CONNECT='TRUE';
    'VCCPRIM_AVID'<46>:
      PIN_NUMBER='(0,0,0,0,0,0,0,0,0,AA30,0,0,0,0)';
      PINUSE='POWER';
      NO_LOAD_CHECK='Both';
      NO_IO_CHECK='Both';
      NO_ASSERT_CHECK='TRUE';
      NO_DIR_CHECK='TRUE';
      ALLOW_CONNECT='TRUE';
    'VCCPRIM_AVID'<45>:
      PIN_NUMBER='(0,0,0,0,0,0,0,0,0,AA32,0,0,0,0)';
      PINUSE='POWER';
      NO_LOAD_CHECK='Both';
      NO_IO_CHECK='Both';
      NO_ASSERT_CHECK='TRUE';
      NO_DIR_CHECK='TRUE';
      ALLOW_CONNECT='TRUE';
    'VCCPRIM_AVID'<44>:
      PIN_NUMBER='(0,0,0,0,0,0,0,0,0,AA34,0,0,0,0)';
      PINUSE='POWER';
      NO_LOAD_CHECK='Both';
      NO_IO_CHECK='Both';
      NO_ASSERT_CHECK='TRUE';
      NO_DIR_CHECK='TRUE';
      ALLOW_CONNECT='TRUE';
    'VCCPRIM_AVID'<43>:
      PIN_NUMBER='(0,0,0,0,0,0,0,0,0,AA36,0,0,0,0)';
      PINUSE='POWER';
      NO_LOAD_CHECK='Both';
      NO_IO_CHECK='Both';
      NO_ASSERT_CHECK='TRUE';
      NO_DIR_CHECK='TRUE';
      ALLOW_CONNECT='TRUE';
    'VCCPRIM_AVID'<42>:
      PIN_NUMBER='(0,0,0,0,0,0,0,0,0,AA37,0,0,0,0)';
      PINUSE='POWER';
      NO_LOAD_CHECK='Both';
      NO_IO_CHECK='Both';
      NO_ASSERT_CHECK='TRUE';
      NO_DIR_CHECK='TRUE';
      ALLOW_CONNECT='TRUE';
    'VCCPRIM_AVID'<41>:
      PIN_NUMBER='(0,0,0,0,0,0,0,0,0,AA39,0,0,0,0)';
      PINUSE='POWER';
      NO_LOAD_CHECK='Both';
      NO_IO_CHECK='Both';
      NO_ASSERT_CHECK='TRUE';
      NO_DIR_CHECK='TRUE';
      ALLOW_CONNECT='TRUE';
    'VCCPRIM_AVID'<40>:
      PIN_NUMBER='(0,0,0,0,0,0,0,0,0,AA41,0,0,0,0)';
      PINUSE='POWER';
      NO_LOAD_CHECK='Both';
      NO_IO_CHECK='Both';
      NO_ASSERT_CHECK='TRUE';
      NO_DIR_CHECK='TRUE';
      ALLOW_CONNECT='TRUE';
    'VCCPRIM_AVID'<39>:
      PIN_NUMBER='(0,0,0,0,0,0,0,0,0,AC29,0,0,0,0)';
      PINUSE='POWER';
      NO_LOAD_CHECK='Both';
      NO_IO_CHECK='Both';
      NO_ASSERT_CHECK='TRUE';
      NO_DIR_CHECK='TRUE';
      ALLOW_CONNECT='TRUE';
    'VCCPRIM_AVID'<38>:
      PIN_NUMBER='(0,0,0,0,0,0,0,0,0,AC30,0,0,0,0)';
      PINUSE='POWER';
      NO_LOAD_CHECK='Both';
      NO_IO_CHECK='Both';
      NO_ASSERT_CHECK='TRUE';
      NO_DIR_CHECK='TRUE';
      ALLOW_CONNECT='TRUE';
    'VCCPRIM_AVID'<37>:
      PIN_NUMBER='(0,0,0,0,0,0,0,0,0,AC32,0,0,0,0)';
      PINUSE='POWER';
      NO_LOAD_CHECK='Both';
      NO_IO_CHECK='Both';
      NO_ASSERT_CHECK='TRUE';
      NO_DIR_CHECK='TRUE';
      ALLOW_CONNECT='TRUE';
    'VCCPRIM_AVID'<36>:
      PIN_NUMBER='(0,0,0,0,0,0,0,0,0,AC34,0,0,0,0)';
      PINUSE='POWER';
      NO_LOAD_CHECK='Both';
      NO_IO_CHECK='Both';
      NO_ASSERT_CHECK='TRUE';
      NO_DIR_CHECK='TRUE';
      ALLOW_CONNECT='TRUE';
    'VCCPRIM_AVID'<35>:
      PIN_NUMBER='(0,0,0,0,0,0,0,0,0,AC36,0,0,0,0)';
      PINUSE='POWER';
      NO_LOAD_CHECK='Both';
      NO_IO_CHECK='Both';
      NO_ASSERT_CHECK='TRUE';
      NO_DIR_CHECK='TRUE';
      ALLOW_CONNECT='TRUE';
    'VCCPRIM_AVID'<34>:
      PIN_NUMBER='(0,0,0,0,0,0,0,0,0,AC37,0,0,0,0)';
      PINUSE='POWER';
      NO_LOAD_CHECK='Both';
      NO_IO_CHECK='Both';
      NO_ASSERT_CHECK='TRUE';
      NO_DIR_CHECK='TRUE';
      ALLOW_CONNECT='TRUE';
    'VCCPRIM_AVID'<33>:
      PIN_NUMBER='(0,0,0,0,0,0,0,0,0,AC39,0,0,0,0)';
      PINUSE='POWER';
      NO_LOAD_CHECK='Both';
      NO_IO_CHECK='Both';
      NO_ASSERT_CHECK='TRUE';
      NO_DIR_CHECK='TRUE';
      ALLOW_CONNECT='TRUE';
    'VCCPRIM_AVID'<32>:
      PIN_NUMBER='(0,0,0,0,0,0,0,0,0,AC41,0,0,0,0)';
      PINUSE='POWER';
      NO_LOAD_CHECK='Both';
      NO_IO_CHECK='Both';
      NO_ASSERT_CHECK='TRUE';
      NO_DIR_CHECK='TRUE';
      ALLOW_CONNECT='TRUE';
    'VCCPRIM_AVID'<31>:
      PIN_NUMBER='(0,0,0,0,0,0,0,0,0,U27,0,0,0,0)';
      PINUSE='UNSPEC';
      NO_LOAD_CHECK='Both';
      NO_IO_CHECK='Both';
      NO_ASSERT_CHECK='TRUE';
      NO_DIR_CHECK='TRUE';
      ALLOW_CONNECT='TRUE';
    'VCCPRIM_AVID'<30>:
      PIN_NUMBER='(0,0,0,0,0,0,0,0,0,AE30,0,0,0,0)';
      PINUSE='POWER';
      NO_LOAD_CHECK='Both';
      NO_IO_CHECK='Both';
      NO_ASSERT_CHECK='TRUE';
      NO_DIR_CHECK='TRUE';
      ALLOW_CONNECT='TRUE';
    'VCCPRIM_AVID'<29>:
      PIN_NUMBER='(0,0,0,0,0,0,0,0,0,AE32,0,0,0,0)';
      PINUSE='POWER';
      NO_LOAD_CHECK='Both';
      NO_IO_CHECK='Both';
      NO_ASSERT_CHECK='TRUE';
      NO_DIR_CHECK='TRUE';
      ALLOW_CONNECT='TRUE';
    'VCCPRIM_AVID'<28>:
      PIN_NUMBER='(0,0,0,0,0,0,0,0,0,AE34,0,0,0,0)';
      PINUSE='POWER';
      NO_LOAD_CHECK='Both';
      NO_IO_CHECK='Both';
      NO_ASSERT_CHECK='TRUE';
      NO_DIR_CHECK='TRUE';
      ALLOW_CONNECT='TRUE';
    'VCCPRIM_AVID'<27>:
      PIN_NUMBER='(0,0,0,0,0,0,0,0,0,AE36,0,0,0,0)';
      PINUSE='POWER';
      NO_LOAD_CHECK='Both';
      NO_IO_CHECK='Both';
      NO_ASSERT_CHECK='TRUE';
      NO_DIR_CHECK='TRUE';
      ALLOW_CONNECT='TRUE';
    'VCCPRIM_AVID'<26>:
      PIN_NUMBER='(0,0,0,0,0,0,0,0,0,AE37,0,0,0,0)';
      PINUSE='POWER';
      NO_LOAD_CHECK='Both';
      NO_IO_CHECK='Both';
      NO_ASSERT_CHECK='TRUE';
      NO_DIR_CHECK='TRUE';
      ALLOW_CONNECT='TRUE';
    'VCCPRIM_AVID'<25>:
      PIN_NUMBER='(0,0,0,0,0,0,0,0,0,AE39,0,0,0,0)';
      PINUSE='POWER';
      NO_LOAD_CHECK='Both';
      NO_IO_CHECK='Both';
      NO_ASSERT_CHECK='TRUE';
      NO_DIR_CHECK='TRUE';
      ALLOW_CONNECT='TRUE';
    'VCCPRIM_AVID'<24>:
      PIN_NUMBER='(0,0,0,0,0,0,0,0,0,AE41,0,0,0,0)';
      PINUSE='POWER';
      NO_LOAD_CHECK='Both';
      NO_IO_CHECK='Both';
      NO_ASSERT_CHECK='TRUE';
      NO_DIR_CHECK='TRUE';
      ALLOW_CONNECT='TRUE';
    'VCCPRIM_AVID'<23>:
      PIN_NUMBER='(0,0,0,0,0,0,0,0,0,AG32,0,0,0,0)';
      PINUSE='POWER';
      NO_LOAD_CHECK='Both';
      NO_IO_CHECK='Both';
      NO_ASSERT_CHECK='TRUE';
      NO_DIR_CHECK='TRUE';
      ALLOW_CONNECT='TRUE';
    'VCCPRIM_AVID'<22>:
      PIN_NUMBER='(0,0,0,0,0,0,0,0,0,AG34,0,0,0,0)';
      PINUSE='POWER';
      NO_LOAD_CHECK='Both';
      NO_IO_CHECK='Both';
      NO_ASSERT_CHECK='TRUE';
      NO_DIR_CHECK='TRUE';
      ALLOW_CONNECT='TRUE';
    'VCCPRIM_AVID'<21>:
      PIN_NUMBER='(0,0,0,0,0,0,0,0,0,AG36,0,0,0,0)';
      PINUSE='POWER';
      NO_LOAD_CHECK='Both';
      NO_IO_CHECK='Both';
      NO_ASSERT_CHECK='TRUE';
      NO_DIR_CHECK='TRUE';
      ALLOW_CONNECT='TRUE';
    'VCCPRIM_AVID'<20>:
      PIN_NUMBER='(0,0,0,0,0,0,0,0,0,AG37,0,0,0,0)';
      PINUSE='POWER';
      NO_LOAD_CHECK='Both';
      NO_IO_CHECK='Both';
      NO_ASSERT_CHECK='TRUE';
      NO_DIR_CHECK='TRUE';
      ALLOW_CONNECT='TRUE';
    'VCCPRIM_AVID'<19>:
      PIN_NUMBER='(0,0,0,0,0,0,0,0,0,AG39,0,0,0,0)';
      PINUSE='POWER';
      NO_LOAD_CHECK='Both';
      NO_IO_CHECK='Both';
      NO_ASSERT_CHECK='TRUE';
      NO_DIR_CHECK='TRUE';
      ALLOW_CONNECT='TRUE';
    'VCCPRIM_AVID'<18>:
      PIN_NUMBER='(0,0,0,0,0,0,0,0,0,AK34,0,0,0,0)';
      PINUSE='POWER';
      NO_LOAD_CHECK='Both';
      NO_IO_CHECK='Both';
      NO_ASSERT_CHECK='TRUE';
      NO_DIR_CHECK='TRUE';
      ALLOW_CONNECT='TRUE';
    'VCCPRIM_AVID'<17>:
      PIN_NUMBER='(0,0,0,0,0,0,0,0,0,AK37,0,0,0,0)';
      PINUSE='POWER';
      NO_LOAD_CHECK='Both';
      NO_IO_CHECK='Both';
      NO_ASSERT_CHECK='TRUE';
      NO_DIR_CHECK='TRUE';
      ALLOW_CONNECT='TRUE';
    'VCCPRIM_AVID'<16>:
      PIN_NUMBER='(0,0,0,0,0,0,0,0,0,AK39,0,0,0,0)';
      PINUSE='POWER';
      NO_LOAD_CHECK='Both';
      NO_IO_CHECK='Both';
      NO_ASSERT_CHECK='TRUE';
      NO_DIR_CHECK='TRUE';
      ALLOW_CONNECT='TRUE';
    'VCCPRIM_AVID'<15>:
      PIN_NUMBER='(0,0,0,0,0,0,0,0,0,AM32,0,0,0,0)';
      PINUSE='POWER';
      NO_LOAD_CHECK='Both';
      NO_IO_CHECK='Both';
      NO_ASSERT_CHECK='TRUE';
      NO_DIR_CHECK='TRUE';
      ALLOW_CONNECT='TRUE';
    'VCCPRIM_AVID'<14>:
      PIN_NUMBER='(0,0,0,0,0,0,0,0,0,AM34,0,0,0,0)';
      PINUSE='POWER';
      NO_LOAD_CHECK='Both';
      NO_IO_CHECK='Both';
      NO_ASSERT_CHECK='TRUE';
      NO_DIR_CHECK='TRUE';
      ALLOW_CONNECT='TRUE';
    'VCCPRIM_AVID'<13>:
      PIN_NUMBER='(0,0,0,0,0,0,0,0,0,AM36,0,0,0,0)';
      PINUSE='POWER';
      NO_LOAD_CHECK='Both';
      NO_IO_CHECK='Both';
      NO_ASSERT_CHECK='TRUE';
      NO_DIR_CHECK='TRUE';
      ALLOW_CONNECT='TRUE';
    'VCCPRIM_AVID'<12>:
      PIN_NUMBER='(0,0,0,0,0,0,0,0,0,AM37,0,0,0,0)';
      PINUSE='POWER';
      NO_LOAD_CHECK='Both';
      NO_IO_CHECK='Both';
      NO_ASSERT_CHECK='TRUE';
      NO_DIR_CHECK='TRUE';
      ALLOW_CONNECT='TRUE';
    'VCCPRIM_AVID'<11>:
      PIN_NUMBER='(0,0,0,0,0,0,0,0,0,AM39,0,0,0,0)';
      PINUSE='POWER';
      NO_LOAD_CHECK='Both';
      NO_IO_CHECK='Both';
      NO_ASSERT_CHECK='TRUE';
      NO_DIR_CHECK='TRUE';
      ALLOW_CONNECT='TRUE';
    'VCCPRIM_AVID'<10>:
      PIN_NUMBER='(0,0,0,0,0,0,0,0,0,AP32,0,0,0,0)';
      PINUSE='POWER';
      NO_LOAD_CHECK='Both';
      NO_IO_CHECK='Both';
      NO_ASSERT_CHECK='TRUE';
      NO_DIR_CHECK='TRUE';
      ALLOW_CONNECT='TRUE';
    'VCCPRIM_AVID'<9>:
      PIN_NUMBER='(0,0,0,0,0,0,0,0,0,AP34,0,0,0,0)';
      PINUSE='POWER';
      NO_LOAD_CHECK='Both';
      NO_IO_CHECK='Both';
      NO_ASSERT_CHECK='TRUE';
      NO_DIR_CHECK='TRUE';
      ALLOW_CONNECT='TRUE';
    'VCCPRIM_AVID'<8>:
      PIN_NUMBER='(0,0,0,0,0,0,0,0,0,AP36,0,0,0,0)';
      PINUSE='POWER';
      NO_LOAD_CHECK='Both';
      NO_IO_CHECK='Both';
      NO_ASSERT_CHECK='TRUE';
      NO_DIR_CHECK='TRUE';
      ALLOW_CONNECT='TRUE';
    'VCCPRIM_AVID'<7>:
      PIN_NUMBER='(0,0,0,0,0,0,0,0,0,AP37,0,0,0,0)';
      PINUSE='POWER';
      NO_LOAD_CHECK='Both';
      NO_IO_CHECK='Both';
      NO_ASSERT_CHECK='TRUE';
      NO_DIR_CHECK='TRUE';
      ALLOW_CONNECT='TRUE';
    'VCCPRIM_AVID'<6>:
      PIN_NUMBER='(0,0,0,0,0,0,0,0,0,AP39,0,0,0,0)';
      PINUSE='POWER';
      NO_LOAD_CHECK='Both';
      NO_IO_CHECK='Both';
      NO_ASSERT_CHECK='TRUE';
      NO_DIR_CHECK='TRUE';
      ALLOW_CONNECT='TRUE';
    'VCCPRIM_AVID'<5>:
      PIN_NUMBER='(0,0,0,0,0,0,0,0,0,AT32,0,0,0,0)';
      PINUSE='POWER';
      NO_LOAD_CHECK='Both';
      NO_IO_CHECK='Both';
      NO_ASSERT_CHECK='TRUE';
      NO_DIR_CHECK='TRUE';
      ALLOW_CONNECT='TRUE';
    'VCCPRIM_AVID'<4>:
      PIN_NUMBER='(0,0,0,0,0,0,0,0,0,AT34,0,0,0,0)';
      PINUSE='POWER';
      NO_LOAD_CHECK='Both';
      NO_IO_CHECK='Both';
      NO_ASSERT_CHECK='TRUE';
      NO_DIR_CHECK='TRUE';
      ALLOW_CONNECT='TRUE';
    'VCCPRIM_AVID'<3>:
      PIN_NUMBER='(0,0,0,0,0,0,0,0,0,AT36,0,0,0,0)';
      PINUSE='POWER';
      NO_LOAD_CHECK='Both';
      NO_IO_CHECK='Both';
      NO_ASSERT_CHECK='TRUE';
      NO_DIR_CHECK='TRUE';
      ALLOW_CONNECT='TRUE';
    'VCCPRIM_AVID'<2>:
      PIN_NUMBER='(0,0,0,0,0,0,0,0,0,AU32,0,0,0,0)';
      PINUSE='POWER';
      NO_LOAD_CHECK='Both';
      NO_IO_CHECK='Both';
      NO_ASSERT_CHECK='TRUE';
      NO_DIR_CHECK='TRUE';
      ALLOW_CONNECT='TRUE';
    'VCCPRIM_AVID'<1>:
      PIN_NUMBER='(0,0,0,0,0,0,0,0,0,AU34,0,0,0,0)';
      PINUSE='POWER';
      NO_LOAD_CHECK='Both';
      NO_IO_CHECK='Both';
      NO_ASSERT_CHECK='TRUE';
      NO_DIR_CHECK='TRUE';
      ALLOW_CONNECT='TRUE';
    'VCCPRIM_AVID'<0>:
      PIN_NUMBER='(0,0,0,0,0,0,0,0,0,AU36,0,0,0,0)';
      PINUSE='POWER';
      NO_LOAD_CHECK='Both';
      NO_IO_CHECK='Both';
      NO_ASSERT_CHECK='TRUE';
      NO_DIR_CHECK='TRUE';
      ALLOW_CONNECT='TRUE';
    'VCCPRIM_AVID_QAT_SENSE':
      PIN_NUMBER='(0,0,0,0,0,0,0,0,0,V37,0,0,0,0)';
      PINUSE='UNSPEC';
      NO_LOAD_CHECK='Both';
      NO_IO_CHECK='Both';
      NO_ASSERT_CHECK='TRUE';
      NO_DIR_CHECK='TRUE';
      ALLOW_CONNECT='TRUE';
    'VCCPRIM_AVID_SENSE':
      PIN_NUMBER='(0,0,0,0,0,0,0,0,0,AK36,0,0,0,0)';
      BIDIRECTIONAL='TRUE';
      INPUT_LOAD='(-0.01,0.01)';
      OUTPUT_LOAD='(1.0,-1.0)';
      PINUSE='BI';
    'VCCPRTC':
      PIN_NUMBER='(0,0,0,0,0,0,0,0,AJ27,0,0,0,0,0)';
      PINUSE='POWER';
      NO_LOAD_CHECK='Both';
      NO_IO_CHECK='Both';
      NO_ASSERT_CHECK='TRUE';
      NO_DIR_CHECK='TRUE';
      ALLOW_CONNECT='TRUE';
    'VCCPRTCPRIM_3P3':
      PIN_NUMBER='(0,0,0,0,0,0,0,0,AG29,0,0,0,0,0)';
      PINUSE='POWER';
      NO_LOAD_CHECK='Both';
      NO_IO_CHECK='Both';
      NO_ASSERT_CHECK='TRUE';
      NO_DIR_CHECK='TRUE';
      ALLOW_CONNECT='TRUE';
    'VCCPSPI':
      PIN_NUMBER='(0,0,0,0,0,0,0,0,AR24,0,0,0,0,0)';
      PINUSE='POWER';
      NO_LOAD_CHECK='Both';
      NO_IO_CHECK='Both';
      NO_ASSERT_CHECK='TRUE';
      NO_DIR_CHECK='TRUE';
      ALLOW_CONNECT='TRUE';
    'VCCPSPI_1P8':
      PIN_NUMBER='(0,0,0,0,0,0,0,0,AK29,0,0,0,0,0)';
      PINUSE='POWER';
      NO_LOAD_CHECK='Both';
      NO_IO_CHECK='Both';
      NO_ASSERT_CHECK='TRUE';
      NO_DIR_CHECK='TRUE';
      ALLOW_CONNECT='TRUE';
    'VCCPUSBDSW_3P3':
      PIN_NUMBER='(0,0,0,0,0,0,0,0,BA48,0,0,0,0,0)';
      PINUSE='POWER';
      NO_LOAD_CHECK='Both';
      NO_IO_CHECK='Both';
      NO_ASSERT_CHECK='TRUE';
      NO_DIR_CHECK='TRUE';
      ALLOW_CONNECT='TRUE';
    'VCCP_1P8'<1>:
      PIN_NUMBER='(0,0,0,0,0,0,0,0,AE26,0,0,0,0,0)';
      PINUSE='POWER';
      NO_LOAD_CHECK='Both';
      NO_IO_CHECK='Both';
      NO_ASSERT_CHECK='TRUE';
      NO_DIR_CHECK='TRUE';
      ALLOW_CONNECT='TRUE';
    'VCCP_1P8'<0>:
      PIN_NUMBER='(0,0,0,0,0,0,0,0,BD46,0,0,0,0,0)';
      PINUSE='POWER';
      NO_LOAD_CHECK='Both';
      NO_IO_CHECK='Both';
      NO_ASSERT_CHECK='TRUE';
      NO_DIR_CHECK='TRUE';
      ALLOW_CONNECT='TRUE';
    'VCCP_3P3'<5>:
      PIN_NUMBER='(0,0,0,0,0,0,0,0,AN24,0,0,0,0,0)';
      PINUSE='UNSPEC';
      NO_LOAD_CHECK='Both';
      NO_IO_CHECK='Both';
      NO_ASSERT_CHECK='TRUE';
      NO_DIR_CHECK='TRUE';
      ALLOW_CONNECT='TRUE';
    'VCCP_3P3'<2>:
      PIN_NUMBER='(0,0,0,0,0,0,0,0,AD24,0,0,0,0,0)';
      PINUSE='POWER';
      NO_LOAD_CHECK='Both';
      NO_IO_CHECK='Both';
      NO_ASSERT_CHECK='TRUE';
      NO_DIR_CHECK='TRUE';
      ALLOW_CONNECT='TRUE';
    'VCCP_3P3'<1>:
      PIN_NUMBER='(0,0,0,0,0,0,0,0,BA45,0,0,0,0,0)';
      PINUSE='POWER';
      NO_LOAD_CHECK='Both';
      NO_IO_CHECK='Both';
      NO_ASSERT_CHECK='TRUE';
      NO_DIR_CHECK='TRUE';
      ALLOW_CONNECT='TRUE';
    'VCCP_3P3'<0>:
      PIN_NUMBER='(0,0,0,0,0,0,0,0,BA46,0,0,0,0,0)';
      PINUSE='POWER';
      NO_LOAD_CHECK='Both';
      NO_IO_CHECK='Both';
      NO_ASSERT_CHECK='TRUE';
      NO_DIR_CHECK='TRUE';
      ALLOW_CONNECT='TRUE';
    'VCCP_HSIOPLLUNF_1P05':
      PIN_NUMBER='(0,0,0,0,0,0,0,0,AT48,0,0,0,0,0)';
      PINUSE='POWER';
      NO_LOAD_CHECK='Both';
      NO_IO_CHECK='Both';
      NO_ASSERT_CHECK='TRUE';
      NO_DIR_CHECK='TRUE';
      ALLOW_CONNECT='TRUE';
    'VCCP_HSIOPLL_1P05'<3>:
      PIN_NUMBER='(0,0,0,0,0,0,0,0,AP48,0,0,0,0,0)';
      PINUSE='POWER';
      NO_LOAD_CHECK='Both';
      NO_IO_CHECK='Both';
      NO_ASSERT_CHECK='TRUE';
      NO_DIR_CHECK='TRUE';
      ALLOW_CONNECT='TRUE';
    'VCCP_HSIOPLL_1P05'<2>:
      PIN_NUMBER='(0,0,0,0,0,0,0,0,AU48,0,0,0,0,0)';
      PINUSE='POWER';
      NO_LOAD_CHECK='Both';
      NO_IO_CHECK='Both';
      NO_ASSERT_CHECK='TRUE';
      NO_DIR_CHECK='TRUE';
      ALLOW_CONNECT='TRUE';
    'VCCP_HSIOPLL_1P05'<0>:
      PIN_NUMBER='(0,0,0,0,0,0,0,0,AW48,0,0,0,0,0)';
      PINUSE='POWER';
      NO_LOAD_CHECK='Both';
      NO_IO_CHECK='Both';
      NO_ASSERT_CHECK='TRUE';
      NO_DIR_CHECK='TRUE';
      ALLOW_CONNECT='TRUE';
    'VCCP_UPPLLUNF_1P05':
      PIN_NUMBER='(0,0,0,0,0,0,0,0,AM48,0,0,0,0,0)';
      PINUSE='POWER';
      NO_LOAD_CHECK='Both';
      NO_IO_CHECK='Both';
      NO_ASSERT_CHECK='TRUE';
      NO_DIR_CHECK='TRUE';
      ALLOW_CONNECT='TRUE';
    'VCCP_UPPLL_1P05'<2>:
      PIN_NUMBER='(0,0,0,0,0,0,0,0,AK50,0,0,0,0,0)';
      PINUSE='POWER';
      NO_LOAD_CHECK='Both';
      NO_IO_CHECK='Both';
      NO_ASSERT_CHECK='TRUE';
      NO_DIR_CHECK='TRUE';
      ALLOW_CONNECT='TRUE';
    'VCCP_UPPLL_1P05'<0>:
      PIN_NUMBER='(0,0,0,0,0,0,0,0,AN50,0,0,0,0,0)';
      PINUSE='POWER';
      NO_LOAD_CHECK='Both';
      NO_IO_CHECK='Both';
      NO_ASSERT_CHECK='TRUE';
      NO_DIR_CHECK='TRUE';
      ALLOW_CONNECT='TRUE';
    'VCCRTCEXT':
      PIN_NUMBER='(0,0,0,0,0,0,0,0,AG22,0,0,0,0,0)';
      PINUSE='POWER';
      NO_LOAD_CHECK='Both';
      NO_IO_CHECK='Both';
      NO_ASSERT_CHECK='TRUE';
      NO_DIR_CHECK='TRUE';
      ALLOW_CONNECT='TRUE';
    'VSS'<494>:
      PIN_NUMBER='(0,0,0,0,0,0,0,0,0,0,BP69,0,0,0)';
      PINUSE='GROUND';
      NO_LOAD_CHECK='Both';
      NO_IO_CHECK='Both';
      NO_ASSERT_CHECK='TRUE';
      NO_DIR_CHECK='TRUE';
      ALLOW_CONNECT='TRUE';
    'VSS'<493>:
      PIN_NUMBER='(0,0,0,0,0,0,0,0,0,0,BT69,0,0,0)';
      PINUSE='GROUND';
      NO_LOAD_CHECK='Both';
      NO_IO_CHECK='Both';
      NO_ASSERT_CHECK='TRUE';
      NO_DIR_CHECK='TRUE';
      ALLOW_CONNECT='TRUE';
    'VSS'<492>:
      PIN_NUMBER='(0,0,0,0,0,0,0,0,0,0,BU70,0,0,0)';
      PINUSE='GROUND';
      NO_LOAD_CHECK='Both';
      NO_IO_CHECK='Both';
      NO_ASSERT_CHECK='TRUE';
      NO_DIR_CHECK='TRUE';
      ALLOW_CONNECT='TRUE';
    'VSS'<491>:
      PIN_NUMBER='(0,0,0,0,0,0,0,0,0,0,BR70,0,0,0)';
      PINUSE='GROUND';
      NO_LOAD_CHECK='Both';
      NO_IO_CHECK='Both';
      NO_ASSERT_CHECK='TRUE';
      NO_DIR_CHECK='TRUE';
      ALLOW_CONNECT='TRUE';
    'VSS'<490>:
      PIN_NUMBER='(0,0,0,0,0,0,0,0,0,0,F70,0,0,0)';
      PINUSE='GROUND';
      NO_LOAD_CHECK='Both';
      NO_IO_CHECK='Both';
      NO_ASSERT_CHECK='TRUE';
      NO_DIR_CHECK='TRUE';
      ALLOW_CONNECT='TRUE';
    'VSS'<489>:
      PIN_NUMBER='(0,0,0,0,0,0,0,0,0,0,E70,0,0,0)';
      PINUSE='GROUND';
      NO_LOAD_CHECK='Both';
      NO_IO_CHECK='Both';
      NO_ASSERT_CHECK='TRUE';
      NO_DIR_CHECK='TRUE';
      ALLOW_CONNECT='TRUE';
    'VSS'<488>:
      PIN_NUMBER='(0,0,0,0,0,0,0,0,0,0,BU3,0,0,0)';
      PINUSE='GROUND';
      NO_LOAD_CHECK='Both';
      NO_IO_CHECK='Both';
      NO_ASSERT_CHECK='TRUE';
      NO_DIR_CHECK='TRUE';
      ALLOW_CONNECT='TRUE';
    'VSS'<487>:
      PIN_NUMBER='(0,0,0,0,0,0,0,0,0,0,BR3,0,0,0)';
      PINUSE='GROUND';
      NO_LOAD_CHECK='Both';
      NO_IO_CHECK='Both';
      NO_ASSERT_CHECK='TRUE';
      NO_DIR_CHECK='TRUE';
      ALLOW_CONNECT='TRUE';
    'VSS'<486>:
      PIN_NUMBER='(0,0,0,0,0,0,0,0,0,0,F3,0,0,0)';
      PINUSE='GROUND';
      NO_LOAD_CHECK='Both';
      NO_IO_CHECK='Both';
      NO_ASSERT_CHECK='TRUE';
      NO_DIR_CHECK='TRUE';
      ALLOW_CONNECT='TRUE';
    'VSS'<485>:
      PIN_NUMBER='(0,0,0,0,0,0,0,0,0,0,E3,0,0,0)';
      PINUSE='GROUND';
      NO_LOAD_CHECK='Both';
      NO_IO_CHECK='Both';
      NO_ASSERT_CHECK='TRUE';
      NO_DIR_CHECK='TRUE';
      ALLOW_CONNECT='TRUE';
    'VSS'<484>:
      PIN_NUMBER='(0,0,0,0,0,0,0,0,0,0,A5,0,0,0)';
      PINUSE='GROUND';
      NO_LOAD_CHECK='Both';
      NO_IO_CHECK='Both';
      NO_ASSERT_CHECK='TRUE';
      NO_DIR_CHECK='TRUE';
      ALLOW_CONNECT='TRUE';
    'VSS'<483>:
      PIN_NUMBER='(0,0,0,0,0,0,0,0,0,0,A7,0,0,0)';
      PINUSE='GROUND';
      NO_LOAD_CHECK='Both';
      NO_IO_CHECK='Both';
      NO_ASSERT_CHECK='TRUE';
      NO_DIR_CHECK='TRUE';
      ALLOW_CONNECT='TRUE';
    'VSS'<482>:
      PIN_NUMBER='(0,0,0,0,0,0,0,0,0,0,A9,0,0,0)';
      PINUSE='GROUND';
      NO_LOAD_CHECK='Both';
      NO_IO_CHECK='Both';
      NO_ASSERT_CHECK='TRUE';
      NO_DIR_CHECK='TRUE';
      ALLOW_CONNECT='TRUE';
    'VSS'<481>:
      PIN_NUMBER='(0,0,0,0,0,0,0,0,0,0,A65,0,0,0)';
      PINUSE='GROUND';
      NO_LOAD_CHECK='Both';
      NO_IO_CHECK='Both';
      NO_ASSERT_CHECK='TRUE';
      NO_DIR_CHECK='TRUE';
      ALLOW_CONNECT='TRUE';
    'VSS'<480>:
      PIN_NUMBER='(0,0,0,0,0,0,0,0,0,0,A66,0,0,0)';
      PINUSE='GROUND';
      NO_LOAD_CHECK='Both';
      NO_IO_CHECK='Both';
      NO_ASSERT_CHECK='TRUE';
      NO_DIR_CHECK='TRUE';
      ALLOW_CONNECT='TRUE';
    'VSS'<479>:
      PIN_NUMBER='(0,0,0,0,0,0,0,0,0,0,A68,0,0,0)';
      PINUSE='GROUND';
      NO_LOAD_CHECK='Both';
      NO_IO_CHECK='Both';
      NO_ASSERT_CHECK='TRUE';
      NO_DIR_CHECK='TRUE';
      ALLOW_CONNECT='TRUE';
    'VSS'<478>:
      PIN_NUMBER='(0,0,0,0,0,0,0,0,0,0,J1,0,0,0)';
      PINUSE='GROUND';
      NO_LOAD_CHECK='Both';
      NO_IO_CHECK='Both';
      NO_ASSERT_CHECK='TRUE';
      NO_DIR_CHECK='TRUE';
      ALLOW_CONNECT='TRUE';
    'VSS'<477>:
      PIN_NUMBER='(0,0,0,0,0,0,0,0,0,0,J72,0,0,0)';
      PINUSE='GROUND';
      NO_LOAD_CHECK='Both';
      NO_IO_CHECK='Both';
      NO_ASSERT_CHECK='TRUE';
      NO_DIR_CHECK='TRUE';
      ALLOW_CONNECT='TRUE';
    'VSS'<476>:
      PIN_NUMBER='(0,0,0,0,0,0,0,0,0,0,BN1,0,0,0)';
      PINUSE='GROUND';
      NO_LOAD_CHECK='Both';
      NO_IO_CHECK='Both';
      NO_ASSERT_CHECK='TRUE';
      NO_DIR_CHECK='TRUE';
      ALLOW_CONNECT='TRUE';
    'VSS'<475>:
      PIN_NUMBER='(0,0,0,0,0,0,0,0,0,0,BN72,0,0,0)';
      PINUSE='GROUND';
      NO_LOAD_CHECK='Both';
      NO_IO_CHECK='Both';
      NO_ASSERT_CHECK='TRUE';
      NO_DIR_CHECK='TRUE';
      ALLOW_CONNECT='TRUE';
    'VSS'<474>:
      PIN_NUMBER='(0,0,0,0,0,0,0,0,0,0,CA68,0,0,0)';
      PINUSE='GROUND';
      NO_LOAD_CHECK='Both';
      NO_IO_CHECK='Both';
      NO_ASSERT_CHECK='TRUE';
      NO_DIR_CHECK='TRUE';
      ALLOW_CONNECT='TRUE';
    'VSS'<473>:
      PIN_NUMBER='(0,0,0,0,0,0,0,0,0,0,CA66,0,0,0)';
      PINUSE='GROUND';
      NO_LOAD_CHECK='Both';
      NO_IO_CHECK='Both';
      NO_ASSERT_CHECK='TRUE';
      NO_DIR_CHECK='TRUE';
      ALLOW_CONNECT='TRUE';
    'VSS'<472>:
      PIN_NUMBER='(0,0,0,0,0,0,0,0,0,0,CA65,0,0,0)';
      PINUSE='GROUND';
      NO_LOAD_CHECK='Both';
      NO_IO_CHECK='Both';
      NO_ASSERT_CHECK='TRUE';
      NO_DIR_CHECK='TRUE';
      ALLOW_CONNECT='TRUE';
    'VSS'<471>:
      PIN_NUMBER='(0,0,0,0,0,0,0,0,0,0,CA9,0,0,0)';
      PINUSE='GROUND';
      NO_LOAD_CHECK='Both';
      NO_IO_CHECK='Both';
      NO_ASSERT_CHECK='TRUE';
      NO_DIR_CHECK='TRUE';
      ALLOW_CONNECT='TRUE';
    'VSS'<470>:
      PIN_NUMBER='(0,0,0,0,0,0,0,0,0,0,CA7,0,0,0)';
      PINUSE='GROUND';
      NO_LOAD_CHECK='Both';
      NO_IO_CHECK='Both';
      NO_ASSERT_CHECK='TRUE';
      NO_DIR_CHECK='TRUE';
      ALLOW_CONNECT='TRUE';
    'VSS'<469>:
      PIN_NUMBER='(0,0,0,0,0,0,0,0,0,0,CA5,0,0,0)';
      PINUSE='GROUND';
      NO_LOAD_CHECK='Both';
      NO_IO_CHECK='Both';
      NO_ASSERT_CHECK='TRUE';
      NO_DIR_CHECK='TRUE';
      ALLOW_CONNECT='TRUE';
    'VSS'<468>:
      PIN_NUMBER='(0,0,0,0,0,0,0,0,0,0,A70,0,0,0)';
      PINUSE='GROUND';
      NO_LOAD_CHECK='Both';
      NO_IO_CHECK='Both';
      NO_ASSERT_CHECK='TRUE';
      NO_DIR_CHECK='TRUE';
      ALLOW_CONNECT='TRUE';
    'VSS'<467>:
      PIN_NUMBER='(0,0,0,0,0,0,0,0,0,0,CA3,0,0,0)';
      PINUSE='GROUND';
      NO_LOAD_CHECK='Both';
      NO_IO_CHECK='Both';
      NO_ASSERT_CHECK='TRUE';
      NO_DIR_CHECK='TRUE';
      ALLOW_CONNECT='TRUE';
    'VSS'<466>:
      PIN_NUMBER='(0,0,0,0,0,0,0,0,0,0,BW1,0,0,0)';
      PINUSE='GROUND';
      NO_LOAD_CHECK='Both';
      NO_IO_CHECK='Both';
      NO_ASSERT_CHECK='TRUE';
      NO_DIR_CHECK='TRUE';
      ALLOW_CONNECT='TRUE';
    'VSS'<465>:
      PIN_NUMBER='(0,0,0,0,0,0,0,0,0,0,BU1,0,0,0)';
      PINUSE='GROUND';
      NO_LOAD_CHECK='Both';
      NO_IO_CHECK='Both';
      NO_ASSERT_CHECK='TRUE';
      NO_DIR_CHECK='TRUE';
      ALLOW_CONNECT='TRUE';
    'VSS'<464>:
      PIN_NUMBER='(0,0,0,0,0,0,0,0,0,0,BR1,0,0,0)';
      PINUSE='GROUND';
      NO_LOAD_CHECK='Both';
      NO_IO_CHECK='Both';
      NO_ASSERT_CHECK='TRUE';
      NO_DIR_CHECK='TRUE';
      ALLOW_CONNECT='TRUE';
    'VSS'<463>:
      PIN_NUMBER='(0,0,0,0,0,0,0,0,0,0,C3,0,0,0)';
      PINUSE='GROUND';
      NO_LOAD_CHECK='Both';
      NO_IO_CHECK='Both';
      NO_ASSERT_CHECK='TRUE';
      NO_DIR_CHECK='TRUE';
      ALLOW_CONNECT='TRUE';
    'VSS'<462>:
      PIN_NUMBER='(0,0,0,0,0,0,0,0,0,0,C72,0,0,0)';
      PINUSE='GROUND';
      NO_LOAD_CHECK='Both';
      NO_IO_CHECK='Both';
      NO_ASSERT_CHECK='TRUE';
      NO_DIR_CHECK='TRUE';
      ALLOW_CONNECT='TRUE';
    'VSS'<461>:
      PIN_NUMBER='(0,0,0,0,0,0,0,0,0,0,E1,0,0,0)';
      PINUSE='GROUND';
      NO_LOAD_CHECK='Both';
      NO_IO_CHECK='Both';
      NO_ASSERT_CHECK='TRUE';
      NO_DIR_CHECK='TRUE';
      ALLOW_CONNECT='TRUE';
    'VSS'<460>:
      PIN_NUMBER='(0,0,0,0,0,0,0,0,0,0,E72,0,0,0)';
      PINUSE='GROUND';
      NO_LOAD_CHECK='Both';
      NO_IO_CHECK='Both';
      NO_ASSERT_CHECK='TRUE';
      NO_DIR_CHECK='TRUE';
      ALLOW_CONNECT='TRUE';
    'VSS'<459>:
      PIN_NUMBER='(0,0,0,0,0,0,0,0,0,0,G1,0,0,0)';
      PINUSE='GROUND';
      NO_LOAD_CHECK='Both';
      NO_IO_CHECK='Both';
      NO_ASSERT_CHECK='TRUE';
      NO_DIR_CHECK='TRUE';
      ALLOW_CONNECT='TRUE';
    'VSS'<458>:
      PIN_NUMBER='(0,0,0,0,0,0,0,0,0,0,G72,0,0,0)';
      PINUSE='GROUND';
      NO_LOAD_CHECK='Both';
      NO_IO_CHECK='Both';
      NO_ASSERT_CHECK='TRUE';
      NO_DIR_CHECK='TRUE';
      ALLOW_CONNECT='TRUE';
    'VSS'<457>:
      PIN_NUMBER='(0,0,0,0,0,0,0,0,0,0,BR72,0,0,0)';
      PINUSE='GROUND';
      NO_LOAD_CHECK='Both';
      NO_IO_CHECK='Both';
      NO_ASSERT_CHECK='TRUE';
      NO_DIR_CHECK='TRUE';
      ALLOW_CONNECT='TRUE';
    'VSS'<456>:
      PIN_NUMBER='(0,0,0,0,0,0,0,0,0,0,BU72,0,0,0)';
      PINUSE='GROUND';
      NO_LOAD_CHECK='Both';
      NO_IO_CHECK='Both';
      NO_ASSERT_CHECK='TRUE';
      NO_DIR_CHECK='TRUE';
      ALLOW_CONNECT='TRUE';
    'VSS'<455>:
      PIN_NUMBER='(0,0,0,0,0,0,0,0,0,0,BW70,0,0,0)';
      PINUSE='GROUND';
      NO_LOAD_CHECK='Both';
      NO_IO_CHECK='Both';
      NO_ASSERT_CHECK='TRUE';
      NO_DIR_CHECK='TRUE';
      ALLOW_CONNECT='TRUE';
    'VSS'<454>:
      PIN_NUMBER='(0,0,0,0,0,0,0,0,0,0,BW72,0,0,0)';
      PINUSE='GROUND';
      NO_LOAD_CHECK='Both';
      NO_IO_CHECK='Both';
      NO_ASSERT_CHECK='TRUE';
      NO_DIR_CHECK='TRUE';
      ALLOW_CONNECT='TRUE';
    'VSS'<453>:
      PIN_NUMBER='(0,0,0,0,0,0,0,0,0,0,CA70,0,0,0)';
      PINUSE='GROUND';
      NO_LOAD_CHECK='Both';
      NO_IO_CHECK='Both';
      NO_ASSERT_CHECK='TRUE';
      NO_DIR_CHECK='TRUE';
      ALLOW_CONNECT='TRUE';
    'VSS'<452>:
      PIN_NUMBER='(0,0,0,0,0,0,0,0,0,0,BB48,0,0,0)';
      PINUSE='GROUND';
      NO_LOAD_CHECK='Both';
      NO_IO_CHECK='Both';
      NO_ASSERT_CHECK='TRUE';
      NO_DIR_CHECK='TRUE';
      ALLOW_CONNECT='TRUE';
    'VSS'<451>:
      PIN_NUMBER='(0,0,0,0,0,0,0,0,0,0,AT37,0,0,0)';
      PINUSE='GROUND';
      NO_LOAD_CHECK='Both';
      NO_IO_CHECK='Both';
      NO_ASSERT_CHECK='TRUE';
      NO_DIR_CHECK='TRUE';
      ALLOW_CONNECT='TRUE';
    'VSS'<450>:
      PIN_NUMBER='(0,0,0,0,0,0,0,0,0,0,Y72,0,0,0)';
      PINUSE='GROUND';
      NO_LOAD_CHECK='Both';
      NO_IO_CHECK='Both';
      NO_ASSERT_CHECK='TRUE';
      NO_DIR_CHECK='TRUE';
      ALLOW_CONNECT='TRUE';
    'VSS'<449>:
      PIN_NUMBER='(0,0,0,0,0,0,0,0,0,0,Y70,0,0,0)';
      PINUSE='GROUND';
      NO_LOAD_CHECK='Both';
      NO_IO_CHECK='Both';
      NO_ASSERT_CHECK='TRUE';
      NO_DIR_CHECK='TRUE';
      ALLOW_CONNECT='TRUE';
    'VSS'<448>:
      PIN_NUMBER='(0,0,0,0,0,0,0,0,0,0,A18,0,0,0)';
      PINUSE='GROUND';
      NO_LOAD_CHECK='Both';
      NO_IO_CHECK='Both';
      NO_ASSERT_CHECK='TRUE';
      NO_DIR_CHECK='TRUE';
      ALLOW_CONNECT='TRUE';
    'VSS'<447>:
      PIN_NUMBER='(0,0,0,0,0,0,0,0,0,0,A22,0,0,0)';
      PINUSE='GROUND';
      NO_LOAD_CHECK='Both';
      NO_IO_CHECK='Both';
      NO_ASSERT_CHECK='TRUE';
      NO_DIR_CHECK='TRUE';
      ALLOW_CONNECT='TRUE';
    'VSS'<446>:
      PIN_NUMBER='(0,0,0,0,0,0,0,0,0,0,A30,0,0,0)';
      PINUSE='GROUND';
      NO_LOAD_CHECK='Both';
      NO_IO_CHECK='Both';
      NO_ASSERT_CHECK='TRUE';
      NO_DIR_CHECK='TRUE';
      ALLOW_CONNECT='TRUE';
    'VSS'<445>:
      PIN_NUMBER='(0,0,0,0,0,0,0,0,0,0,A34,0,0,0)';
      PINUSE='GROUND';
      NO_LOAD_CHECK='Both';
      NO_IO_CHECK='Both';
      NO_ASSERT_CHECK='TRUE';
      NO_DIR_CHECK='TRUE';
      ALLOW_CONNECT='TRUE';
    'VSS'<444>:
      PIN_NUMBER='(0,0,0,0,0,0,0,0,0,0,A37,0,0,0)';
      PINUSE='GROUND';
      NO_LOAD_CHECK='Both';
      NO_IO_CHECK='Both';
      NO_ASSERT_CHECK='TRUE';
      NO_DIR_CHECK='TRUE';
      ALLOW_CONNECT='TRUE';
    'VSS'<443>:
      PIN_NUMBER='(0,0,0,0,0,0,0,0,0,0,A41,0,0,0)';
      PINUSE='GROUND';
      NO_LOAD_CHECK='Both';
      NO_IO_CHECK='Both';
      NO_ASSERT_CHECK='TRUE';
      NO_DIR_CHECK='TRUE';
      ALLOW_CONNECT='TRUE';
    'VSS'<442>:
      PIN_NUMBER='(0,0,0,0,0,0,0,0,0,0,B12,0,0,0)';
      PINUSE='GROUND';
      NO_LOAD_CHECK='Both';
      NO_IO_CHECK='Both';
      NO_ASSERT_CHECK='TRUE';
      NO_DIR_CHECK='TRUE';
      ALLOW_CONNECT='TRUE';
    'VSS'<441>:
      PIN_NUMBER='(0,0,0,0,0,0,0,0,0,0,B19,0,0,0)';
      PINUSE='GROUND';
      NO_LOAD_CHECK='Both';
      NO_IO_CHECK='Both';
      NO_ASSERT_CHECK='TRUE';
      NO_DIR_CHECK='TRUE';
      ALLOW_CONNECT='TRUE';
    'VSS'<440>:
      PIN_NUMBER='(0,0,0,0,0,0,0,0,0,0,B25,0,0,0)';
      PINUSE='GROUND';
      NO_LOAD_CHECK='Both';
      NO_IO_CHECK='Both';
      NO_ASSERT_CHECK='TRUE';
      NO_DIR_CHECK='TRUE';
      ALLOW_CONNECT='TRUE';
    'VSS'<439>:
      PIN_NUMBER='(0,0,0,0,0,0,0,0,0,0,B27,0,0,0)';
      PINUSE='GROUND';
      NO_LOAD_CHECK='Both';
      NO_IO_CHECK='Both';
      NO_ASSERT_CHECK='TRUE';
      NO_DIR_CHECK='TRUE';
      ALLOW_CONNECT='TRUE';
    'VSS'<438>:
      PIN_NUMBER='(0,0,0,0,0,0,0,0,0,0,B47,0,0,0)';
      PINUSE='GROUND';
      NO_LOAD_CHECK='Both';
      NO_IO_CHECK='Both';
      NO_ASSERT_CHECK='TRUE';
      NO_DIR_CHECK='TRUE';
      ALLOW_CONNECT='TRUE';
    'VSS'<437>:
      PIN_NUMBER='(0,0,0,0,0,0,0,0,0,0,C22,0,0,0)';
      PINUSE='GROUND';
      NO_LOAD_CHECK='Both';
      NO_IO_CHECK='Both';
      NO_ASSERT_CHECK='TRUE';
      NO_DIR_CHECK='TRUE';
      ALLOW_CONNECT='TRUE';
    'VSS'<436>:
      PIN_NUMBER='(0,0,0,0,0,0,0,0,0,0,C30,0,0,0)';
      PINUSE='GROUND';
      NO_LOAD_CHECK='Both';
      NO_IO_CHECK='Both';
      NO_ASSERT_CHECK='TRUE';
      NO_DIR_CHECK='TRUE';
      ALLOW_CONNECT='TRUE';
    'VSS'<435>:
      PIN_NUMBER='(0,0,0,0,0,0,0,0,0,0,C34,0,0,0)';
      PINUSE='GROUND';
      NO_LOAD_CHECK='Both';
      NO_IO_CHECK='Both';
      NO_ASSERT_CHECK='TRUE';
      NO_DIR_CHECK='TRUE';
      ALLOW_CONNECT='TRUE';
    'VSS'<434>:
      PIN_NUMBER='(0,0,0,0,0,0,0,0,0,0,C37,0,0,0)';
      PINUSE='GROUND';
      NO_LOAD_CHECK='Both';
      NO_IO_CHECK='Both';
      NO_ASSERT_CHECK='TRUE';
      NO_DIR_CHECK='TRUE';
      ALLOW_CONNECT='TRUE';
    'VSS'<433>:
      PIN_NUMBER='(0,0,0,0,0,0,0,0,0,0,C41,0,0,0)';
      PINUSE='GROUND';
      NO_LOAD_CHECK='Both';
      NO_IO_CHECK='Both';
      NO_ASSERT_CHECK='TRUE';
      NO_DIR_CHECK='TRUE';
      ALLOW_CONNECT='TRUE';
    'VSS'<432>:
      PIN_NUMBER='(0,0,0,0,0,0,0,0,0,0,C65,0,0,0)';
      PINUSE='GROUND';
      NO_LOAD_CHECK='Both';
      NO_IO_CHECK='Both';
      NO_ASSERT_CHECK='TRUE';
      NO_DIR_CHECK='TRUE';
      ALLOW_CONNECT='TRUE';
    'VSS'<431>:
      PIN_NUMBER='(0,0,0,0,0,0,0,0,0,0,D12,0,0,0)';
      PINUSE='GROUND';
      NO_LOAD_CHECK='Both';
      NO_IO_CHECK='Both';
      NO_ASSERT_CHECK='TRUE';
      NO_DIR_CHECK='TRUE';
      ALLOW_CONNECT='TRUE';
    'VSS'<430>:
      PIN_NUMBER='(0,0,0,0,0,0,0,0,0,0,D16,0,0,0)';
      PINUSE='GROUND';
      NO_LOAD_CHECK='Both';
      NO_IO_CHECK='Both';
      NO_ASSERT_CHECK='TRUE';
      NO_DIR_CHECK='TRUE';
      ALLOW_CONNECT='TRUE';
    'VSS'<429>:
      PIN_NUMBER='(0,0,0,0,0,0,0,0,0,0,D19,0,0,0)';
      PINUSE='GROUND';
      NO_LOAD_CHECK='Both';
      NO_IO_CHECK='Both';
      NO_ASSERT_CHECK='TRUE';
      NO_DIR_CHECK='TRUE';
      ALLOW_CONNECT='TRUE';
    'VSS'<428>:
      PIN_NUMBER='(0,0,0,0,0,0,0,0,0,0,D25,0,0,0)';
      PINUSE='GROUND';
      NO_LOAD_CHECK='Both';
      NO_IO_CHECK='Both';
      NO_ASSERT_CHECK='TRUE';
      NO_DIR_CHECK='TRUE';
      ALLOW_CONNECT='TRUE';
    'VSS'<427>:
      PIN_NUMBER='(0,0,0,0,0,0,0,0,0,0,D27,0,0,0)';
      PINUSE='GROUND';
      NO_LOAD_CHECK='Both';
      NO_IO_CHECK='Both';
      NO_ASSERT_CHECK='TRUE';
      NO_DIR_CHECK='TRUE';
      ALLOW_CONNECT='TRUE';
    'VSS'<426>:
      PIN_NUMBER='(0,0,0,0,0,0,0,0,0,0,E59,0,0,0)';
      PINUSE='GROUND';
      NO_LOAD_CHECK='Both';
      NO_IO_CHECK='Both';
      NO_ASSERT_CHECK='TRUE';
      NO_DIR_CHECK='TRUE';
      ALLOW_CONNECT='TRUE';
    'VSS'<425>:
      PIN_NUMBER='(0,0,0,0,0,0,0,0,0,0,E65,0,0,0)';
      PINUSE='GROUND';
      NO_LOAD_CHECK='Both';
      NO_IO_CHECK='Both';
      NO_ASSERT_CHECK='TRUE';
      NO_DIR_CHECK='TRUE';
      ALLOW_CONNECT='TRUE';
    'VSS'<424>:
      PIN_NUMBER='(0,0,0,0,0,0,0,0,0,0,D47,0,0,0)';
      PINUSE='GROUND';
      NO_LOAD_CHECK='Both';
      NO_IO_CHECK='Both';
      NO_ASSERT_CHECK='TRUE';
      NO_DIR_CHECK='TRUE';
      ALLOW_CONNECT='TRUE';
    'VSS'<423>:
      PIN_NUMBER='(0,0,0,0,0,0,0,0,0,0,E11,0,0,0)';
      PINUSE='GROUND';
      NO_LOAD_CHECK='Both';
      NO_IO_CHECK='Both';
      NO_ASSERT_CHECK='TRUE';
      NO_DIR_CHECK='TRUE';
      ALLOW_CONNECT='TRUE';
    'VSS'<422>:
      PIN_NUMBER='(0,0,0,0,0,0,0,0,0,0,E13,0,0,0)';
      PINUSE='GROUND';
      NO_LOAD_CHECK='Both';
      NO_IO_CHECK='Both';
      NO_ASSERT_CHECK='TRUE';
      NO_DIR_CHECK='TRUE';
      ALLOW_CONNECT='TRUE';
    'VSS'<421>:
      PIN_NUMBER='(0,0,0,0,0,0,0,0,0,0,E15,0,0,0)';
      PINUSE='GROUND';
      NO_LOAD_CHECK='Both';
      NO_IO_CHECK='Both';
      NO_ASSERT_CHECK='TRUE';
      NO_DIR_CHECK='TRUE';
      ALLOW_CONNECT='TRUE';
    'VSS'<420>:
      PIN_NUMBER='(0,0,0,0,0,0,0,0,0,0,E20,0,0,0)';
      PINUSE='GROUND';
      NO_LOAD_CHECK='Both';
      NO_IO_CHECK='Both';
      NO_ASSERT_CHECK='TRUE';
      NO_DIR_CHECK='TRUE';
      ALLOW_CONNECT='TRUE';
    'VSS'<419>:
      PIN_NUMBER='(0,0,0,0,0,0,0,0,0,0,E22,0,0,0)';
      PINUSE='GROUND';
      NO_LOAD_CHECK='Both';
      NO_IO_CHECK='Both';
      NO_ASSERT_CHECK='TRUE';
      NO_DIR_CHECK='TRUE';
      ALLOW_CONNECT='TRUE';
    'VSS'<418>:
      PIN_NUMBER='(0,0,0,0,0,0,0,0,0,0,E24,0,0,0)';
      PINUSE='GROUND';
      NO_LOAD_CHECK='Both';
      NO_IO_CHECK='Both';
      NO_ASSERT_CHECK='TRUE';
      NO_DIR_CHECK='TRUE';
      ALLOW_CONNECT='TRUE';
    'VSS'<417>:
      PIN_NUMBER='(0,0,0,0,0,0,0,0,0,0,E26,0,0,0)';
      PINUSE='GROUND';
      NO_LOAD_CHECK='Both';
      NO_IO_CHECK='Both';
      NO_ASSERT_CHECK='TRUE';
      NO_DIR_CHECK='TRUE';
      ALLOW_CONNECT='TRUE';
    'VSS'<416>:
      PIN_NUMBER='(0,0,0,0,0,0,0,0,0,0,E28,0,0,0)';
      PINUSE='GROUND';
      NO_LOAD_CHECK='Both';
      NO_IO_CHECK='Both';
      NO_ASSERT_CHECK='TRUE';
      NO_DIR_CHECK='TRUE';
      ALLOW_CONNECT='TRUE';
    'VSS'<415>:
      PIN_NUMBER='(0,0,0,0,0,0,0,0,0,0,E30,0,0,0)';
      PINUSE='GROUND';
      NO_LOAD_CHECK='Both';
      NO_IO_CHECK='Both';
      NO_ASSERT_CHECK='TRUE';
      NO_DIR_CHECK='TRUE';
      ALLOW_CONNECT='TRUE';
    'VSS'<414>:
      PIN_NUMBER='(0,0,0,0,0,0,0,0,0,0,E32,0,0,0)';
      PINUSE='GROUND';
      NO_LOAD_CHECK='Both';
      NO_IO_CHECK='Both';
      NO_ASSERT_CHECK='TRUE';
      NO_DIR_CHECK='TRUE';
      ALLOW_CONNECT='TRUE';
    'VSS'<413>:
      PIN_NUMBER='(0,0,0,0,0,0,0,0,0,0,E34,0,0,0)';
      PINUSE='GROUND';
      NO_LOAD_CHECK='Both';
      NO_IO_CHECK='Both';
      NO_ASSERT_CHECK='TRUE';
      NO_DIR_CHECK='TRUE';
      ALLOW_CONNECT='TRUE';
    'VSS'<412>:
      PIN_NUMBER='(0,0,0,0,0,0,0,0,0,0,E37,0,0,0)';
      PINUSE='GROUND';
      NO_LOAD_CHECK='Both';
      NO_IO_CHECK='Both';
      NO_ASSERT_CHECK='TRUE';
      NO_DIR_CHECK='TRUE';
      ALLOW_CONNECT='TRUE';
    'VSS'<411>:
      PIN_NUMBER='(0,0,0,0,0,0,0,0,0,0,E39,0,0,0)';
      PINUSE='GROUND';
      NO_LOAD_CHECK='Both';
      NO_IO_CHECK='Both';
      NO_ASSERT_CHECK='TRUE';
      NO_DIR_CHECK='TRUE';
      ALLOW_CONNECT='TRUE';
    'VSS'<410>:
      PIN_NUMBER='(0,0,0,0,0,0,0,0,0,0,E41,0,0,0)';
      PINUSE='GROUND';
      NO_LOAD_CHECK='Both';
      NO_IO_CHECK='Both';
      NO_ASSERT_CHECK='TRUE';
      NO_DIR_CHECK='TRUE';
      ALLOW_CONNECT='TRUE';
    'VSS'<409>:
      PIN_NUMBER='(0,0,0,0,0,0,0,0,0,0,E43,0,0,0)';
      PINUSE='GROUND';
      NO_LOAD_CHECK='Both';
      NO_IO_CHECK='Both';
      NO_ASSERT_CHECK='TRUE';
      NO_DIR_CHECK='TRUE';
      ALLOW_CONNECT='TRUE';
    'VSS'<408>:
      PIN_NUMBER='(0,0,0,0,0,0,0,0,0,0,E45,0,0,0)';
      PINUSE='GROUND';
      NO_LOAD_CHECK='Both';
      NO_IO_CHECK='Both';
      NO_ASSERT_CHECK='TRUE';
      NO_DIR_CHECK='TRUE';
      ALLOW_CONNECT='TRUE';
    'VSS'<407>:
      PIN_NUMBER='(0,0,0,0,0,0,0,0,0,0,E48,0,0,0)';
      PINUSE='GROUND';
      NO_LOAD_CHECK='Both';
      NO_IO_CHECK='Both';
      NO_ASSERT_CHECK='TRUE';
      NO_DIR_CHECK='TRUE';
      ALLOW_CONNECT='TRUE';
    'VSS'<406>:
      PIN_NUMBER='(0,0,0,0,0,0,0,0,0,0,E50,0,0,0)';
      PINUSE='GROUND';
      NO_LOAD_CHECK='Both';
      NO_IO_CHECK='Both';
      NO_ASSERT_CHECK='TRUE';
      NO_DIR_CHECK='TRUE';
      ALLOW_CONNECT='TRUE';
    'VSS'<405>:
      PIN_NUMBER='(0,0,0,0,0,0,0,0,0,0,E52,0,0,0)';
      PINUSE='GROUND';
      NO_LOAD_CHECK='Both';
      NO_IO_CHECK='Both';
      NO_ASSERT_CHECK='TRUE';
      NO_DIR_CHECK='TRUE';
      ALLOW_CONNECT='TRUE';
    'VSS'<404>:
      PIN_NUMBER='(0,0,0,0,0,0,0,0,0,0,E54,0,0,0)';
      PINUSE='GROUND';
      NO_LOAD_CHECK='Both';
      NO_IO_CHECK='Both';
      NO_ASSERT_CHECK='TRUE';
      NO_DIR_CHECK='TRUE';
      ALLOW_CONNECT='TRUE';
    'VSS'<403>:
      PIN_NUMBER='(0,0,0,0,0,0,0,0,0,0,E57,0,0,0)';
      PINUSE='GROUND';
      NO_LOAD_CHECK='Both';
      NO_IO_CHECK='Both';
      NO_ASSERT_CHECK='TRUE';
      NO_DIR_CHECK='TRUE';
      ALLOW_CONNECT='TRUE';
    'VSS'<402>:
      PIN_NUMBER='(0,0,0,0,0,0,0,0,0,0,E6,0,0,0)';
      PINUSE='GROUND';
      NO_LOAD_CHECK='Both';
      NO_IO_CHECK='Both';
      NO_ASSERT_CHECK='TRUE';
      NO_DIR_CHECK='TRUE';
      ALLOW_CONNECT='TRUE';
    'VSS'<401>:
      PIN_NUMBER='(0,0,0,0,0,0,0,0,0,0,E61,0,0,0)';
      PINUSE='GROUND';
      NO_LOAD_CHECK='Both';
      NO_IO_CHECK='Both';
      NO_ASSERT_CHECK='TRUE';
      NO_DIR_CHECK='TRUE';
      ALLOW_CONNECT='TRUE';
    'VSS'<400>:
      PIN_NUMBER='(0,0,0,0,0,0,0,0,0,0,E63,0,0,0)';
      PINUSE='GROUND';
      NO_LOAD_CHECK='Both';
      NO_IO_CHECK='Both';
      NO_ASSERT_CHECK='TRUE';
      NO_DIR_CHECK='TRUE';
      ALLOW_CONNECT='TRUE';
    'VSS'<399>:
      PIN_NUMBER='(0,0,0,0,0,0,0,0,0,0,G59,0,0,0)';
      PINUSE='GROUND';
      NO_LOAD_CHECK='Both';
      NO_IO_CHECK='Both';
      NO_ASSERT_CHECK='TRUE';
      NO_DIR_CHECK='TRUE';
      ALLOW_CONNECT='TRUE';
    'VSS'<398>:
      PIN_NUMBER='(0,0,0,0,0,0,0,0,0,0,E9,0,0,0)';
      PINUSE='GROUND';
      NO_LOAD_CHECK='Both';
      NO_IO_CHECK='Both';
      NO_ASSERT_CHECK='TRUE';
      NO_DIR_CHECK='TRUE';
      ALLOW_CONNECT='TRUE';
    'VSS'<397>:
      PIN_NUMBER='(0,0,0,0,0,0,0,0,0,0,G22,0,0,0)';
      PINUSE='GROUND';
      NO_LOAD_CHECK='Both';
      NO_IO_CHECK='Both';
      NO_ASSERT_CHECK='TRUE';
      NO_DIR_CHECK='TRUE';
      ALLOW_CONNECT='TRUE';
    'VSS'<396>:
      PIN_NUMBER='(0,0,0,0,0,0,0,0,0,0,G29,0,0,0)';
      PINUSE='GROUND';
      NO_LOAD_CHECK='Both';
      NO_IO_CHECK='Both';
      NO_ASSERT_CHECK='TRUE';
      NO_DIR_CHECK='TRUE';
      ALLOW_CONNECT='TRUE';
    'VSS'<395>:
      PIN_NUMBER='(0,0,0,0,0,0,0,0,0,0,G37,0,0,0)';
      PINUSE='GROUND';
      NO_LOAD_CHECK='Both';
      NO_IO_CHECK='Both';
      NO_ASSERT_CHECK='TRUE';
      NO_DIR_CHECK='TRUE';
      ALLOW_CONNECT='TRUE';
    'VSS'<394>:
      PIN_NUMBER='(0,0,0,0,0,0,0,0,0,0,G48,0,0,0)';
      PINUSE='GROUND';
      NO_LOAD_CHECK='Both';
      NO_IO_CHECK='Both';
      NO_ASSERT_CHECK='TRUE';
      NO_DIR_CHECK='TRUE';
      ALLOW_CONNECT='TRUE';
    'VSS'<393>:
      PIN_NUMBER='(0,0,0,0,0,0,0,0,0,0,G6,0,0,0)';
      PINUSE='GROUND';
      NO_LOAD_CHECK='Both';
      NO_IO_CHECK='Both';
      NO_ASSERT_CHECK='TRUE';
      NO_DIR_CHECK='TRUE';
      ALLOW_CONNECT='TRUE';
    'VSS'<392>:
      PIN_NUMBER='(0,0,0,0,0,0,0,0,0,0,G63,0,0,0)';
      PINUSE='GROUND';
      NO_LOAD_CHECK='Both';
      NO_IO_CHECK='Both';
      NO_ASSERT_CHECK='TRUE';
      NO_DIR_CHECK='TRUE';
      ALLOW_CONNECT='TRUE';
    'VSS'<391>:
      PIN_NUMBER='(0,0,0,0,0,0,0,0,0,0,G66,0,0,0)';
      PINUSE='GROUND';
      NO_LOAD_CHECK='Both';
      NO_IO_CHECK='Both';
      NO_ASSERT_CHECK='TRUE';
      NO_DIR_CHECK='TRUE';
      ALLOW_CONNECT='TRUE';
    'VSS'<390>:
      PIN_NUMBER='(0,0,0,0,0,0,0,0,0,0,H58,0,0,0)';
      PINUSE='GROUND';
      NO_LOAD_CHECK='Both';
      NO_IO_CHECK='Both';
      NO_ASSERT_CHECK='TRUE';
      NO_DIR_CHECK='TRUE';
      ALLOW_CONNECT='TRUE';
    'VSS'<389>:
      PIN_NUMBER='(0,0,0,0,0,0,0,0,0,0,J29,0,0,0)';
      PINUSE='GROUND';
      NO_LOAD_CHECK='Both';
      NO_IO_CHECK='Both';
      NO_ASSERT_CHECK='TRUE';
      NO_DIR_CHECK='TRUE';
      ALLOW_CONNECT='TRUE';
    'VSS'<388>:
      PIN_NUMBER='(0,0,0,0,0,0,0,0,0,0,J5,0,0,0)';
      PINUSE='GROUND';
      NO_LOAD_CHECK='Both';
      NO_IO_CHECK='Both';
      NO_ASSERT_CHECK='TRUE';
      NO_DIR_CHECK='TRUE';
      ALLOW_CONNECT='TRUE';
    'VSS'<387>:
      PIN_NUMBER='(0,0,0,0,0,0,0,0,0,0,J7,0,0,0)';
      PINUSE='GROUND';
      NO_LOAD_CHECK='Both';
      NO_IO_CHECK='Both';
      NO_ASSERT_CHECK='TRUE';
      NO_DIR_CHECK='TRUE';
      ALLOW_CONNECT='TRUE';
    'VSS'<386>:
      PIN_NUMBER='(0,0,0,0,0,0,0,0,0,0,H65,0,0,0)';
      PINUSE='GROUND';
      NO_LOAD_CHECK='Both';
      NO_IO_CHECK='Both';
      NO_ASSERT_CHECK='TRUE';
      NO_DIR_CHECK='TRUE';
      ALLOW_CONNECT='TRUE';
    'VSS'<385>:
      PIN_NUMBER='(0,0,0,0,0,0,0,0,0,0,J11,0,0,0)';
      PINUSE='GROUND';
      NO_LOAD_CHECK='Both';
      NO_IO_CHECK='Both';
      NO_ASSERT_CHECK='TRUE';
      NO_DIR_CHECK='TRUE';
      ALLOW_CONNECT='TRUE';
    'VSS'<384>:
      PIN_NUMBER='(0,0,0,0,0,0,0,0,0,0,J15,0,0,0)';
      PINUSE='GROUND';
      NO_LOAD_CHECK='Both';
      NO_IO_CHECK='Both';
      NO_ASSERT_CHECK='TRUE';
      NO_DIR_CHECK='TRUE';
      ALLOW_CONNECT='TRUE';
    'VSS'<383>:
      PIN_NUMBER='(0,0,0,0,0,0,0,0,0,0,J22,0,0,0)';
      PINUSE='GROUND';
      NO_LOAD_CHECK='Both';
      NO_IO_CHECK='Both';
      NO_ASSERT_CHECK='TRUE';
      NO_DIR_CHECK='TRUE';
      ALLOW_CONNECT='TRUE';
    'VSS'<382>:
      PIN_NUMBER='(0,0,0,0,0,0,0,0,0,0,J37,0,0,0)';
      PINUSE='GROUND';
      NO_LOAD_CHECK='Both';
      NO_IO_CHECK='Both';
      NO_ASSERT_CHECK='TRUE';
      NO_DIR_CHECK='TRUE';
      ALLOW_CONNECT='TRUE';
    'VSS'<381>:
      PIN_NUMBER='(0,0,0,0,0,0,0,0,0,0,J44,0,0,0)';
      PINUSE='GROUND';
      NO_LOAD_CHECK='Both';
      NO_IO_CHECK='Both';
      NO_ASSERT_CHECK='TRUE';
      NO_DIR_CHECK='TRUE';
      ALLOW_CONNECT='TRUE';
    'VSS'<380>:
      PIN_NUMBER='(0,0,0,0,0,0,0,0,0,0,J59,0,0,0)';
      PINUSE='GROUND';
      NO_LOAD_CHECK='Both';
      NO_IO_CHECK='Both';
      NO_ASSERT_CHECK='TRUE';
      NO_DIR_CHECK='TRUE';
      ALLOW_CONNECT='TRUE';
    'VSS'<379>:
      PIN_NUMBER='(0,0,0,0,0,0,0,0,0,0,J68,0,0,0)';
      PINUSE='GROUND';
      NO_LOAD_CHECK='Both';
      NO_IO_CHECK='Both';
      NO_ASSERT_CHECK='TRUE';
      NO_DIR_CHECK='TRUE';
      ALLOW_CONNECT='TRUE';
    'VSS'<378>:
      PIN_NUMBER='(0,0,0,0,0,0,0,0,0,0,J70,0,0,0)';
      PINUSE='GROUND';
      NO_LOAD_CHECK='Both';
      NO_IO_CHECK='Both';
      NO_ASSERT_CHECK='TRUE';
      NO_DIR_CHECK='TRUE';
      ALLOW_CONNECT='TRUE';
    'VSS'<377>:
      PIN_NUMBER='(0,0,0,0,0,0,0,0,0,0,K54,0,0,0)';
      PINUSE='GROUND';
      NO_LOAD_CHECK='Both';
      NO_IO_CHECK='Both';
      NO_ASSERT_CHECK='TRUE';
      NO_DIR_CHECK='TRUE';
      ALLOW_CONNECT='TRUE';
    'VSS'<376>:
      PIN_NUMBER='(0,0,0,0,0,0,0,0,0,0,K69,0,0,0)';
      PINUSE='GROUND';
      NO_LOAD_CHECK='Both';
      NO_IO_CHECK='Both';
      NO_ASSERT_CHECK='TRUE';
      NO_DIR_CHECK='TRUE';
      ALLOW_CONNECT='TRUE';
    'VSS'<375>:
      PIN_NUMBER='(0,0,0,0,0,0,0,0,0,0,K71,0,0,0)';
      PINUSE='GROUND';
      NO_LOAD_CHECK='Both';
      NO_IO_CHECK='Both';
      NO_ASSERT_CHECK='TRUE';
      NO_DIR_CHECK='TRUE';
      ALLOW_CONNECT='TRUE';
    'VSS'<374>:
      PIN_NUMBER='(0,0,0,0,0,0,0,0,0,0,L5,0,0,0)';
      PINUSE='GROUND';
      NO_LOAD_CHECK='Both';
      NO_IO_CHECK='Both';
      NO_ASSERT_CHECK='TRUE';
      NO_DIR_CHECK='TRUE';
      ALLOW_CONNECT='TRUE';
    'VSS'<373>:
      PIN_NUMBER='(0,0,0,0,0,0,0,0,0,0,L68,0,0,0)';
      PINUSE='GROUND';
      NO_LOAD_CHECK='Both';
      NO_IO_CHECK='Both';
      NO_ASSERT_CHECK='TRUE';
      NO_DIR_CHECK='TRUE';
      ALLOW_CONNECT='TRUE';
    'VSS'<372>:
      PIN_NUMBER='(0,0,0,0,0,0,0,0,0,0,M2,0,0,0)';
      PINUSE='GROUND';
      NO_LOAD_CHECK='Both';
      NO_IO_CHECK='Both';
      NO_ASSERT_CHECK='TRUE';
      NO_DIR_CHECK='TRUE';
      ALLOW_CONNECT='TRUE';
    'VSS'<371>:
      PIN_NUMBER='(0,0,0,0,0,0,0,0,0,0,M22,0,0,0)';
      PINUSE='GROUND';
      NO_LOAD_CHECK='Both';
      NO_IO_CHECK='Both';
      NO_ASSERT_CHECK='TRUE';
      NO_DIR_CHECK='TRUE';
      ALLOW_CONNECT='TRUE';
    'VSS'<370>:
      PIN_NUMBER='(0,0,0,0,0,0,0,0,0,0,M26,0,0,0)';
      PINUSE='GROUND';
      NO_LOAD_CHECK='Both';
      NO_IO_CHECK='Both';
      NO_ASSERT_CHECK='TRUE';
      NO_DIR_CHECK='TRUE';
      ALLOW_CONNECT='TRUE';
    'VSS'<369>:
      PIN_NUMBER='(0,0,0,0,0,0,0,0,0,0,M29,0,0,0)';
      PINUSE='GROUND';
      NO_LOAD_CHECK='Both';
      NO_IO_CHECK='Both';
      NO_ASSERT_CHECK='TRUE';
      NO_DIR_CHECK='TRUE';
      ALLOW_CONNECT='TRUE';
    'VSS'<368>:
      PIN_NUMBER='(0,0,0,0,0,0,0,0,0,0,M33,0,0,0)';
      PINUSE='GROUND';
      NO_LOAD_CHECK='Both';
      NO_IO_CHECK='Both';
      NO_ASSERT_CHECK='TRUE';
      NO_DIR_CHECK='TRUE';
      ALLOW_CONNECT='TRUE';
    'VSS'<367>:
      PIN_NUMBER='(0,0,0,0,0,0,0,0,0,0,M37,0,0,0)';
      PINUSE='GROUND';
      NO_LOAD_CHECK='Both';
      NO_IO_CHECK='Both';
      NO_ASSERT_CHECK='TRUE';
      NO_DIR_CHECK='TRUE';
      ALLOW_CONNECT='TRUE';
    'VSS'<366>:
      PIN_NUMBER='(0,0,0,0,0,0,0,0,0,0,M4,0,0,0)';
      PINUSE='GROUND';
      NO_LOAD_CHECK='Both';
      NO_IO_CHECK='Both';
      NO_ASSERT_CHECK='TRUE';
      NO_DIR_CHECK='TRUE';
      ALLOW_CONNECT='TRUE';
    'VSS'<365>:
      PIN_NUMBER='(0,0,0,0,0,0,0,0,0,0,M40,0,0,0)';
      PINUSE='GROUND';
      NO_LOAD_CHECK='Both';
      NO_IO_CHECK='Both';
      NO_ASSERT_CHECK='TRUE';
      NO_DIR_CHECK='TRUE';
      ALLOW_CONNECT='TRUE';
    'VSS'<364>:
      PIN_NUMBER='(0,0,0,0,0,0,0,0,0,0,N42,0,0,0)';
      PINUSE='GROUND';
      NO_LOAD_CHECK='Both';
      NO_IO_CHECK='Both';
      NO_ASSERT_CHECK='TRUE';
      NO_DIR_CHECK='TRUE';
      ALLOW_CONNECT='TRUE';
    'VSS'<363>:
      PIN_NUMBER='(0,0,0,0,0,0,0,0,0,0,N50,0,0,0)';
      PINUSE='GROUND';
      NO_LOAD_CHECK='Both';
      NO_IO_CHECK='Both';
      NO_ASSERT_CHECK='TRUE';
      NO_DIR_CHECK='TRUE';
      ALLOW_CONNECT='TRUE';
    'VSS'<362>:
      PIN_NUMBER='(0,0,0,0,0,0,0,0,0,0,M44,0,0,0)';
      PINUSE='GROUND';
      NO_LOAD_CHECK='Both';
      NO_IO_CHECK='Both';
      NO_ASSERT_CHECK='TRUE';
      NO_DIR_CHECK='TRUE';
      ALLOW_CONNECT='TRUE';
    'VSS'<361>:
      PIN_NUMBER='(0,0,0,0,0,0,0,0,0,0,M48,0,0,0)';
      PINUSE='GROUND';
      NO_LOAD_CHECK='Both';
      NO_IO_CHECK='Both';
      NO_ASSERT_CHECK='TRUE';
      NO_DIR_CHECK='TRUE';
      ALLOW_CONNECT='TRUE';
    'VSS'<360>:
      PIN_NUMBER='(0,0,0,0,0,0,0,0,0,0,N13,0,0,0)';
      PINUSE='GROUND';
      NO_LOAD_CHECK='Both';
      NO_IO_CHECK='Both';
      NO_ASSERT_CHECK='TRUE';
      NO_DIR_CHECK='TRUE';
      ALLOW_CONNECT='TRUE';
    'VSS'<359>:
      PIN_NUMBER='(0,0,0,0,0,0,0,0,0,0,N17,0,0,0)';
      PINUSE='GROUND';
      NO_LOAD_CHECK='Both';
      NO_IO_CHECK='Both';
      NO_ASSERT_CHECK='TRUE';
      NO_DIR_CHECK='TRUE';
      ALLOW_CONNECT='TRUE';
    'VSS'<358>:
      PIN_NUMBER='(0,0,0,0,0,0,0,0,0,0,N20,0,0,0)';
      PINUSE='GROUND';
      NO_LOAD_CHECK='Both';
      NO_IO_CHECK='Both';
      NO_ASSERT_CHECK='TRUE';
      NO_DIR_CHECK='TRUE';
      ALLOW_CONNECT='TRUE';
    'VSS'<357>:
      PIN_NUMBER='(0,0,0,0,0,0,0,0,0,0,N24,0,0,0)';
      PINUSE='GROUND';
      NO_LOAD_CHECK='Both';
      NO_IO_CHECK='Both';
      NO_ASSERT_CHECK='TRUE';
      NO_DIR_CHECK='TRUE';
      ALLOW_CONNECT='TRUE';
    'VSS'<356>:
      PIN_NUMBER='(0,0,0,0,0,0,0,0,0,0,N27,0,0,0)';
      PINUSE='GROUND';
      NO_LOAD_CHECK='Both';
      NO_IO_CHECK='Both';
      NO_ASSERT_CHECK='TRUE';
      NO_DIR_CHECK='TRUE';
      ALLOW_CONNECT='TRUE';
    'VSS'<355>:
      PIN_NUMBER='(0,0,0,0,0,0,0,0,0,0,N31,0,0,0)';
      PINUSE='GROUND';
      NO_LOAD_CHECK='Both';
      NO_IO_CHECK='Both';
      NO_ASSERT_CHECK='TRUE';
      NO_DIR_CHECK='TRUE';
      ALLOW_CONNECT='TRUE';
    'VSS'<354>:
      PIN_NUMBER='(0,0,0,0,0,0,0,0,0,0,0,N35,0,0)';
      PINUSE='GROUND';
      NO_LOAD_CHECK='Both';
      NO_IO_CHECK='Both';
      NO_ASSERT_CHECK='TRUE';
      NO_DIR_CHECK='TRUE';
      ALLOW_CONNECT='TRUE';
    'VSS'<353>:
      PIN_NUMBER='(0,0,0,0,0,0,0,0,0,0,0,N38,0,0)';
      PINUSE='GROUND';
      NO_LOAD_CHECK='Both';
      NO_IO_CHECK='Both';
      NO_ASSERT_CHECK='TRUE';
      NO_DIR_CHECK='TRUE';
      ALLOW_CONNECT='TRUE';
    'VSS'<352>:
      PIN_NUMBER='(0,0,0,0,0,0,0,0,0,0,0,N46,0,0)';
      PINUSE='GROUND';
      NO_LOAD_CHECK='Both';
      NO_IO_CHECK='Both';
      NO_ASSERT_CHECK='TRUE';
      NO_DIR_CHECK='TRUE';
      ALLOW_CONNECT='TRUE';
    'VSS'<351>:
      PIN_NUMBER='(0,0,0,0,0,0,0,0,0,0,0,N5,0,0)';
      PINUSE='GROUND';
      NO_LOAD_CHECK='Both';
      NO_IO_CHECK='Both';
      NO_ASSERT_CHECK='TRUE';
      NO_DIR_CHECK='TRUE';
      ALLOW_CONNECT='TRUE';
    'VSS'<350>:
      PIN_NUMBER='(0,0,0,0,0,0,0,0,0,0,0,R38,0,0)';
      PINUSE='GROUND';
      NO_LOAD_CHECK='Both';
      NO_IO_CHECK='Both';
      NO_ASSERT_CHECK='TRUE';
      NO_DIR_CHECK='TRUE';
      ALLOW_CONNECT='TRUE';
    'VSS'<349>:
      PIN_NUMBER='(0,0,0,0,0,0,0,0,0,0,0,N68,0,0)';
      PINUSE='GROUND';
      NO_LOAD_CHECK='Both';
      NO_IO_CHECK='Both';
      NO_ASSERT_CHECK='TRUE';
      NO_DIR_CHECK='TRUE';
      ALLOW_CONNECT='TRUE';
    'VSS'<348>:
      PIN_NUMBER='(0,0,0,0,0,0,0,0,0,0,0,N9,0,0)';
      PINUSE='GROUND';
      NO_LOAD_CHECK='Both';
      NO_IO_CHECK='Both';
      NO_ASSERT_CHECK='TRUE';
      NO_DIR_CHECK='TRUE';
      ALLOW_CONNECT='TRUE';
    'VSS'<347>:
      PIN_NUMBER='(0,0,0,0,0,0,0,0,0,0,0,AE43,0,0)';
      PINUSE='GROUND';
      NO_LOAD_CHECK='Both';
      NO_IO_CHECK='Both';
      NO_ASSERT_CHECK='TRUE';
      NO_DIR_CHECK='TRUE';
      ALLOW_CONNECT='TRUE';
    'VSS'<346>:
      PIN_NUMBER='(0,0,0,0,0,0,0,0,0,0,0,P63,0,0)';
      PINUSE='GROUND';
      NO_LOAD_CHECK='Both';
      NO_IO_CHECK='Both';
      NO_ASSERT_CHECK='TRUE';
      NO_DIR_CHECK='TRUE';
      ALLOW_CONNECT='TRUE';
    'VSS'<345>:
      PIN_NUMBER='(0,0,0,0,0,0,0,0,0,0,0,R27,0,0)';
      PINUSE='GROUND';
      NO_LOAD_CHECK='Both';
      NO_IO_CHECK='Both';
      NO_ASSERT_CHECK='TRUE';
      NO_DIR_CHECK='TRUE';
      ALLOW_CONNECT='TRUE';
    'VSS'<344>:
      PIN_NUMBER='(0,0,0,0,0,0,0,0,0,0,0,U42,0,0)';
      PINUSE='GROUND';
      NO_LOAD_CHECK='Both';
      NO_IO_CHECK='Both';
      NO_ASSERT_CHECK='TRUE';
      NO_DIR_CHECK='TRUE';
      ALLOW_CONNECT='TRUE';
    'VSS'<343>:
      PIN_NUMBER='(0,0,0,0,0,0,0,0,0,0,0,R5,0,0)';
      PINUSE='GROUND';
      NO_LOAD_CHECK='Both';
      NO_IO_CHECK='Both';
      NO_ASSERT_CHECK='TRUE';
      NO_DIR_CHECK='TRUE';
      ALLOW_CONNECT='TRUE';
    'VSS'<342>:
      PIN_NUMBER='(0,0,0,0,0,0,0,0,0,0,0,R50,0,0)';
      PINUSE='GROUND';
      NO_LOAD_CHECK='Both';
      NO_IO_CHECK='Both';
      NO_ASSERT_CHECK='TRUE';
      NO_DIR_CHECK='TRUE';
      ALLOW_CONNECT='TRUE';
    'VSS'<341>:
      PIN_NUMBER='(0,0,0,0,0,0,0,0,0,0,0,R54,0,0)';
      PINUSE='GROUND';
      NO_LOAD_CHECK='Both';
      NO_IO_CHECK='Both';
      NO_ASSERT_CHECK='TRUE';
      NO_DIR_CHECK='TRUE';
      ALLOW_CONNECT='TRUE';
    'VSS'<340>:
      PIN_NUMBER='(0,0,0,0,0,0,0,0,0,0,0,T56,0,0)';
      PINUSE='GROUND';
      NO_LOAD_CHECK='Both';
      NO_IO_CHECK='Both';
      NO_ASSERT_CHECK='TRUE';
      NO_DIR_CHECK='TRUE';
      ALLOW_CONNECT='TRUE';
    'VSS'<339>:
      PIN_NUMBER='(0,0,0,0,0,0,0,0,0,0,0,R58,0,0)';
      PINUSE='GROUND';
      NO_LOAD_CHECK='Both';
      NO_IO_CHECK='Both';
      NO_ASSERT_CHECK='TRUE';
      NO_DIR_CHECK='TRUE';
      ALLOW_CONNECT='TRUE';
    'VSS'<338>:
      PIN_NUMBER='(0,0,0,0,0,0,0,0,0,0,0,R68,0,0)';
      PINUSE='GROUND';
      NO_LOAD_CHECK='Both';
      NO_IO_CHECK='Both';
      NO_ASSERT_CHECK='TRUE';
      NO_DIR_CHECK='TRUE';
      ALLOW_CONNECT='TRUE';
    'VSS'<337>:
      PIN_NUMBER='(0,0,0,0,0,0,0,0,0,0,0,T11,0,0)';
      PINUSE='GROUND';
      NO_LOAD_CHECK='Both';
      NO_IO_CHECK='Both';
      NO_ASSERT_CHECK='TRUE';
      NO_DIR_CHECK='TRUE';
      ALLOW_CONNECT='TRUE';
    'VSS'<336>:
      PIN_NUMBER='(0,0,0,0,0,0,0,0,0,0,0,T15,0,0)';
      PINUSE='GROUND';
      NO_LOAD_CHECK='Both';
      NO_IO_CHECK='Both';
      NO_ASSERT_CHECK='TRUE';
      NO_DIR_CHECK='TRUE';
      ALLOW_CONNECT='TRUE';
    'VSS'<335>:
      PIN_NUMBER='(0,0,0,0,0,0,0,0,0,0,0,T18,0,0)';
      PINUSE='GROUND';
      NO_LOAD_CHECK='Both';
      NO_IO_CHECK='Both';
      NO_ASSERT_CHECK='TRUE';
      NO_DIR_CHECK='TRUE';
      ALLOW_CONNECT='TRUE';
    'VSS'<334>:
      PIN_NUMBER='(0,0,0,0,0,0,0,0,0,0,0,T22,0,0)';
      PINUSE='GROUND';
      NO_LOAD_CHECK='Both';
      NO_IO_CHECK='Both';
      NO_ASSERT_CHECK='TRUE';
      NO_DIR_CHECK='TRUE';
      ALLOW_CONNECT='TRUE';
    'VSS'<333>:
      PIN_NUMBER='(0,0,0,0,0,0,0,0,0,0,0,T26,0,0)';
      PINUSE='GROUND';
      NO_LOAD_CHECK='Both';
      NO_IO_CHECK='Both';
      NO_ASSERT_CHECK='TRUE';
      NO_DIR_CHECK='TRUE';
      ALLOW_CONNECT='TRUE';
    'VSS'<332>:
      PIN_NUMBER='(0,0,0,0,0,0,0,0,0,0,0,T29,0,0)';
      PINUSE='GROUND';
      NO_LOAD_CHECK='Both';
      NO_IO_CHECK='Both';
      NO_ASSERT_CHECK='TRUE';
      NO_DIR_CHECK='TRUE';
      ALLOW_CONNECT='TRUE';
    'VSS'<331>:
      PIN_NUMBER='(0,0,0,0,0,0,0,0,0,0,0,T33,0,0)';
      PINUSE='GROUND';
      NO_LOAD_CHECK='Both';
      NO_IO_CHECK='Both';
      NO_ASSERT_CHECK='TRUE';
      NO_DIR_CHECK='TRUE';
      ALLOW_CONNECT='TRUE';
    'VSS'<330>:
      PIN_NUMBER='(0,0,0,0,0,0,0,0,0,0,0,T37,0,0)';
      PINUSE='GROUND';
      NO_LOAD_CHECK='Both';
      NO_IO_CHECK='Both';
      NO_ASSERT_CHECK='TRUE';
      NO_DIR_CHECK='TRUE';
      ALLOW_CONNECT='TRUE';
    'VSS'<329>:
      PIN_NUMBER='(0,0,0,0,0,0,0,0,0,0,0,T40,0,0)';
      PINUSE='GROUND';
      NO_LOAD_CHECK='Both';
      NO_IO_CHECK='Both';
      NO_ASSERT_CHECK='TRUE';
      NO_DIR_CHECK='TRUE';
      ALLOW_CONNECT='TRUE';
    'VSS'<328>:
      PIN_NUMBER='(0,0,0,0,0,0,0,0,0,0,0,AJ45,0,0)';
      PINUSE='GROUND';
      NO_LOAD_CHECK='Both';
      NO_IO_CHECK='Both';
      NO_ASSERT_CHECK='TRUE';
      NO_DIR_CHECK='TRUE';
      ALLOW_CONNECT='TRUE';
    'VSS'<327>:
      PIN_NUMBER='(0,0,0,0,0,0,0,0,0,0,0,T48,0,0)';
      PINUSE='GROUND';
      NO_LOAD_CHECK='Both';
      NO_IO_CHECK='Both';
      NO_ASSERT_CHECK='TRUE';
      NO_DIR_CHECK='TRUE';
      ALLOW_CONNECT='TRUE';
    'VSS'<326>:
      PIN_NUMBER='(0,0,0,0,0,0,0,0,0,0,0,T52,0,0)';
      PINUSE='GROUND';
      NO_LOAD_CHECK='Both';
      NO_IO_CHECK='Both';
      NO_ASSERT_CHECK='TRUE';
      NO_DIR_CHECK='TRUE';
      ALLOW_CONNECT='TRUE';
    'VSS'<325>:
      PIN_NUMBER='(0,0,0,0,0,0,0,0,0,0,0,T66,0,0)';
      PINUSE='GROUND';
      NO_LOAD_CHECK='Both';
      NO_IO_CHECK='Both';
      NO_ASSERT_CHECK='TRUE';
      NO_DIR_CHECK='TRUE';
      ALLOW_CONNECT='TRUE';
    'VSS'<324>:
      PIN_NUMBER='(0,0,0,0,0,0,0,0,0,0,0,T7,0,0)';
      PINUSE='GROUND';
      NO_LOAD_CHECK='Both';
      NO_IO_CHECK='Both';
      NO_ASSERT_CHECK='TRUE';
      NO_DIR_CHECK='TRUE';
      ALLOW_CONNECT='TRUE';
    'VSS'<323>:
      PIN_NUMBER='(0,0,0,0,0,0,0,0,0,0,0,AF50,0,0)';
      PINUSE='GROUND';
      NO_LOAD_CHECK='Both';
      NO_IO_CHECK='Both';
      NO_ASSERT_CHECK='TRUE';
      NO_DIR_CHECK='TRUE';
      ALLOW_CONNECT='TRUE';
    'VSS'<322>:
      PIN_NUMBER='(0,0,0,0,0,0,0,0,0,0,0,AG46,0,0)';
      PINUSE='GROUND';
      NO_LOAD_CHECK='Both';
      NO_IO_CHECK='Both';
      NO_ASSERT_CHECK='TRUE';
      NO_DIR_CHECK='TRUE';
      ALLOW_CONNECT='TRUE';
    'VSS'<321>:
      PIN_NUMBER='(0,0,0,0,0,0,0,0,0,0,0,U58,0,0)';
      PINUSE='GROUND';
      NO_LOAD_CHECK='Both';
      NO_IO_CHECK='Both';
      NO_ASSERT_CHECK='TRUE';
      NO_DIR_CHECK='TRUE';
      ALLOW_CONNECT='TRUE';
    'VSS'<320>:
      PIN_NUMBER='(0,0,0,0,0,0,0,0,0,0,0,V26,0,0)';
      PINUSE='GROUND';
      NO_LOAD_CHECK='Both';
      NO_IO_CHECK='Both';
      NO_ASSERT_CHECK='TRUE';
      NO_DIR_CHECK='TRUE';
      ALLOW_CONNECT='TRUE';
    'VSS'<319>:
      PIN_NUMBER='(0,0,0,0,0,0,0,0,0,0,0,V48,0,0)';
      PINUSE='GROUND';
      NO_LOAD_CHECK='Both';
      NO_IO_CHECK='Both';
      NO_ASSERT_CHECK='TRUE';
      NO_DIR_CHECK='TRUE';
      ALLOW_CONNECT='TRUE';
    'VSS'<318>:
      PIN_NUMBER='(0,0,0,0,0,0,0,0,0,0,0,V5,0,0)';
      PINUSE='GROUND';
      NO_LOAD_CHECK='Both';
      NO_IO_CHECK='Both';
      NO_ASSERT_CHECK='TRUE';
      NO_DIR_CHECK='TRUE';
      ALLOW_CONNECT='TRUE';
    'VSS'<317>:
      PIN_NUMBER='(0,0,0,0,0,0,0,0,0,0,0,V52,0,0)';
      PINUSE='GROUND';
      NO_LOAD_CHECK='Both';
      NO_IO_CHECK='Both';
      NO_ASSERT_CHECK='TRUE';
      NO_DIR_CHECK='TRUE';
      ALLOW_CONNECT='TRUE';
    'VSS'<316>:
      PIN_NUMBER='(0,0,0,0,0,0,0,0,0,0,0,W58,0,0)';
      PINUSE='GROUND';
      NO_LOAD_CHECK='Both';
      NO_IO_CHECK='Both';
      NO_ASSERT_CHECK='TRUE';
      NO_DIR_CHECK='TRUE';
      ALLOW_CONNECT='TRUE';
    'VSS'<315>:
      PIN_NUMBER='(0,0,0,0,0,0,0,0,0,0,0,V66,0,0)';
      PINUSE='GROUND';
      NO_LOAD_CHECK='Both';
      NO_IO_CHECK='Both';
      NO_ASSERT_CHECK='TRUE';
      NO_DIR_CHECK='TRUE';
      ALLOW_CONNECT='TRUE';
    'VSS'<314>:
      PIN_NUMBER='(0,0,0,0,0,0,0,0,0,0,0,V68,0,0)';
      PINUSE='GROUND';
      NO_LOAD_CHECK='Both';
      NO_IO_CHECK='Both';
      NO_ASSERT_CHECK='TRUE';
      NO_DIR_CHECK='TRUE';
      ALLOW_CONNECT='TRUE';
    'VSS'<313>:
      PIN_NUMBER='(0,0,0,0,0,0,0,0,0,0,0,W13,0,0)';
      PINUSE='GROUND';
      NO_LOAD_CHECK='Both';
      NO_IO_CHECK='Both';
      NO_ASSERT_CHECK='TRUE';
      NO_DIR_CHECK='TRUE';
      ALLOW_CONNECT='TRUE';
    'VSS'<312>:
      PIN_NUMBER='(0,0,0,0,0,0,0,0,0,0,0,W17,0,0)';
      PINUSE='GROUND';
      NO_LOAD_CHECK='Both';
      NO_IO_CHECK='Both';
      NO_ASSERT_CHECK='TRUE';
      NO_DIR_CHECK='TRUE';
      ALLOW_CONNECT='TRUE';
    'VSS'<311>:
      PIN_NUMBER='(0,0,0,0,0,0,0,0,0,0,0,W20,0,0)';
      PINUSE='GROUND';
      NO_LOAD_CHECK='Both';
      NO_IO_CHECK='Both';
      NO_ASSERT_CHECK='TRUE';
      NO_DIR_CHECK='TRUE';
      ALLOW_CONNECT='TRUE';
    'VSS'<310>:
      PIN_NUMBER='(0,0,0,0,0,0,0,0,0,0,0,W24,0,0)';
      PINUSE='GROUND';
      NO_LOAD_CHECK='Both';
      NO_IO_CHECK='Both';
      NO_ASSERT_CHECK='TRUE';
      NO_DIR_CHECK='TRUE';
      ALLOW_CONNECT='TRUE';
    'VSS'<309>:
      PIN_NUMBER='(0,0,0,0,0,0,0,0,0,0,0,AA50,0,0)';
      PINUSE='GROUND';
      NO_LOAD_CHECK='Both';
      NO_IO_CHECK='Both';
      NO_ASSERT_CHECK='TRUE';
      NO_DIR_CHECK='TRUE';
      ALLOW_CONNECT='TRUE';
    'VSS'<308>:
      PIN_NUMBER='(0,0,0,0,0,0,0,0,0,0,0,Y43,0,0)';
      PINUSE='GROUND';
      NO_LOAD_CHECK='Both';
      NO_IO_CHECK='Both';
      NO_ASSERT_CHECK='TRUE';
      NO_DIR_CHECK='TRUE';
      ALLOW_CONNECT='TRUE';
    'VSS'<307>:
      PIN_NUMBER='(0,0,0,0,0,0,0,0,0,0,0,W61,0,0)';
      PINUSE='GROUND';
      NO_LOAD_CHECK='Both';
      NO_IO_CHECK='Both';
      NO_ASSERT_CHECK='TRUE';
      NO_DIR_CHECK='TRUE';
      ALLOW_CONNECT='TRUE';
    'VSS'<306>:
      PIN_NUMBER='(0,0,0,0,0,0,0,0,0,0,0,W9,0,0)';
      PINUSE='GROUND';
      NO_LOAD_CHECK='Both';
      NO_IO_CHECK='Both';
      NO_ASSERT_CHECK='TRUE';
      NO_DIR_CHECK='TRUE';
      ALLOW_CONNECT='TRUE';
    'VSS'<305>:
      PIN_NUMBER='(0,0,0,0,0,0,0,0,0,0,0,Y22,0,0)';
      PINUSE='GROUND';
      NO_LOAD_CHECK='Both';
      NO_IO_CHECK='Both';
      NO_ASSERT_CHECK='TRUE';
      NO_DIR_CHECK='TRUE';
      ALLOW_CONNECT='TRUE';
    'VSS'<304>:
      PIN_NUMBER='(0,0,0,0,0,0,0,0,0,0,0,Y27,0,0)';
      PINUSE='GROUND';
      NO_LOAD_CHECK='Both';
      NO_IO_CHECK='Both';
      NO_ASSERT_CHECK='TRUE';
      NO_DIR_CHECK='TRUE';
      ALLOW_CONNECT='TRUE';
    'VSS'<303>:
      PIN_NUMBER='(0,0,0,0,0,0,0,0,0,0,0,Y48,0,0)';
      PINUSE='GROUND';
      NO_LOAD_CHECK='Both';
      NO_IO_CHECK='Both';
      NO_ASSERT_CHECK='TRUE';
      NO_DIR_CHECK='TRUE';
      ALLOW_CONNECT='TRUE';
    'VSS'<302>:
      PIN_NUMBER='(0,0,0,0,0,0,0,0,0,0,0,Y5,0,0)';
      PINUSE='GROUND';
      NO_LOAD_CHECK='Both';
      NO_IO_CHECK='Both';
      NO_ASSERT_CHECK='TRUE';
      NO_DIR_CHECK='TRUE';
      ALLOW_CONNECT='TRUE';
    'VSS'<301>:
      PIN_NUMBER='(0,0,0,0,0,0,0,0,0,0,0,Y52,0,0)';
      PINUSE='GROUND';
      NO_LOAD_CHECK='Both';
      NO_IO_CHECK='Both';
      NO_ASSERT_CHECK='TRUE';
      NO_DIR_CHECK='TRUE';
      ALLOW_CONNECT='TRUE';
    'VSS'<300>:
      PIN_NUMBER='(0,0,0,0,0,0,0,0,0,0,0,Y59,0,0)';
      PINUSE='GROUND';
      NO_LOAD_CHECK='Both';
      NO_IO_CHECK='Both';
      NO_ASSERT_CHECK='TRUE';
      NO_DIR_CHECK='TRUE';
      ALLOW_CONNECT='TRUE';
    'VSS'<299>:
      PIN_NUMBER='(0,0,0,0,0,0,0,0,0,0,0,Y63,0,0)';
      PINUSE='GROUND';
      NO_LOAD_CHECK='Both';
      NO_IO_CHECK='Both';
      NO_ASSERT_CHECK='TRUE';
      NO_DIR_CHECK='TRUE';
      ALLOW_CONNECT='TRUE';
    'VSS'<298>:
      PIN_NUMBER='(0,0,0,0,0,0,0,0,0,0,0,Y68,0,0)';
      PINUSE='GROUND';
      NO_LOAD_CHECK='Both';
      NO_IO_CHECK='Both';
      NO_ASSERT_CHECK='TRUE';
      NO_DIR_CHECK='TRUE';
      ALLOW_CONNECT='TRUE';
    'VSS'<297>:
      PIN_NUMBER='(0,0,0,0,0,0,0,0,0,0,0,AA26,0,0)';
      PINUSE='GROUND';
      NO_LOAD_CHECK='Both';
      NO_IO_CHECK='Both';
      NO_ASSERT_CHECK='TRUE';
      NO_DIR_CHECK='TRUE';
      ALLOW_CONNECT='TRUE';
    'VSS'<296>:
      PIN_NUMBER='(0,0,0,0,0,0,0,0,0,0,0,AA27,0,0)';
      PINUSE='GROUND';
      NO_LOAD_CHECK='Both';
      NO_IO_CHECK='Both';
      NO_ASSERT_CHECK='TRUE';
      NO_DIR_CHECK='TRUE';
      ALLOW_CONNECT='TRUE';
    'VSS'<295>:
      PIN_NUMBER='(0,0,0,0,0,0,0,0,0,0,0,AA43,0,0)';
      PINUSE='GROUND';
      NO_LOAD_CHECK='Both';
      NO_IO_CHECK='Both';
      NO_ASSERT_CHECK='TRUE';
      NO_DIR_CHECK='TRUE';
      ALLOW_CONNECT='TRUE';
    'VSS'<294>:
      PIN_NUMBER='(0,0,0,0,0,0,0,0,0,0,0,AA48,0,0)';
      PINUSE='GROUND';
      NO_LOAD_CHECK='Both';
      NO_IO_CHECK='Both';
      NO_ASSERT_CHECK='TRUE';
      NO_DIR_CHECK='TRUE';
      ALLOW_CONNECT='TRUE';
    'VSS'<293>:
      PIN_NUMBER='(0,0,0,0,0,0,0,0,0,0,0,AB5,0,0)';
      PINUSE='GROUND';
      NO_LOAD_CHECK='Both';
      NO_IO_CHECK='Both';
      NO_ASSERT_CHECK='TRUE';
      NO_DIR_CHECK='TRUE';
      ALLOW_CONNECT='TRUE';
    'VSS'<292>:
      PIN_NUMBER='(0,0,0,0,0,0,0,0,0,0,0,AB68,0,0)';
      PINUSE='GROUND';
      NO_LOAD_CHECK='Both';
      NO_IO_CHECK='Both';
      NO_ASSERT_CHECK='TRUE';
      NO_DIR_CHECK='TRUE';
      ALLOW_CONNECT='TRUE';
    'VSS'<291>:
      PIN_NUMBER='(0,0,0,0,0,0,0,0,0,0,0,AB70,0,0)';
      PINUSE='GROUND';
      NO_LOAD_CHECK='Both';
      NO_IO_CHECK='Both';
      NO_ASSERT_CHECK='TRUE';
      NO_DIR_CHECK='TRUE';
      ALLOW_CONNECT='TRUE';
    'VSS'<290>:
      PIN_NUMBER='(0,0,0,0,0,0,0,0,0,0,0,AB72,0,0)';
      PINUSE='GROUND';
      NO_LOAD_CHECK='Both';
      NO_IO_CHECK='Both';
      NO_ASSERT_CHECK='TRUE';
      NO_DIR_CHECK='TRUE';
      ALLOW_CONNECT='TRUE';
    'VSS'<289>:
      PIN_NUMBER='(0,0,0,0,0,0,0,0,0,0,0,AC11,0,0)';
      PINUSE='GROUND';
      NO_LOAD_CHECK='Both';
      NO_IO_CHECK='Both';
      NO_ASSERT_CHECK='TRUE';
      NO_DIR_CHECK='TRUE';
      ALLOW_CONNECT='TRUE';
    'VSS'<288>:
      PIN_NUMBER='(0,0,0,0,0,0,0,0,0,0,0,AC15,0,0)';
      PINUSE='GROUND';
      NO_LOAD_CHECK='Both';
      NO_IO_CHECK='Both';
      NO_ASSERT_CHECK='TRUE';
      NO_DIR_CHECK='TRUE';
      ALLOW_CONNECT='TRUE';
    'VSS'<287>:
      PIN_NUMBER='(0,0,0,0,0,0,0,0,0,0,0,AC18,0,0)';
      PINUSE='GROUND';
      NO_LOAD_CHECK='Both';
      NO_IO_CHECK='Both';
      NO_ASSERT_CHECK='TRUE';
      NO_DIR_CHECK='TRUE';
      ALLOW_CONNECT='TRUE';
    'VSS'<286>:
      PIN_NUMBER='(0,0,0,0,0,0,0,0,0,0,0,AC22,0,0)';
      PINUSE='GROUND';
      NO_LOAD_CHECK='Both';
      NO_IO_CHECK='Both';
      NO_ASSERT_CHECK='TRUE';
      NO_DIR_CHECK='TRUE';
      ALLOW_CONNECT='TRUE';
    'VSS'<285>:
      PIN_NUMBER='(0,0,0,0,0,0,0,0,0,0,0,AC45,0,0)';
      PINUSE='GROUND';
      NO_LOAD_CHECK='Both';
      NO_IO_CHECK='Both';
      NO_ASSERT_CHECK='TRUE';
      NO_DIR_CHECK='TRUE';
      ALLOW_CONNECT='TRUE';
    'VSS'<284>:
      PIN_NUMBER='(0,0,0,0,0,0,0,0,0,0,0,AD58,0,0)';
      PINUSE='GROUND';
      NO_LOAD_CHECK='Both';
      NO_IO_CHECK='Both';
      NO_ASSERT_CHECK='TRUE';
      NO_DIR_CHECK='TRUE';
      ALLOW_CONNECT='TRUE';
    'VSS'<283>:
      PIN_NUMBER='(0,0,0,0,0,0,0,0,0,0,0,AC27,0,0)';
      PINUSE='GROUND';
      NO_LOAD_CHECK='Both';
      NO_IO_CHECK='Both';
      NO_ASSERT_CHECK='TRUE';
      NO_DIR_CHECK='TRUE';
      ALLOW_CONNECT='TRUE';
    'VSS'<282>:
      PIN_NUMBER='(0,0,0,0,0,0,0,0,0,0,0,AC43,0,0)';
      PINUSE='GROUND';
      NO_LOAD_CHECK='Both';
      NO_IO_CHECK='Both';
      NO_ASSERT_CHECK='TRUE';
      NO_DIR_CHECK='TRUE';
      ALLOW_CONNECT='TRUE';
    'VSS'<281>:
      PIN_NUMBER='(0,0,0,0,0,0,0,0,0,0,0,AC46,0,0)';
      PINUSE='GROUND';
      NO_LOAD_CHECK='Both';
      NO_IO_CHECK='Both';
      NO_ASSERT_CHECK='TRUE';
      NO_DIR_CHECK='TRUE';
      ALLOW_CONNECT='TRUE';
    'VSS'<280>:
      PIN_NUMBER='(0,0,0,0,0,0,0,0,0,0,0,AC48,0,0)';
      PINUSE='GROUND';
      NO_LOAD_CHECK='Both';
      NO_IO_CHECK='Both';
      NO_ASSERT_CHECK='TRUE';
      NO_DIR_CHECK='TRUE';
      ALLOW_CONNECT='TRUE';
    'VSS'<279>:
      PIN_NUMBER='(0,0,0,0,0,0,0,0,0,0,0,AC52,0,0)';
      PINUSE='GROUND';
      NO_LOAD_CHECK='Both';
      NO_IO_CHECK='Both';
      NO_ASSERT_CHECK='TRUE';
      NO_DIR_CHECK='TRUE';
      ALLOW_CONNECT='TRUE';
    'VSS'<278>:
      PIN_NUMBER='(0,0,0,0,0,0,0,0,0,0,0,AC59,0,0)';
      PINUSE='GROUND';
      NO_LOAD_CHECK='Both';
      NO_IO_CHECK='Both';
      NO_ASSERT_CHECK='TRUE';
      NO_DIR_CHECK='TRUE';
      ALLOW_CONNECT='TRUE';
    'VSS'<277>:
      PIN_NUMBER='(0,0,0,0,0,0,0,0,0,0,0,AC63,0,0)';
      PINUSE='GROUND';
      NO_LOAD_CHECK='Both';
      NO_IO_CHECK='Both';
      NO_ASSERT_CHECK='TRUE';
      NO_DIR_CHECK='TRUE';
      ALLOW_CONNECT='TRUE';
    'VSS'<276>:
      PIN_NUMBER='(0,0,0,0,0,0,0,0,0,0,0,AC66,0,0)';
      PINUSE='GROUND';
      NO_LOAD_CHECK='Both';
      NO_IO_CHECK='Both';
      NO_ASSERT_CHECK='TRUE';
      NO_DIR_CHECK='TRUE';
      ALLOW_CONNECT='TRUE';
    'VSS'<275>:
      PIN_NUMBER='(0,0,0,0,0,0,0,0,0,0,0,AC7,0,0)';
      PINUSE='GROUND';
      NO_LOAD_CHECK='Both';
      NO_IO_CHECK='Both';
      NO_ASSERT_CHECK='TRUE';
      NO_DIR_CHECK='TRUE';
      ALLOW_CONNECT='TRUE';
    'VSS'<274>:
      PIN_NUMBER='(0,0,0,0,0,0,0,0,0,0,0,AD5,0,0)';
      PINUSE='GROUND';
      NO_LOAD_CHECK='Both';
      NO_IO_CHECK='Both';
      NO_ASSERT_CHECK='TRUE';
      NO_DIR_CHECK='TRUE';
      ALLOW_CONNECT='TRUE';
    'VSS'<273>:
      PIN_NUMBER='(0,0,0,0,0,0,0,0,0,0,0,AD65,0,0)';
      PINUSE='GROUND';
      NO_LOAD_CHECK='Both';
      NO_IO_CHECK='Both';
      NO_ASSERT_CHECK='TRUE';
      NO_DIR_CHECK='TRUE';
      ALLOW_CONNECT='TRUE';
    'VSS'<272>:
      PIN_NUMBER='(0,0,0,0,0,0,0,0,0,0,0,AD68,0,0)';
      PINUSE='GROUND';
      NO_LOAD_CHECK='Both';
      NO_IO_CHECK='Both';
      NO_ASSERT_CHECK='TRUE';
      NO_DIR_CHECK='TRUE';
      ALLOW_CONNECT='TRUE';
    'VSS'<271>:
      PIN_NUMBER='(0,0,0,0,0,0,0,0,0,0,0,AE29,0,0)';
      PINUSE='GROUND';
      NO_LOAD_CHECK='Both';
      NO_IO_CHECK='Both';
      NO_ASSERT_CHECK='TRUE';
      NO_DIR_CHECK='TRUE';
      ALLOW_CONNECT='TRUE';
    'VSS'<270>:
      PIN_NUMBER='(0,0,0,0,0,0,0,0,0,0,0,J18,0,0)';
      PINUSE='GROUND';
      NO_LOAD_CHECK='Both';
      NO_IO_CHECK='Both';
      NO_ASSERT_CHECK='TRUE';
      NO_DIR_CHECK='TRUE';
      ALLOW_CONNECT='TRUE';
    'VSS'<269>:
      PIN_NUMBER='(0,0,0,0,0,0,0,0,0,0,0,AE48,0,0)';
      PINUSE='GROUND';
      NO_LOAD_CHECK='Both';
      NO_IO_CHECK='Both';
      NO_ASSERT_CHECK='TRUE';
      NO_DIR_CHECK='TRUE';
      ALLOW_CONNECT='TRUE';
    'VSS'<268>:
      PIN_NUMBER='(0,0,0,0,0,0,0,0,0,0,0,AE52,0,0)';
      PINUSE='GROUND';
      NO_LOAD_CHECK='Both';
      NO_IO_CHECK='Both';
      NO_ASSERT_CHECK='TRUE';
      NO_DIR_CHECK='TRUE';
      ALLOW_CONNECT='TRUE';
    'VSS'<267>:
      PIN_NUMBER='(0,0,0,0,0,0,0,0,0,0,0,AE56,0,0)';
      PINUSE='GROUND';
      NO_LOAD_CHECK='Both';
      NO_IO_CHECK='Both';
      NO_ASSERT_CHECK='TRUE';
      NO_DIR_CHECK='TRUE';
      ALLOW_CONNECT='TRUE';
    'VSS'<266>:
      PIN_NUMBER='(0,0,0,0,0,0,0,0,0,0,0,AE59,0,0)';
      PINUSE='GROUND';
      NO_LOAD_CHECK='Both';
      NO_IO_CHECK='Both';
      NO_ASSERT_CHECK='TRUE';
      NO_DIR_CHECK='TRUE';
      ALLOW_CONNECT='TRUE';
    'VSS'<265>:
      PIN_NUMBER='(0,0,0,0,0,0,0,0,0,0,0,AE63,0,0)';
      PINUSE='GROUND';
      NO_LOAD_CHECK='Both';
      NO_IO_CHECK='Both';
      NO_ASSERT_CHECK='TRUE';
      NO_DIR_CHECK='TRUE';
      ALLOW_CONNECT='TRUE';
    'VSS'<264>:
      PIN_NUMBER='(0,0,0,0,0,0,0,0,0,0,0,AE66,0,0)';
      PINUSE='GROUND';
      NO_LOAD_CHECK='Both';
      NO_IO_CHECK='Both';
      NO_ASSERT_CHECK='TRUE';
      NO_DIR_CHECK='TRUE';
      ALLOW_CONNECT='TRUE';
    'VSS'<263>:
      PIN_NUMBER='(0,0,0,0,0,0,0,0,0,0,0,AF1,0,0)';
      PINUSE='GROUND';
      NO_LOAD_CHECK='Both';
      NO_IO_CHECK='Both';
      NO_ASSERT_CHECK='TRUE';
      NO_DIR_CHECK='TRUE';
      ALLOW_CONNECT='TRUE';
    'VSS'<262>:
      PIN_NUMBER='(0,0,0,0,0,0,0,0,0,0,0,AF13,0,0)';
      PINUSE='GROUND';
      NO_LOAD_CHECK='Both';
      NO_IO_CHECK='Both';
      NO_ASSERT_CHECK='TRUE';
      NO_DIR_CHECK='TRUE';
      ALLOW_CONNECT='TRUE';
    'VSS'<261>:
      PIN_NUMBER='(0,0,0,0,0,0,0,0,0,0,0,AF5,0,0)';
      PINUSE='GROUND';
      NO_LOAD_CHECK='Both';
      NO_IO_CHECK='Both';
      NO_ASSERT_CHECK='TRUE';
      NO_DIR_CHECK='TRUE';
      ALLOW_CONNECT='TRUE';
    'VSS'<260>:
      PIN_NUMBER='(0,0,0,0,0,0,0,0,0,0,0,AF9,0,0)';
      PINUSE='GROUND';
      NO_LOAD_CHECK='Both';
      NO_IO_CHECK='Both';
      NO_ASSERT_CHECK='TRUE';
      NO_DIR_CHECK='TRUE';
      ALLOW_CONNECT='TRUE';
    'VSS'<259>:
      PIN_NUMBER='(0,0,0,0,0,0,0,0,0,0,0,AF17,0,0)';
      PINUSE='GROUND';
      NO_LOAD_CHECK='Both';
      NO_IO_CHECK='Both';
      NO_ASSERT_CHECK='TRUE';
      NO_DIR_CHECK='TRUE';
      ALLOW_CONNECT='TRUE';
    'VSS'<258>:
      PIN_NUMBER='(0,0,0,0,0,0,0,0,0,0,0,AF24,0,0)';
      PINUSE='GROUND';
      NO_LOAD_CHECK='Both';
      NO_IO_CHECK='Both';
      NO_ASSERT_CHECK='TRUE';
      NO_DIR_CHECK='TRUE';
      ALLOW_CONNECT='TRUE';
    'VSS'<257>:
      PIN_NUMBER='(0,0,0,0,0,0,0,0,0,0,0,AF3,0,0)';
      PINUSE='GROUND';
      NO_LOAD_CHECK='Both';
      NO_IO_CHECK='Both';
      NO_ASSERT_CHECK='TRUE';
      NO_DIR_CHECK='TRUE';
      ALLOW_CONNECT='TRUE';
    'VSS'<256>:
      PIN_NUMBER='(0,0,0,0,0,0,0,0,0,0,0,AF68,0,0)';
      PINUSE='GROUND';
      NO_LOAD_CHECK='Both';
      NO_IO_CHECK='Both';
      NO_ASSERT_CHECK='TRUE';
      NO_DIR_CHECK='TRUE';
      ALLOW_CONNECT='TRUE';
    'VSS'<255>:
      PIN_NUMBER='(0,0,0,0,0,0,0,0,0,0,0,AG26,0,0)';
      PINUSE='GROUND';
      NO_LOAD_CHECK='Both';
      NO_IO_CHECK='Both';
      NO_ASSERT_CHECK='TRUE';
      NO_DIR_CHECK='TRUE';
      ALLOW_CONNECT='TRUE';
    'VSS'<254>:
      PIN_NUMBER='(0,0,0,0,0,0,0,0,0,0,0,AG30,0,0)';
      PINUSE='GROUND';
      NO_LOAD_CHECK='Both';
      NO_IO_CHECK='Both';
      NO_ASSERT_CHECK='TRUE';
      NO_DIR_CHECK='TRUE';
      ALLOW_CONNECT='TRUE';
    'VSS'<253>:
      PIN_NUMBER='(0,0,0,0,0,0,0,0,0,0,0,AG41,0,0)';
      PINUSE='GROUND';
      NO_LOAD_CHECK='Both';
      NO_IO_CHECK='Both';
      NO_ASSERT_CHECK='TRUE';
      NO_DIR_CHECK='TRUE';
      ALLOW_CONNECT='TRUE';
    'VSS'<252>:
      PIN_NUMBER='(0,0,0,0,0,0,0,0,0,0,0,AG43,0,0)';
      PINUSE='GROUND';
      NO_LOAD_CHECK='Both';
      NO_IO_CHECK='Both';
      NO_ASSERT_CHECK='TRUE';
      NO_DIR_CHECK='TRUE';
      ALLOW_CONNECT='TRUE';
    'VSS'<251>:
      PIN_NUMBER='(0,0,0,0,0,0,0,0,0,0,0,AG52,0,0)';
      PINUSE='GROUND';
      NO_LOAD_CHECK='Both';
      NO_IO_CHECK='Both';
      NO_ASSERT_CHECK='TRUE';
      NO_DIR_CHECK='TRUE';
      ALLOW_CONNECT='TRUE';
    'VSS'<250>:
      PIN_NUMBER='(0,0,0,0,0,0,0,0,0,0,0,AG56,0,0)';
      PINUSE='GROUND';
      NO_LOAD_CHECK='Both';
      NO_IO_CHECK='Both';
      NO_ASSERT_CHECK='TRUE';
      NO_DIR_CHECK='TRUE';
      ALLOW_CONNECT='TRUE';
    'VSS'<249>:
      PIN_NUMBER='(0,0,0,0,0,0,0,0,0,0,0,AG59,0,0)';
      PINUSE='GROUND';
      NO_LOAD_CHECK='Both';
      NO_IO_CHECK='Both';
      NO_ASSERT_CHECK='TRUE';
      NO_DIR_CHECK='TRUE';
      ALLOW_CONNECT='TRUE';
    'VSS'<248>:
      PIN_NUMBER='(0,0,0,0,0,0,0,0,0,0,0,AG66,0,0)';
      PINUSE='GROUND';
      NO_LOAD_CHECK='Both';
      NO_IO_CHECK='Both';
      NO_ASSERT_CHECK='TRUE';
      NO_DIR_CHECK='TRUE';
      ALLOW_CONNECT='TRUE';
    'VSS'<247>:
      PIN_NUMBER='(0,0,0,0,0,0,0,0,0,0,0,AH20,0,0)';
      PINUSE='GROUND';
      NO_LOAD_CHECK='Both';
      NO_IO_CHECK='Both';
      NO_ASSERT_CHECK='TRUE';
      NO_DIR_CHECK='TRUE';
      ALLOW_CONNECT='TRUE';
    'VSS'<246>:
      PIN_NUMBER='(0,0,0,0,0,0,0,0,0,0,0,AJ11,0,0)';
      PINUSE='GROUND';
      NO_LOAD_CHECK='Both';
      NO_IO_CHECK='Both';
      NO_ASSERT_CHECK='TRUE';
      NO_DIR_CHECK='TRUE';
      ALLOW_CONNECT='TRUE';
    'VSS'<245>:
      PIN_NUMBER='(0,0,0,0,0,0,0,0,0,0,0,AJ32,0,0)';
      PINUSE='GROUND';
      NO_LOAD_CHECK='Both';
      NO_IO_CHECK='Both';
      NO_ASSERT_CHECK='TRUE';
      NO_DIR_CHECK='TRUE';
      ALLOW_CONNECT='TRUE';
    'VSS'<244>:
      PIN_NUMBER='(0,0,0,0,0,0,0,0,0,0,0,AJ56,0,0)';
      PINUSE='GROUND';
      NO_LOAD_CHECK='Both';
      NO_IO_CHECK='Both';
      NO_ASSERT_CHECK='TRUE';
      NO_DIR_CHECK='TRUE';
      ALLOW_CONNECT='TRUE';
    'VSS'<243>:
      PIN_NUMBER='(0,0,0,0,0,0,0,0,0,0,0,AK30,0,0)';
      PINUSE='GROUND';
      NO_LOAD_CHECK='Both';
      NO_IO_CHECK='Both';
      NO_ASSERT_CHECK='TRUE';
      NO_DIR_CHECK='TRUE';
      ALLOW_CONNECT='TRUE';
    'VSS'<242>:
      PIN_NUMBER='(0,0,0,0,0,0,0,0,0,0,0,AJ15,0,0)';
      PINUSE='GROUND';
      NO_LOAD_CHECK='Both';
      NO_IO_CHECK='Both';
      NO_ASSERT_CHECK='TRUE';
      NO_DIR_CHECK='TRUE';
      ALLOW_CONNECT='TRUE';
    'VSS'<241>:
      PIN_NUMBER='(0,0,0,0,0,0,0,0,0,0,0,AJ18,0,0)';
      PINUSE='GROUND';
      NO_LOAD_CHECK='Both';
      NO_IO_CHECK='Both';
      NO_ASSERT_CHECK='TRUE';
      NO_DIR_CHECK='TRUE';
      ALLOW_CONNECT='TRUE';
    'VSS'<240>:
      PIN_NUMBER='(0,0,0,0,0,0,0,0,0,0,0,AJ22,0,0)';
      PINUSE='GROUND';
      NO_LOAD_CHECK='Both';
      NO_IO_CHECK='Both';
      NO_ASSERT_CHECK='TRUE';
      NO_DIR_CHECK='TRUE';
      ALLOW_CONNECT='TRUE';
    'VSS'<239>:
      PIN_NUMBER='(0,0,0,0,0,0,0,0,0,0,0,AJ26,0,0)';
      PINUSE='GROUND';
      NO_LOAD_CHECK='Both';
      NO_IO_CHECK='Both';
      NO_ASSERT_CHECK='TRUE';
      NO_DIR_CHECK='TRUE';
      ALLOW_CONNECT='TRUE';
    'VSS'<238>:
      PIN_NUMBER='(0,0,0,0,0,0,0,0,0,0,0,AJ30,0,0)';
      PINUSE='GROUND';
      NO_LOAD_CHECK='Both';
      NO_IO_CHECK='Both';
      NO_ASSERT_CHECK='TRUE';
      NO_DIR_CHECK='TRUE';
      ALLOW_CONNECT='TRUE';
    'VSS'<237>:
      PIN_NUMBER='(0,0,0,0,0,0,0,0,0,0,0,AJ34,0,0)';
      PINUSE='GROUND';
      NO_LOAD_CHECK='Both';
      NO_IO_CHECK='Both';
      NO_ASSERT_CHECK='TRUE';
      NO_DIR_CHECK='TRUE';
      ALLOW_CONNECT='TRUE';
    'VSS'<236>:
      PIN_NUMBER='(0,0,0,0,0,0,0,0,0,0,0,AJ36,0,0)';
      PINUSE='GROUND';
      NO_LOAD_CHECK='Both';
      NO_IO_CHECK='Both';
      NO_ASSERT_CHECK='TRUE';
      NO_DIR_CHECK='TRUE';
      ALLOW_CONNECT='TRUE';
    'VSS'<235>:
      PIN_NUMBER='(0,0,0,0,0,0,0,0,0,0,0,AJ37,0,0)';
      PINUSE='GROUND';
      NO_LOAD_CHECK='Both';
      NO_IO_CHECK='Both';
      NO_ASSERT_CHECK='TRUE';
      NO_DIR_CHECK='TRUE';
      ALLOW_CONNECT='TRUE';
    'VSS'<234>:
      PIN_NUMBER='(0,0,0,0,0,0,0,0,0,0,0,AJ39,0,0)';
      PINUSE='GROUND';
      NO_LOAD_CHECK='Both';
      NO_IO_CHECK='Both';
      NO_ASSERT_CHECK='TRUE';
      NO_DIR_CHECK='TRUE';
      ALLOW_CONNECT='TRUE';
    'VSS'<233>:
      PIN_NUMBER='(0,0,0,0,0,0,0,0,0,0,0,AJ41,0,0)';
      PINUSE='GROUND';
      NO_LOAD_CHECK='Both';
      NO_IO_CHECK='Both';
      NO_ASSERT_CHECK='TRUE';
      NO_DIR_CHECK='TRUE';
      ALLOW_CONNECT='TRUE';
    'VSS'<232>:
      PIN_NUMBER='(0,0,0,0,0,0,0,0,0,0,0,AJ5,0,0)';
      PINUSE='GROUND';
      NO_LOAD_CHECK='Both';
      NO_IO_CHECK='Both';
      NO_ASSERT_CHECK='TRUE';
      NO_DIR_CHECK='TRUE';
      ALLOW_CONNECT='TRUE';
    'VSS'<231>:
      PIN_NUMBER='(0,0,0,0,0,0,0,0,0,0,0,AJ52,0,0)';
      PINUSE='GROUND';
      NO_LOAD_CHECK='Both';
      NO_IO_CHECK='Both';
      NO_ASSERT_CHECK='TRUE';
      NO_DIR_CHECK='TRUE';
      ALLOW_CONNECT='TRUE';
    'VSS'<230>:
      PIN_NUMBER='(0,0,0,0,0,0,0,0,0,0,0,AJ59,0,0)';
      PINUSE='GROUND';
      NO_LOAD_CHECK='Both';
      NO_IO_CHECK='Both';
      NO_ASSERT_CHECK='TRUE';
      NO_DIR_CHECK='TRUE';
      ALLOW_CONNECT='TRUE';
    'VSS'<229>:
      PIN_NUMBER='(0,0,0,0,0,0,0,0,0,0,0,AJ66,0,0)';
      PINUSE='GROUND';
      NO_LOAD_CHECK='Both';
      NO_IO_CHECK='Both';
      NO_ASSERT_CHECK='TRUE';
      NO_DIR_CHECK='TRUE';
      ALLOW_CONNECT='TRUE';
    'VSS'<228>:
      PIN_NUMBER='(0,0,0,0,0,0,0,0,0,0,0,AJ68,0,0)';
      PINUSE='GROUND';
      NO_LOAD_CHECK='Both';
      NO_IO_CHECK='Both';
      NO_ASSERT_CHECK='TRUE';
      NO_DIR_CHECK='TRUE';
      ALLOW_CONNECT='TRUE';
    'VSS'<227>:
      PIN_NUMBER='(0,0,0,0,0,0,0,0,0,0,0,AJ7,0,0)';
      PINUSE='GROUND';
      NO_LOAD_CHECK='Both';
      NO_IO_CHECK='Both';
      NO_ASSERT_CHECK='TRUE';
      NO_DIR_CHECK='TRUE';
      ALLOW_CONNECT='TRUE';
    'VSS'<226>:
      PIN_NUMBER='(0,0,0,0,0,0,0,0,0,0,0,AK26,0,0)';
      PINUSE='GROUND';
      NO_LOAD_CHECK='Both';
      NO_IO_CHECK='Both';
      NO_ASSERT_CHECK='TRUE';
      NO_DIR_CHECK='TRUE';
      ALLOW_CONNECT='TRUE';
    'VSS'<225>:
      PIN_NUMBER='(0,0,0,0,0,0,0,0,0,0,0,AK41,0,0)';
      PINUSE='GROUND';
      NO_LOAD_CHECK='Both';
      NO_IO_CHECK='Both';
      NO_ASSERT_CHECK='TRUE';
      NO_DIR_CHECK='TRUE';
      ALLOW_CONNECT='TRUE';
    'VSS'<224>:
      PIN_NUMBER='(0,0,0,0,0,0,0,0,0,0,0,AK46,0,0)';
      PINUSE='GROUND';
      NO_LOAD_CHECK='Both';
      NO_IO_CHECK='Both';
      NO_ASSERT_CHECK='TRUE';
      NO_DIR_CHECK='TRUE';
      ALLOW_CONNECT='TRUE';
    'VSS'<223>:
      PIN_NUMBER='(0,0,0,0,0,0,0,0,0,0,0,AK48,0,0)';
      PINUSE='GROUND';
      NO_LOAD_CHECK='Both';
      NO_IO_CHECK='Both';
      NO_ASSERT_CHECK='TRUE';
      NO_DIR_CHECK='TRUE';
      ALLOW_CONNECT='TRUE';
    'VSS'<222>:
      PIN_NUMBER='(0,0,0,0,0,0,0,0,0,0,0,AK58,0,0)';
      PINUSE='GROUND';
      NO_LOAD_CHECK='Both';
      NO_IO_CHECK='Both';
      NO_ASSERT_CHECK='TRUE';
      NO_DIR_CHECK='TRUE';
      ALLOW_CONNECT='TRUE';
    'VSS'<221>:
      PIN_NUMBER='(0,0,0,0,0,0,0,0,0,0,0,AK61,0,0)';
      PINUSE='GROUND';
      NO_LOAD_CHECK='Both';
      NO_IO_CHECK='Both';
      NO_ASSERT_CHECK='TRUE';
      NO_DIR_CHECK='TRUE';
      ALLOW_CONNECT='TRUE';
    'VSS'<220>:
      PIN_NUMBER='(0,0,0,0,0,0,0,0,0,0,0,AK69,0,0)';
      PINUSE='GROUND';
      NO_LOAD_CHECK='Both';
      NO_IO_CHECK='Both';
      NO_ASSERT_CHECK='TRUE';
      NO_DIR_CHECK='TRUE';
      ALLOW_CONNECT='TRUE';
    'VSS'<219>:
      PIN_NUMBER='(0,0,0,0,0,0,0,0,0,0,0,AK71,0,0)';
      PINUSE='GROUND';
      NO_LOAD_CHECK='Both';
      NO_IO_CHECK='Both';
      NO_ASSERT_CHECK='TRUE';
      NO_DIR_CHECK='TRUE';
      ALLOW_CONNECT='TRUE';
    'VSS'<218>:
      PIN_NUMBER='(0,0,0,0,0,0,0,0,0,0,0,AL22,0,0)';
      PINUSE='GROUND';
      NO_LOAD_CHECK='Both';
      NO_IO_CHECK='Both';
      NO_ASSERT_CHECK='TRUE';
      NO_DIR_CHECK='TRUE';
      ALLOW_CONNECT='TRUE';
    'VSS'<217>:
      PIN_NUMBER='(0,0,0,0,0,0,0,0,0,0,0,AL5,0,0)';
      PINUSE='GROUND';
      NO_LOAD_CHECK='Both';
      NO_IO_CHECK='Both';
      NO_ASSERT_CHECK='TRUE';
      NO_DIR_CHECK='TRUE';
      ALLOW_CONNECT='TRUE';
    'VSS'<216>:
      PIN_NUMBER='(0,0,0,0,0,0,0,0,0,0,0,AL52,0,0)';
      PINUSE='GROUND';
      NO_LOAD_CHECK='Both';
      NO_IO_CHECK='Both';
      NO_ASSERT_CHECK='TRUE';
      NO_DIR_CHECK='TRUE';
      ALLOW_CONNECT='TRUE';
    'VSS'<215>:
      PIN_NUMBER='(0,0,0,0,0,0,0,0,0,0,0,AL59,0,0)';
      PINUSE='GROUND';
      NO_LOAD_CHECK='Both';
      NO_IO_CHECK='Both';
      NO_ASSERT_CHECK='TRUE';
      NO_DIR_CHECK='TRUE';
      ALLOW_CONNECT='TRUE';
    'VSS'<214>:
      PIN_NUMBER='(0,0,0,0,0,0,0,0,0,0,0,0,AL68,0)';
      PINUSE='GROUND';
      NO_LOAD_CHECK='Both';
      NO_IO_CHECK='Both';
      NO_ASSERT_CHECK='TRUE';
      NO_DIR_CHECK='TRUE';
      ALLOW_CONNECT='TRUE';
    'VSS'<213>:
      PIN_NUMBER='(0,0,0,0,0,0,0,0,0,0,0,0,AL70,0)';
      PINUSE='GROUND';
      NO_LOAD_CHECK='Both';
      NO_IO_CHECK='Both';
      NO_ASSERT_CHECK='TRUE';
      NO_DIR_CHECK='TRUE';
      ALLOW_CONNECT='TRUE';
    'VSS'<212>:
      PIN_NUMBER='(0,0,0,0,0,0,0,0,0,0,0,0,AL72,0)';
      PINUSE='GROUND';
      NO_LOAD_CHECK='Both';
      NO_IO_CHECK='Both';
      NO_ASSERT_CHECK='TRUE';
      NO_DIR_CHECK='TRUE';
      ALLOW_CONNECT='TRUE';
    'VSS'<211>:
      PIN_NUMBER='(0,0,0,0,0,0,0,0,0,0,0,0,AM26,0)';
      PINUSE='GROUND';
      NO_LOAD_CHECK='Both';
      NO_IO_CHECK='Both';
      NO_ASSERT_CHECK='TRUE';
      NO_DIR_CHECK='TRUE';
      ALLOW_CONNECT='TRUE';
    'VSS'<210>:
      PIN_NUMBER='(0,0,0,0,0,0,0,0,0,0,0,0,AM30,0)';
      PINUSE='GROUND';
      NO_LOAD_CHECK='Both';
      NO_IO_CHECK='Both';
      NO_ASSERT_CHECK='TRUE';
      NO_DIR_CHECK='TRUE';
      ALLOW_CONNECT='TRUE';
    'VSS'<209>:
      PIN_NUMBER='(0,0,0,0,0,0,0,0,0,0,0,0,AM41,0)';
      PINUSE='GROUND';
      NO_LOAD_CHECK='Both';
      NO_IO_CHECK='Both';
      NO_ASSERT_CHECK='TRUE';
      NO_DIR_CHECK='TRUE';
      ALLOW_CONNECT='TRUE';
    'VSS'<208>:
      PIN_NUMBER='(0,0,0,0,0,0,0,0,0,0,0,0,AM46,0)';
      PINUSE='GROUND';
      NO_LOAD_CHECK='Both';
      NO_IO_CHECK='Both';
      NO_ASSERT_CHECK='TRUE';
      NO_DIR_CHECK='TRUE';
      ALLOW_CONNECT='TRUE';
    'VSS'<207>:
      PIN_NUMBER='(0,0,0,0,0,0,0,0,0,0,0,0,AN13,0)';
      PINUSE='GROUND';
      NO_LOAD_CHECK='Both';
      NO_IO_CHECK='Both';
      NO_ASSERT_CHECK='TRUE';
      NO_DIR_CHECK='TRUE';
      ALLOW_CONNECT='TRUE';
    'VSS'<206>:
      PIN_NUMBER='(0,0,0,0,0,0,0,0,0,0,0,0,AN17,0)';
      PINUSE='GROUND';
      NO_LOAD_CHECK='Both';
      NO_IO_CHECK='Both';
      NO_ASSERT_CHECK='TRUE';
      NO_DIR_CHECK='TRUE';
      ALLOW_CONNECT='TRUE';
    'VSS'<205>:
      PIN_NUMBER='(0,0,0,0,0,0,0,0,0,0,0,0,AN68,0)';
      PINUSE='GROUND';
      NO_LOAD_CHECK='Both';
      NO_IO_CHECK='Both';
      NO_ASSERT_CHECK='TRUE';
      NO_DIR_CHECK='TRUE';
      ALLOW_CONNECT='TRUE';
    'VSS'<204>:
      PIN_NUMBER='(0,0,0,0,0,0,0,0,0,0,0,0,AP22,0)';
      PINUSE='GROUND';
      NO_LOAD_CHECK='Both';
      NO_IO_CHECK='Both';
      NO_ASSERT_CHECK='TRUE';
      NO_DIR_CHECK='TRUE';
      ALLOW_CONNECT='TRUE';
    'VSS'<203>:
      PIN_NUMBER='(0,0,0,0,0,0,0,0,0,0,0,0,AN20,0)';
      PINUSE='GROUND';
      NO_LOAD_CHECK='Both';
      NO_IO_CHECK='Both';
      NO_ASSERT_CHECK='TRUE';
      NO_DIR_CHECK='TRUE';
      ALLOW_CONNECT='TRUE';
    'VSS'<202>:
      PIN_NUMBER='(0,0,0,0,0,0,0,0,0,0,0,0,AN5,0)';
      PINUSE='GROUND';
      NO_LOAD_CHECK='Both';
      NO_IO_CHECK='Both';
      NO_ASSERT_CHECK='TRUE';
      NO_DIR_CHECK='TRUE';
      ALLOW_CONNECT='TRUE';
    'VSS'<201>:
      PIN_NUMBER='(0,0,0,0,0,0,0,0,0,0,0,0,AN58,0)';
      PINUSE='GROUND';
      NO_LOAD_CHECK='Both';
      NO_IO_CHECK='Both';
      NO_ASSERT_CHECK='TRUE';
      NO_DIR_CHECK='TRUE';
      ALLOW_CONNECT='TRUE';
    'VSS'<200>:
      PIN_NUMBER='(0,0,0,0,0,0,0,0,0,0,0,0,AN9,0)';
      PINUSE='GROUND';
      NO_LOAD_CHECK='Both';
      NO_IO_CHECK='Both';
      NO_ASSERT_CHECK='TRUE';
      NO_DIR_CHECK='TRUE';
      ALLOW_CONNECT='TRUE';
    'VSS'<199>:
      PIN_NUMBER='(0,0,0,0,0,0,0,0,0,0,0,0,AP2,0)';
      PINUSE='GROUND';
      NO_LOAD_CHECK='Both';
      NO_IO_CHECK='Both';
      NO_ASSERT_CHECK='TRUE';
      NO_DIR_CHECK='TRUE';
      ALLOW_CONNECT='TRUE';
    'VSS'<198>:
      PIN_NUMBER='(0,0,0,0,0,0,0,0,0,0,0,0,AP26,0)';
      PINUSE='GROUND';
      NO_LOAD_CHECK='Both';
      NO_IO_CHECK='Both';
      NO_ASSERT_CHECK='TRUE';
      NO_DIR_CHECK='TRUE';
      ALLOW_CONNECT='TRUE';
    'VSS'<197>:
      PIN_NUMBER='(0,0,0,0,0,0,0,0,0,0,0,0,AP30,0)';
      PINUSE='GROUND';
      NO_LOAD_CHECK='Both';
      NO_IO_CHECK='Both';
      NO_ASSERT_CHECK='TRUE';
      NO_DIR_CHECK='TRUE';
      ALLOW_CONNECT='TRUE';
    'VSS'<196>:
      PIN_NUMBER='(0,0,0,0,0,0,0,0,0,0,0,0,AP4,0)';
      PINUSE='GROUND';
      NO_LOAD_CHECK='Both';
      NO_IO_CHECK='Both';
      NO_ASSERT_CHECK='TRUE';
      NO_DIR_CHECK='TRUE';
      ALLOW_CONNECT='TRUE';
    'VSS'<195>:
      PIN_NUMBER='(0,0,0,0,0,0,0,0,0,0,0,0,AP41,0)';
      PINUSE='GROUND';
      NO_LOAD_CHECK='Both';
      NO_IO_CHECK='Both';
      NO_ASSERT_CHECK='TRUE';
      NO_DIR_CHECK='TRUE';
      ALLOW_CONNECT='TRUE';
    'VSS'<194>:
      PIN_NUMBER='(0,0,0,0,0,0,0,0,0,0,0,0,AP46,0)';
      PINUSE='GROUND';
      NO_LOAD_CHECK='Both';
      NO_IO_CHECK='Both';
      NO_ASSERT_CHECK='TRUE';
      NO_DIR_CHECK='TRUE';
      ALLOW_CONNECT='TRUE';
    'VSS'<193>:
      PIN_NUMBER='(0,0,0,0,0,0,0,0,0,0,0,0,AP52,0)';
      PINUSE='GROUND';
      NO_LOAD_CHECK='Both';
      NO_IO_CHECK='Both';
      NO_ASSERT_CHECK='TRUE';
      NO_DIR_CHECK='TRUE';
      ALLOW_CONNECT='TRUE';
    'VSS'<192>:
      PIN_NUMBER='(0,0,0,0,0,0,0,0,0,0,0,0,AP66,0)';
      PINUSE='GROUND';
      NO_LOAD_CHECK='Both';
      NO_IO_CHECK='Both';
      NO_ASSERT_CHECK='TRUE';
      NO_DIR_CHECK='TRUE';
      ALLOW_CONNECT='TRUE';
    'VSS'<191>:
      PIN_NUMBER='(0,0,0,0,0,0,0,0,0,0,0,0,AR5,0)';
      PINUSE='GROUND';
      NO_LOAD_CHECK='Both';
      NO_IO_CHECK='Both';
      NO_ASSERT_CHECK='TRUE';
      NO_DIR_CHECK='TRUE';
      ALLOW_CONNECT='TRUE';
    'VSS'<190>:
      PIN_NUMBER='(0,0,0,0,0,0,0,0,0,0,0,0,AR50,0)';
      PINUSE='GROUND';
      NO_LOAD_CHECK='Both';
      NO_IO_CHECK='Both';
      NO_ASSERT_CHECK='TRUE';
      NO_DIR_CHECK='TRUE';
      ALLOW_CONNECT='TRUE';
    'VSS'<189>:
      PIN_NUMBER='(0,0,0,0,0,0,0,0,0,0,0,0,AR58,0)';
      PINUSE='GROUND';
      NO_LOAD_CHECK='Both';
      NO_IO_CHECK='Both';
      NO_ASSERT_CHECK='TRUE';
      NO_DIR_CHECK='TRUE';
      ALLOW_CONNECT='TRUE';
    'VSS'<188>:
      PIN_NUMBER='(0,0,0,0,0,0,0,0,0,0,0,0,AR65,0)';
      PINUSE='GROUND';
      NO_LOAD_CHECK='Both';
      NO_IO_CHECK='Both';
      NO_ASSERT_CHECK='TRUE';
      NO_DIR_CHECK='TRUE';
      ALLOW_CONNECT='TRUE';
    'VSS'<187>:
      PIN_NUMBER='(0,0,0,0,0,0,0,0,0,0,0,0,AR68,0)';
      PINUSE='GROUND';
      NO_LOAD_CHECK='Both';
      NO_IO_CHECK='Both';
      NO_ASSERT_CHECK='TRUE';
      NO_DIR_CHECK='TRUE';
      ALLOW_CONNECT='TRUE';
    'VSS'<186>:
      PIN_NUMBER='(0,0,0,0,0,0,0,0,0,0,0,0,AR70,0)';
      PINUSE='GROUND';
      NO_LOAD_CHECK='Both';
      NO_IO_CHECK='Both';
      NO_ASSERT_CHECK='TRUE';
      NO_DIR_CHECK='TRUE';
      ALLOW_CONNECT='TRUE';
    'VSS'<185>:
      PIN_NUMBER='(0,0,0,0,0,0,0,0,0,0,0,0,AR72,0)';
      PINUSE='GROUND';
      NO_LOAD_CHECK='Both';
      NO_IO_CHECK='Both';
      NO_ASSERT_CHECK='TRUE';
      NO_DIR_CHECK='TRUE';
      ALLOW_CONNECT='TRUE';
    'VSS'<184>:
      PIN_NUMBER='(0,0,0,0,0,0,0,0,0,0,0,0,AT7,0)';
      PINUSE='GROUND';
      NO_LOAD_CHECK='Both';
      NO_IO_CHECK='Both';
      NO_ASSERT_CHECK='TRUE';
      NO_DIR_CHECK='TRUE';
      ALLOW_CONNECT='TRUE';
    'VSS'<183>:
      PIN_NUMBER='(0,0,0,0,0,0,0,0,0,0,0,0,AT11,0)';
      PINUSE='GROUND';
      NO_LOAD_CHECK='Both';
      NO_IO_CHECK='Both';
      NO_ASSERT_CHECK='TRUE';
      NO_DIR_CHECK='TRUE';
      ALLOW_CONNECT='TRUE';
    'VSS'<182>:
      PIN_NUMBER='(0,0,0,0,0,0,0,0,0,0,0,0,AT15,0)';
      PINUSE='GROUND';
      NO_LOAD_CHECK='Both';
      NO_IO_CHECK='Both';
      NO_ASSERT_CHECK='TRUE';
      NO_DIR_CHECK='TRUE';
      ALLOW_CONNECT='TRUE';
    'VSS'<181>:
      PIN_NUMBER='(0,0,0,0,0,0,0,0,0,0,0,0,AT18,0)';
      PINUSE='GROUND';
      NO_LOAD_CHECK='Both';
      NO_IO_CHECK='Both';
      NO_ASSERT_CHECK='TRUE';
      NO_DIR_CHECK='TRUE';
      ALLOW_CONNECT='TRUE';
    'VSS'<180>:
      PIN_NUMBER='(0,0,0,0,0,0,0,0,0,0,0,0,AT22,0)';
      PINUSE='GROUND';
      NO_LOAD_CHECK='Both';
      NO_IO_CHECK='Both';
      NO_ASSERT_CHECK='TRUE';
      NO_DIR_CHECK='TRUE';
      ALLOW_CONNECT='TRUE';
    'VSS'<179>:
      PIN_NUMBER='(0,0,0,0,0,0,0,0,0,0,0,0,AT26,0)';
      PINUSE='GROUND';
      NO_LOAD_CHECK='Both';
      NO_IO_CHECK='Both';
      NO_ASSERT_CHECK='TRUE';
      NO_DIR_CHECK='TRUE';
      ALLOW_CONNECT='TRUE';
    'VSS'<178>:
      PIN_NUMBER='(0,0,0,0,0,0,0,0,0,0,0,0,AT30,0)';
      PINUSE='GROUND';
      NO_LOAD_CHECK='Both';
      NO_IO_CHECK='Both';
      NO_ASSERT_CHECK='TRUE';
      NO_DIR_CHECK='TRUE';
      ALLOW_CONNECT='TRUE';
    'VSS'<177>:
      PIN_NUMBER='(0,0,0,0,0,0,0,0,0,0,0,0,AT41,0)';
      PINUSE='GROUND';
      NO_LOAD_CHECK='Both';
      NO_IO_CHECK='Both';
      NO_ASSERT_CHECK='TRUE';
      NO_DIR_CHECK='TRUE';
      ALLOW_CONNECT='TRUE';
    'VSS'<176>:
      PIN_NUMBER='(0,0,0,0,0,0,0,0,0,0,0,0,AT46,0)';
      PINUSE='GROUND';
      NO_LOAD_CHECK='Both';
      NO_IO_CHECK='Both';
      NO_ASSERT_CHECK='TRUE';
      NO_DIR_CHECK='TRUE';
      ALLOW_CONNECT='TRUE';
    'VSS'<175>:
      PIN_NUMBER='(0,0,0,0,0,0,0,0,0,0,0,0,AT59,0)';
      PINUSE='GROUND';
      NO_LOAD_CHECK='Both';
      NO_IO_CHECK='Both';
      NO_ASSERT_CHECK='TRUE';
      NO_DIR_CHECK='TRUE';
      ALLOW_CONNECT='TRUE';
    'VSS'<174>:
      PIN_NUMBER='(0,0,0,0,0,0,0,0,0,0,0,0,AU26,0)';
      PINUSE='GROUND';
      NO_LOAD_CHECK='Both';
      NO_IO_CHECK='Both';
      NO_ASSERT_CHECK='TRUE';
      NO_DIR_CHECK='TRUE';
      ALLOW_CONNECT='TRUE';
    'VSS'<173>:
      PIN_NUMBER='(0,0,0,0,0,0,0,0,0,0,0,0,AU30,0)';
      PINUSE='GROUND';
      NO_LOAD_CHECK='Both';
      NO_IO_CHECK='Both';
      NO_ASSERT_CHECK='TRUE';
      NO_DIR_CHECK='TRUE';
      ALLOW_CONNECT='TRUE';
    'VSS'<172>:
      PIN_NUMBER='(0,0,0,0,0,0,0,0,0,0,0,0,AE22,0)';
      PINUSE='GROUND';
      NO_LOAD_CHECK='Both';
      NO_IO_CHECK='Both';
      NO_ASSERT_CHECK='TRUE';
      NO_DIR_CHECK='TRUE';
      ALLOW_CONNECT='TRUE';
    'VSS'<171>:
      PIN_NUMBER='(0,0,0,0,0,0,0,0,0,0,0,0,AU41,0)';
      PINUSE='GROUND';
      NO_LOAD_CHECK='Both';
      NO_IO_CHECK='Both';
      NO_ASSERT_CHECK='TRUE';
      NO_DIR_CHECK='TRUE';
      ALLOW_CONNECT='TRUE';
    'VSS'<170>:
      PIN_NUMBER='(0,0,0,0,0,0,0,0,0,0,0,0,AU46,0)';
      PINUSE='GROUND';
      NO_LOAD_CHECK='Both';
      NO_IO_CHECK='Both';
      NO_ASSERT_CHECK='TRUE';
      NO_DIR_CHECK='TRUE';
      ALLOW_CONNECT='TRUE';
    'VSS'<169>:
      PIN_NUMBER='(0,0,0,0,0,0,0,0,0,0,0,0,AU50,0)';
      PINUSE='GROUND';
      NO_LOAD_CHECK='Both';
      NO_IO_CHECK='Both';
      NO_ASSERT_CHECK='TRUE';
      NO_DIR_CHECK='TRUE';
      ALLOW_CONNECT='TRUE';
    'VSS'<168>:
      PIN_NUMBER='(0,0,0,0,0,0,0,0,0,0,0,0,AU54,0)';
      PINUSE='GROUND';
      NO_LOAD_CHECK='Both';
      NO_IO_CHECK='Both';
      NO_ASSERT_CHECK='TRUE';
      NO_DIR_CHECK='TRUE';
      ALLOW_CONNECT='TRUE';
    'VSS'<167>:
      PIN_NUMBER='(0,0,0,0,0,0,0,0,0,0,0,0,AU61,0)';
      PINUSE='GROUND';
      NO_LOAD_CHECK='Both';
      NO_IO_CHECK='Both';
      NO_ASSERT_CHECK='TRUE';
      NO_DIR_CHECK='TRUE';
      ALLOW_CONNECT='TRUE';
    'VSS'<166>:
      PIN_NUMBER='(0,0,0,0,0,0,0,0,0,0,0,0,AV5,0)';
      PINUSE='GROUND';
      NO_LOAD_CHECK='Both';
      NO_IO_CHECK='Both';
      NO_ASSERT_CHECK='TRUE';
      NO_DIR_CHECK='TRUE';
      ALLOW_CONNECT='TRUE';
    'VSS'<165>:
      PIN_NUMBER='(0,0,0,0,0,0,0,0,0,0,0,0,AV22,0)';
      PINUSE='GROUND';
      NO_LOAD_CHECK='Both';
      NO_IO_CHECK='Both';
      NO_ASSERT_CHECK='TRUE';
      NO_DIR_CHECK='TRUE';
      ALLOW_CONNECT='TRUE';
    'VSS'<164>:
      PIN_NUMBER='(0,0,0,0,0,0,0,0,0,0,0,0,AV59,0)';
      PINUSE='GROUND';
      NO_LOAD_CHECK='Both';
      NO_IO_CHECK='Both';
      NO_ASSERT_CHECK='TRUE';
      NO_DIR_CHECK='TRUE';
      ALLOW_CONNECT='TRUE';
    'VSS'<163>:
      PIN_NUMBER='(0,0,0,0,0,0,0,0,0,0,0,0,AV68,0)';
      PINUSE='GROUND';
      NO_LOAD_CHECK='Both';
      NO_IO_CHECK='Both';
      NO_ASSERT_CHECK='TRUE';
      NO_DIR_CHECK='TRUE';
      ALLOW_CONNECT='TRUE';
    'VSS'<162>:
      PIN_NUMBER='(0,0,0,0,0,0,0,0,0,0,0,0,AW9,0)';
      PINUSE='GROUND';
      NO_LOAD_CHECK='Both';
      NO_IO_CHECK='Both';
      NO_ASSERT_CHECK='TRUE';
      NO_DIR_CHECK='TRUE';
      ALLOW_CONNECT='TRUE';
    'VSS'<161>:
      PIN_NUMBER='(0,0,0,0,0,0,0,0,0,0,0,0,AW13,0)';
      PINUSE='GROUND';
      NO_LOAD_CHECK='Both';
      NO_IO_CHECK='Both';
      NO_ASSERT_CHECK='TRUE';
      NO_DIR_CHECK='TRUE';
      ALLOW_CONNECT='TRUE';
    'VSS'<160>:
      PIN_NUMBER='(0,0,0,0,0,0,0,0,0,0,0,0,AW17,0)';
      PINUSE='GROUND';
      NO_LOAD_CHECK='Both';
      NO_IO_CHECK='Both';
      NO_ASSERT_CHECK='TRUE';
      NO_DIR_CHECK='TRUE';
      ALLOW_CONNECT='TRUE';
    'VSS'<159>:
      PIN_NUMBER='(0,0,0,0,0,0,0,0,0,0,0,0,AW26,0)';
      PINUSE='GROUND';
      NO_LOAD_CHECK='Both';
      NO_IO_CHECK='Both';
      NO_ASSERT_CHECK='TRUE';
      NO_DIR_CHECK='TRUE';
      ALLOW_CONNECT='TRUE';
    'VSS'<158>:
      PIN_NUMBER='(0,0,0,0,0,0,0,0,0,0,0,0,AW30,0)';
      PINUSE='GROUND';
      NO_LOAD_CHECK='Both';
      NO_IO_CHECK='Both';
      NO_ASSERT_CHECK='TRUE';
      NO_DIR_CHECK='TRUE';
      ALLOW_CONNECT='TRUE';
    'VSS'<157>:
      PIN_NUMBER='(0,0,0,0,0,0,0,0,0,0,0,0,AW32,0)';
      PINUSE='GROUND';
      NO_LOAD_CHECK='Both';
      NO_IO_CHECK='Both';
      NO_ASSERT_CHECK='TRUE';
      NO_DIR_CHECK='TRUE';
      ALLOW_CONNECT='TRUE';
    'VSS'<156>:
      PIN_NUMBER='(0,0,0,0,0,0,0,0,0,0,0,0,AW34,0)';
      PINUSE='GROUND';
      NO_LOAD_CHECK='Both';
      NO_IO_CHECK='Both';
      NO_ASSERT_CHECK='TRUE';
      NO_DIR_CHECK='TRUE';
      ALLOW_CONNECT='TRUE';
    'VSS'<155>:
      PIN_NUMBER='(0,0,0,0,0,0,0,0,0,0,0,0,AW36,0)';
      PINUSE='GROUND';
      NO_LOAD_CHECK='Both';
      NO_IO_CHECK='Both';
      NO_ASSERT_CHECK='TRUE';
      NO_DIR_CHECK='TRUE';
      ALLOW_CONNECT='TRUE';
    'VSS'<154>:
      PIN_NUMBER='(0,0,0,0,0,0,0,0,0,0,0,0,AW37,0)';
      PINUSE='GROUND';
      NO_LOAD_CHECK='Both';
      NO_IO_CHECK='Both';
      NO_ASSERT_CHECK='TRUE';
      NO_DIR_CHECK='TRUE';
      ALLOW_CONNECT='TRUE';
    'VSS'<153>:
      PIN_NUMBER='(0,0,0,0,0,0,0,0,0,0,0,0,AW39,0)';
      PINUSE='GROUND';
      NO_LOAD_CHECK='Both';
      NO_IO_CHECK='Both';
      NO_ASSERT_CHECK='TRUE';
      NO_DIR_CHECK='TRUE';
      ALLOW_CONNECT='TRUE';
    'VSS'<152>:
      PIN_NUMBER='(0,0,0,0,0,0,0,0,0,0,0,0,AW41,0)';
      PINUSE='GROUND';
      NO_LOAD_CHECK='Both';
      NO_IO_CHECK='Both';
      NO_ASSERT_CHECK='TRUE';
      NO_DIR_CHECK='TRUE';
      ALLOW_CONNECT='TRUE';
    'VSS'<151>:
      PIN_NUMBER='(0,0,0,0,0,0,0,0,0,0,0,0,AW46,0)';
      PINUSE='GROUND';
      NO_LOAD_CHECK='Both';
      NO_IO_CHECK='Both';
      NO_ASSERT_CHECK='TRUE';
      NO_DIR_CHECK='TRUE';
      ALLOW_CONNECT='TRUE';
    'VSS'<150>:
      PIN_NUMBER='(0,0,0,0,0,0,0,0,0,0,0,0,AW50,0)';
      PINUSE='GROUND';
      NO_LOAD_CHECK='Both';
      NO_IO_CHECK='Both';
      NO_ASSERT_CHECK='TRUE';
      NO_DIR_CHECK='TRUE';
      ALLOW_CONNECT='TRUE';
    'VSS'<149>:
      PIN_NUMBER='(0,0,0,0,0,0,0,0,0,0,0,0,AW58,0)';
      PINUSE='GROUND';
      NO_LOAD_CHECK='Both';
      NO_IO_CHECK='Both';
      NO_ASSERT_CHECK='TRUE';
      NO_DIR_CHECK='TRUE';
      ALLOW_CONNECT='TRUE';
    'VSS'<148>:
      PIN_NUMBER='(0,0,0,0,0,0,0,0,0,0,0,0,AW61,0)';
      PINUSE='GROUND';
      NO_LOAD_CHECK='Both';
      NO_IO_CHECK='Both';
      NO_ASSERT_CHECK='TRUE';
      NO_DIR_CHECK='TRUE';
      ALLOW_CONNECT='TRUE';
    'VSS'<147>:
      PIN_NUMBER='(0,0,0,0,0,0,0,0,0,0,0,0,AY5,0)';
      PINUSE='GROUND';
      NO_LOAD_CHECK='Both';
      NO_IO_CHECK='Both';
      NO_ASSERT_CHECK='TRUE';
      NO_DIR_CHECK='TRUE';
      ALLOW_CONNECT='TRUE';
    'VSS'<146>:
      PIN_NUMBER='(0,0,0,0,0,0,0,0,0,0,0,0,AY22,0)';
      PINUSE='GROUND';
      NO_LOAD_CHECK='Both';
      NO_IO_CHECK='Both';
      NO_ASSERT_CHECK='TRUE';
      NO_DIR_CHECK='TRUE';
      ALLOW_CONNECT='TRUE';
    'VSS'<145>:
      PIN_NUMBER='(0,0,0,0,0,0,0,0,0,0,0,0,AY56,0)';
      PINUSE='GROUND';
      NO_LOAD_CHECK='Both';
      NO_IO_CHECK='Both';
      NO_ASSERT_CHECK='TRUE';
      NO_DIR_CHECK='TRUE';
      ALLOW_CONNECT='TRUE';
    'VSS'<144>:
      PIN_NUMBER='(0,0,0,0,0,0,0,0,0,0,0,0,AY63,0)';
      PINUSE='GROUND';
      NO_LOAD_CHECK='Both';
      NO_IO_CHECK='Both';
      NO_ASSERT_CHECK='TRUE';
      NO_DIR_CHECK='TRUE';
      ALLOW_CONNECT='TRUE';
    'VSS'<143>:
      PIN_NUMBER='(0,0,0,0,0,0,0,0,0,0,0,0,AY68,0)';
      PINUSE='GROUND';
      NO_LOAD_CHECK='Both';
      NO_IO_CHECK='Both';
      NO_ASSERT_CHECK='TRUE';
      NO_DIR_CHECK='TRUE';
      ALLOW_CONNECT='TRUE';
    'VSS'<142>:
      PIN_NUMBER='(0,0,0,0,0,0,0,0,0,0,0,0,BA50,0)';
      PINUSE='GROUND';
      NO_LOAD_CHECK='Both';
      NO_IO_CHECK='Both';
      NO_ASSERT_CHECK='TRUE';
      NO_DIR_CHECK='TRUE';
      ALLOW_CONNECT='TRUE';
    'VSS'<141>:
      PIN_NUMBER='(0,0,0,0,0,0,0,0,0,0,0,0,BA54,0)';
      PINUSE='GROUND';
      NO_LOAD_CHECK='Both';
      NO_IO_CHECK='Both';
      NO_ASSERT_CHECK='TRUE';
      NO_DIR_CHECK='TRUE';
      ALLOW_CONNECT='TRUE';
    'VSS'<140>:
      PIN_NUMBER='(0,0,0,0,0,0,0,0,0,0,0,0,BA58,0)';
      PINUSE='GROUND';
      NO_LOAD_CHECK='Both';
      NO_IO_CHECK='Both';
      NO_ASSERT_CHECK='TRUE';
      NO_DIR_CHECK='TRUE';
      ALLOW_CONNECT='TRUE';
    'VSS'<139>:
      PIN_NUMBER='(0,0,0,0,0,0,0,0,0,0,0,0,BB5,0)';
      PINUSE='GROUND';
      NO_LOAD_CHECK='Both';
      NO_IO_CHECK='Both';
      NO_ASSERT_CHECK='TRUE';
      NO_DIR_CHECK='TRUE';
      ALLOW_CONNECT='TRUE';
    'VSS'<138>:
      PIN_NUMBER='(0,0,0,0,0,0,0,0,0,0,0,0,BB7,0)';
      PINUSE='GROUND';
      NO_LOAD_CHECK='Both';
      NO_IO_CHECK='Both';
      NO_ASSERT_CHECK='TRUE';
      NO_DIR_CHECK='TRUE';
      ALLOW_CONNECT='TRUE';
    'VSS'<137>:
      PIN_NUMBER='(0,0,0,0,0,0,0,0,0,0,0,0,BB11,0)';
      PINUSE='GROUND';
      NO_LOAD_CHECK='Both';
      NO_IO_CHECK='Both';
      NO_ASSERT_CHECK='TRUE';
      NO_DIR_CHECK='TRUE';
      ALLOW_CONNECT='TRUE';
    'VSS'<136>:
      PIN_NUMBER='(0,0,0,0,0,0,0,0,0,0,0,0,BB15,0)';
      PINUSE='GROUND';
      NO_LOAD_CHECK='Both';
      NO_IO_CHECK='Both';
      NO_ASSERT_CHECK='TRUE';
      NO_DIR_CHECK='TRUE';
      ALLOW_CONNECT='TRUE';
    'VSS'<135>:
      PIN_NUMBER='(0,0,0,0,0,0,0,0,0,0,0,0,BB18,0)';
      PINUSE='GROUND';
      NO_LOAD_CHECK='Both';
      NO_IO_CHECK='Both';
      NO_ASSERT_CHECK='TRUE';
      NO_DIR_CHECK='TRUE';
      ALLOW_CONNECT='TRUE';
    'VSS'<134>:
      PIN_NUMBER='(0,0,0,0,0,0,0,0,0,0,0,0,BB22,0)';
      PINUSE='GROUND';
      NO_LOAD_CHECK='Both';
      NO_IO_CHECK='Both';
      NO_ASSERT_CHECK='TRUE';
      NO_DIR_CHECK='TRUE';
      ALLOW_CONNECT='TRUE';
    'VSS'<133>:
      PIN_NUMBER='(0,0,0,0,0,0,0,0,0,0,0,0,BB44,0)';
      PINUSE='GROUND';
      NO_LOAD_CHECK='Both';
      NO_IO_CHECK='Both';
      NO_ASSERT_CHECK='TRUE';
      NO_DIR_CHECK='TRUE';
      ALLOW_CONNECT='TRUE';
    'VSS'<132>:
      PIN_NUMBER='(0,0,0,0,0,0,0,0,0,0,0,0,BB59,0)';
      PINUSE='GROUND';
      NO_LOAD_CHECK='Both';
      NO_IO_CHECK='Both';
      NO_ASSERT_CHECK='TRUE';
      NO_DIR_CHECK='TRUE';
      ALLOW_CONNECT='TRUE';
    'VSS'<131>:
      PIN_NUMBER='(0,0,0,0,0,0,0,0,0,0,0,0,BB66,0)';
      PINUSE='GROUND';
      NO_LOAD_CHECK='Both';
      NO_IO_CHECK='Both';
      NO_ASSERT_CHECK='TRUE';
      NO_DIR_CHECK='TRUE';
      ALLOW_CONNECT='TRUE';
    'VSS'<130>:
      PIN_NUMBER='(0,0,0,0,0,0,0,0,0,0,0,0,BB68,0)';
      PINUSE='GROUND';
      NO_LOAD_CHECK='Both';
      NO_IO_CHECK='Both';
      NO_ASSERT_CHECK='TRUE';
      NO_DIR_CHECK='TRUE';
      ALLOW_CONNECT='TRUE';
    'VSS'<129>:
      PIN_NUMBER='(0,0,0,0,0,0,0,0,0,0,0,0,BB70,0)';
      PINUSE='GROUND';
      NO_LOAD_CHECK='Both';
      NO_IO_CHECK='Both';
      NO_ASSERT_CHECK='TRUE';
      NO_DIR_CHECK='TRUE';
      ALLOW_CONNECT='TRUE';
    'VSS'<128>:
      PIN_NUMBER='(0,0,0,0,0,0,0,0,0,0,0,0,BB72,0)';
      PINUSE='GROUND';
      NO_LOAD_CHECK='Both';
      NO_IO_CHECK='Both';
      NO_ASSERT_CHECK='TRUE';
      NO_DIR_CHECK='TRUE';
      ALLOW_CONNECT='TRUE';
    'VSS'<127>:
      PIN_NUMBER='(0,0,0,0,0,0,0,0,0,0,0,0,BC69,0)';
      PINUSE='GROUND';
      NO_LOAD_CHECK='Both';
      NO_IO_CHECK='Both';
      NO_ASSERT_CHECK='TRUE';
      NO_DIR_CHECK='TRUE';
      ALLOW_CONNECT='TRUE';
    'VSS'<126>:
      PIN_NUMBER='(0,0,0,0,0,0,0,0,0,0,0,0,BC71,0)';
      PINUSE='GROUND';
      NO_LOAD_CHECK='Both';
      NO_IO_CHECK='Both';
      NO_ASSERT_CHECK='TRUE';
      NO_DIR_CHECK='TRUE';
      ALLOW_CONNECT='TRUE';
    'VSS'<125>:
      PIN_NUMBER='(0,0,0,0,0,0,0,0,0,0,0,0,BD24,0)';
      PINUSE='GROUND';
      NO_LOAD_CHECK='Both';
      NO_IO_CHECK='Both';
      NO_ASSERT_CHECK='TRUE';
      NO_DIR_CHECK='TRUE';
      ALLOW_CONNECT='TRUE';
    'VSS'<124>:
      PIN_NUMBER='(0,0,0,0,0,0,0,0,0,0,0,0,BD27,0)';
      PINUSE='GROUND';
      NO_LOAD_CHECK='Both';
      NO_IO_CHECK='Both';
      NO_ASSERT_CHECK='TRUE';
      NO_DIR_CHECK='TRUE';
      ALLOW_CONNECT='TRUE';
    'VSS'<123>:
      PIN_NUMBER='(0,0,0,0,0,0,0,0,0,0,0,0,BD31,0)';
      PINUSE='GROUND';
      NO_LOAD_CHECK='Both';
      NO_IO_CHECK='Both';
      NO_ASSERT_CHECK='TRUE';
      NO_DIR_CHECK='TRUE';
      ALLOW_CONNECT='TRUE';
    'VSS'<122>:
      PIN_NUMBER='(0,0,0,0,0,0,0,0,0,0,0,0,BD35,0)';
      PINUSE='GROUND';
      NO_LOAD_CHECK='Both';
      NO_IO_CHECK='Both';
      NO_ASSERT_CHECK='TRUE';
      NO_DIR_CHECK='TRUE';
      ALLOW_CONNECT='TRUE';
    'VSS'<121>:
      PIN_NUMBER='(0,0,0,0,0,0,0,0,0,0,0,0,BD5,0)';
      PINUSE='GROUND';
      NO_LOAD_CHECK='Both';
      NO_IO_CHECK='Both';
      NO_ASSERT_CHECK='TRUE';
      NO_DIR_CHECK='TRUE';
      ALLOW_CONNECT='TRUE';
    'VSS'<120>:
      PIN_NUMBER='(0,0,0,0,0,0,0,0,0,0,0,0,BD50,0)';
      PINUSE='GROUND';
      NO_LOAD_CHECK='Both';
      NO_IO_CHECK='Both';
      NO_ASSERT_CHECK='TRUE';
      NO_DIR_CHECK='TRUE';
      ALLOW_CONNECT='TRUE';
    'VSS'<119>:
      PIN_NUMBER='(0,0,0,0,0,0,0,0,0,0,0,0,BD54,0)';
      PINUSE='GROUND';
      NO_LOAD_CHECK='Both';
      NO_IO_CHECK='Both';
      NO_ASSERT_CHECK='TRUE';
      NO_DIR_CHECK='TRUE';
      ALLOW_CONNECT='TRUE';
    'VSS'<118>:
      PIN_NUMBER='(0,0,0,0,0,0,0,0,0,0,0,0,BD68,0)';
      PINUSE='GROUND';
      NO_LOAD_CHECK='Both';
      NO_IO_CHECK='Both';
      NO_ASSERT_CHECK='TRUE';
      NO_DIR_CHECK='TRUE';
      ALLOW_CONNECT='TRUE';
    'VSS'<117>:
      PIN_NUMBER='(0,0,0,0,0,0,0,0,0,0,0,0,BE29,0)';
      PINUSE='GROUND';
      NO_LOAD_CHECK='Both';
      NO_IO_CHECK='Both';
      NO_ASSERT_CHECK='TRUE';
      NO_DIR_CHECK='TRUE';
      ALLOW_CONNECT='TRUE';
    'VSS'<116>:
      PIN_NUMBER='(0,0,0,0,0,0,0,0,0,0,0,0,BE33,0)';
      PINUSE='GROUND';
      NO_LOAD_CHECK='Both';
      NO_IO_CHECK='Both';
      NO_ASSERT_CHECK='TRUE';
      NO_DIR_CHECK='TRUE';
      ALLOW_CONNECT='TRUE';
    'VSS'<115>:
      PIN_NUMBER='(0,0,0,0,0,0,0,0,0,0,0,0,BE37,0)';
      PINUSE='GROUND';
      NO_LOAD_CHECK='Both';
      NO_IO_CHECK='Both';
      NO_ASSERT_CHECK='TRUE';
      NO_DIR_CHECK='TRUE';
      ALLOW_CONNECT='TRUE';
    'VSS'<114>:
      PIN_NUMBER='(0,0,0,0,0,0,0,0,0,0,0,0,BE56,0)';
      PINUSE='GROUND';
      NO_LOAD_CHECK='Both';
      NO_IO_CHECK='Both';
      NO_ASSERT_CHECK='TRUE';
      NO_DIR_CHECK='TRUE';
      ALLOW_CONNECT='TRUE';
    'VSS'<113>:
      PIN_NUMBER='(0,0,0,0,0,0,0,0,0,0,0,0,BE59,0)';
      PINUSE='GROUND';
      NO_LOAD_CHECK='Both';
      NO_IO_CHECK='Both';
      NO_ASSERT_CHECK='TRUE';
      NO_DIR_CHECK='TRUE';
      ALLOW_CONNECT='TRUE';
    'VSS'<112>:
      PIN_NUMBER='(0,0,0,0,0,0,0,0,0,0,0,0,BE63,0)';
      PINUSE='GROUND';
      NO_LOAD_CHECK='Both';
      NO_IO_CHECK='Both';
      NO_ASSERT_CHECK='TRUE';
      NO_DIR_CHECK='TRUE';
      ALLOW_CONNECT='TRUE';
    'VSS'<111>:
      PIN_NUMBER='(0,0,0,0,0,0,0,0,0,0,0,0,BE66,0)';
      PINUSE='GROUND';
      NO_LOAD_CHECK='Both';
      NO_IO_CHECK='Both';
      NO_ASSERT_CHECK='TRUE';
      NO_DIR_CHECK='TRUE';
      ALLOW_CONNECT='TRUE';
    'VSS'<110>:
      PIN_NUMBER='(0,0,0,0,0,0,0,0,0,0,0,0,BF13,0)';
      PINUSE='GROUND';
      NO_LOAD_CHECK='Both';
      NO_IO_CHECK='Both';
      NO_ASSERT_CHECK='TRUE';
      NO_DIR_CHECK='TRUE';
      ALLOW_CONNECT='TRUE';
    'VSS'<109>:
      PIN_NUMBER='(0,0,0,0,0,0,0,0,0,0,0,0,BF17,0)';
      PINUSE='GROUND';
      NO_LOAD_CHECK='Both';
      NO_IO_CHECK='Both';
      NO_ASSERT_CHECK='TRUE';
      NO_DIR_CHECK='TRUE';
      ALLOW_CONNECT='TRUE';
    'VSS'<108>:
      PIN_NUMBER='(0,0,0,0,0,0,0,0,0,0,0,0,BF54,0)';
      PINUSE='GROUND';
      NO_LOAD_CHECK='Both';
      NO_IO_CHECK='Both';
      NO_ASSERT_CHECK='TRUE';
      NO_DIR_CHECK='TRUE';
      ALLOW_CONNECT='TRUE';
    'VSS'<107>:
      PIN_NUMBER='(0,0,0,0,0,0,0,0,0,0,0,0,BG44,0)';
      PINUSE='GROUND';
      NO_LOAD_CHECK='Both';
      NO_IO_CHECK='Both';
      NO_ASSERT_CHECK='TRUE';
      NO_DIR_CHECK='TRUE';
      ALLOW_CONNECT='TRUE';
    'VSS'<106>:
      PIN_NUMBER='(0,0,0,0,0,0,0,0,0,0,0,0,BF20,0)';
      PINUSE='GROUND';
      NO_LOAD_CHECK='Both';
      NO_IO_CHECK='Both';
      NO_ASSERT_CHECK='TRUE';
      NO_DIR_CHECK='TRUE';
      ALLOW_CONNECT='TRUE';
    'VSS'<105>:
      PIN_NUMBER='(0,0,0,0,0,0,0,0,0,0,0,0,BF24,0)';
      PINUSE='GROUND';
      NO_LOAD_CHECK='Both';
      NO_IO_CHECK='Both';
      NO_ASSERT_CHECK='TRUE';
      NO_DIR_CHECK='TRUE';
      ALLOW_CONNECT='TRUE';
    'VSS'<104>:
      PIN_NUMBER='(0,0,0,0,0,0,0,0,0,0,0,0,BF27,0)';
      PINUSE='GROUND';
      NO_LOAD_CHECK='Both';
      NO_IO_CHECK='Both';
      NO_ASSERT_CHECK='TRUE';
      NO_DIR_CHECK='TRUE';
      ALLOW_CONNECT='TRUE';
    'VSS'<103>:
      PIN_NUMBER='(0,0,0,0,0,0,0,0,0,0,0,0,BF38,0)';
      PINUSE='GROUND';
      NO_LOAD_CHECK='Both';
      NO_IO_CHECK='Both';
      NO_ASSERT_CHECK='TRUE';
      NO_DIR_CHECK='TRUE';
      ALLOW_CONNECT='TRUE';
    'VSS'<102>:
      PIN_NUMBER='(0,0,0,0,0,0,0,0,0,0,0,0,BF42,0)';
      PINUSE='GROUND';
      NO_LOAD_CHECK='Both';
      NO_IO_CHECK='Both';
      NO_ASSERT_CHECK='TRUE';
      NO_DIR_CHECK='TRUE';
      ALLOW_CONNECT='TRUE';
    'VSS'<101>:
      PIN_NUMBER='(0,0,0,0,0,0,0,0,0,0,0,0,BF5,0)';
      PINUSE='GROUND';
      NO_LOAD_CHECK='Both';
      NO_IO_CHECK='Both';
      NO_ASSERT_CHECK='TRUE';
      NO_DIR_CHECK='TRUE';
      ALLOW_CONNECT='TRUE';
    'VSS'<100>:
      PIN_NUMBER='(0,0,0,0,0,0,0,0,0,0,0,0,BF50,0)';
      PINUSE='GROUND';
      NO_LOAD_CHECK='Both';
      NO_IO_CHECK='Both';
      NO_ASSERT_CHECK='TRUE';
      NO_DIR_CHECK='TRUE';
      ALLOW_CONNECT='TRUE';
    'VSS'<99>:
      PIN_NUMBER='(0,0,0,0,0,0,0,0,0,0,0,0,BF58,0)';
      PINUSE='GROUND';
      NO_LOAD_CHECK='Both';
      NO_IO_CHECK='Both';
      NO_ASSERT_CHECK='TRUE';
      NO_DIR_CHECK='TRUE';
      ALLOW_CONNECT='TRUE';
    'VSS'<98>:
      PIN_NUMBER='(0,0,0,0,0,0,0,0,0,0,0,0,BF61,0)';
      PINUSE='GROUND';
      NO_LOAD_CHECK='Both';
      NO_IO_CHECK='Both';
      NO_ASSERT_CHECK='TRUE';
      NO_DIR_CHECK='TRUE';
      ALLOW_CONNECT='TRUE';
    'VSS'<97>:
      PIN_NUMBER='(0,0,0,0,0,0,0,0,0,0,0,0,BF65,0)';
      PINUSE='GROUND';
      NO_LOAD_CHECK='Both';
      NO_IO_CHECK='Both';
      NO_ASSERT_CHECK='TRUE';
      NO_DIR_CHECK='TRUE';
      ALLOW_CONNECT='TRUE';
    'VSS'<96>:
      PIN_NUMBER='(0,0,0,0,0,0,0,0,0,0,0,0,BF68,0)';
      PINUSE='GROUND';
      NO_LOAD_CHECK='Both';
      NO_IO_CHECK='Both';
      NO_ASSERT_CHECK='TRUE';
      NO_DIR_CHECK='TRUE';
      ALLOW_CONNECT='TRUE';
    'VSS'<95>:
      PIN_NUMBER='(0,0,0,0,0,0,0,0,0,0,0,0,BF9,0)';
      PINUSE='GROUND';
      NO_LOAD_CHECK='Both';
      NO_IO_CHECK='Both';
      NO_ASSERT_CHECK='TRUE';
      NO_DIR_CHECK='TRUE';
      ALLOW_CONNECT='TRUE';
    'VSS'<94>:
      PIN_NUMBER='(0,0,0,0,0,0,0,0,0,0,0,0,BG33,0)';
      PINUSE='GROUND';
      NO_LOAD_CHECK='Both';
      NO_IO_CHECK='Both';
      NO_ASSERT_CHECK='TRUE';
      NO_DIR_CHECK='TRUE';
      ALLOW_CONNECT='TRUE';
    'VSS'<93>:
      PIN_NUMBER='(0,0,0,0,0,0,0,0,0,0,0,0,BG48,0)';
      PINUSE='GROUND';
      NO_LOAD_CHECK='Both';
      NO_IO_CHECK='Both';
      NO_ASSERT_CHECK='TRUE';
      NO_DIR_CHECK='TRUE';
      ALLOW_CONNECT='TRUE';
    'VSS'<92>:
      PIN_NUMBER='(0,0,0,0,0,0,0,0,0,0,0,0,BG59,0)';
      PINUSE='GROUND';
      NO_LOAD_CHECK='Both';
      NO_IO_CHECK='Both';
      NO_ASSERT_CHECK='TRUE';
      NO_DIR_CHECK='TRUE';
      ALLOW_CONNECT='TRUE';
    'VSS'<91>:
      PIN_NUMBER='(0,0,0,0,0,0,0,0,0,0,0,0,BG63,0)';
      PINUSE='GROUND';
      NO_LOAD_CHECK='Both';
      NO_IO_CHECK='Both';
      NO_ASSERT_CHECK='TRUE';
      NO_DIR_CHECK='TRUE';
      ALLOW_CONNECT='TRUE';
    'VSS'<90>:
      PIN_NUMBER='(0,0,0,0,0,0,0,0,0,0,0,0,BH27,0)';
      PINUSE='GROUND';
      NO_LOAD_CHECK='Both';
      NO_IO_CHECK='Both';
      NO_ASSERT_CHECK='TRUE';
      NO_DIR_CHECK='TRUE';
      ALLOW_CONNECT='TRUE';
    'VSS'<89>:
      PIN_NUMBER='(0,0,0,0,0,0,0,0,0,0,0,0,BH38,0)';
      PINUSE='GROUND';
      NO_LOAD_CHECK='Both';
      NO_IO_CHECK='Both';
      NO_ASSERT_CHECK='TRUE';
      NO_DIR_CHECK='TRUE';
      ALLOW_CONNECT='TRUE';
    'VSS'<88>:
      PIN_NUMBER='(0,0,0,0,0,0,0,0,0,0,0,0,BH42,0)';
      PINUSE='GROUND';
      NO_LOAD_CHECK='Both';
      NO_IO_CHECK='Both';
      NO_ASSERT_CHECK='TRUE';
      NO_DIR_CHECK='TRUE';
      ALLOW_CONNECT='TRUE';
    'VSS'<87>:
      PIN_NUMBER='(0,0,0,0,0,0,0,0,0,0,0,0,BH46,0)';
      PINUSE='GROUND';
      NO_LOAD_CHECK='Both';
      NO_IO_CHECK='Both';
      NO_ASSERT_CHECK='TRUE';
      NO_DIR_CHECK='TRUE';
      ALLOW_CONNECT='TRUE';
    'VSS'<86>:
      PIN_NUMBER='(0,0,0,0,0,0,0,0,0,0,0,0,BH54,0)';
      PINUSE='GROUND';
      NO_LOAD_CHECK='Both';
      NO_IO_CHECK='Both';
      NO_ASSERT_CHECK='TRUE';
      NO_DIR_CHECK='TRUE';
      ALLOW_CONNECT='TRUE';
    'VSS'<85>:
      PIN_NUMBER='(0,0,0,0,0,0,0,0,0,0,0,0,BJ1,0)';
      PINUSE='GROUND';
      NO_LOAD_CHECK='Both';
      NO_IO_CHECK='Both';
      NO_ASSERT_CHECK='TRUE';
      NO_DIR_CHECK='TRUE';
      ALLOW_CONNECT='TRUE';
    'VSS'<84>:
      PIN_NUMBER='(0,0,0,0,0,0,0,0,0,0,0,0,BJ11,0)';
      PINUSE='GROUND';
      NO_LOAD_CHECK='Both';
      NO_IO_CHECK='Both';
      NO_ASSERT_CHECK='TRUE';
      NO_DIR_CHECK='TRUE';
      ALLOW_CONNECT='TRUE';
    'VSS'<83>:
      PIN_NUMBER='(0,0,0,0,0,0,0,0,0,0,0,0,BJ5,0)';
      PINUSE='GROUND';
      NO_LOAD_CHECK='Both';
      NO_IO_CHECK='Both';
      NO_ASSERT_CHECK='TRUE';
      NO_DIR_CHECK='TRUE';
      ALLOW_CONNECT='TRUE';
    'VSS'<82>:
      PIN_NUMBER='(0,0,0,0,0,0,0,0,0,0,0,0,BJ7,0)';
      PINUSE='GROUND';
      NO_LOAD_CHECK='Both';
      NO_IO_CHECK='Both';
      NO_ASSERT_CHECK='TRUE';
      NO_DIR_CHECK='TRUE';
      ALLOW_CONNECT='TRUE';
    'VSS'<81>:
      PIN_NUMBER='(0,0,0,0,0,0,0,0,0,0,0,0,BJ15,0)';
      PINUSE='GROUND';
      NO_LOAD_CHECK='Both';
      NO_IO_CHECK='Both';
      NO_ASSERT_CHECK='TRUE';
      NO_DIR_CHECK='TRUE';
      ALLOW_CONNECT='TRUE';
    'VSS'<80>:
      PIN_NUMBER='(0,0,0,0,0,0,0,0,0,0,0,0,BJ18,0)';
      PINUSE='GROUND';
      NO_LOAD_CHECK='Both';
      NO_IO_CHECK='Both';
      NO_ASSERT_CHECK='TRUE';
      NO_DIR_CHECK='TRUE';
      ALLOW_CONNECT='TRUE';
    'VSS'<79>:
      PIN_NUMBER='(0,0,0,0,0,0,0,0,0,0,0,0,BJ26,0)';
      PINUSE='GROUND';
      NO_LOAD_CHECK='Both';
      NO_IO_CHECK='Both';
      NO_ASSERT_CHECK='TRUE';
      NO_DIR_CHECK='TRUE';
      ALLOW_CONNECT='TRUE';
    'VSS'<78>:
      PIN_NUMBER='(0,0,0,0,0,0,0,0,0,0,0,0,BJ3,0)';
      PINUSE='GROUND';
      NO_LOAD_CHECK='Both';
      NO_IO_CHECK='Both';
      NO_ASSERT_CHECK='TRUE';
      NO_DIR_CHECK='TRUE';
      ALLOW_CONNECT='TRUE';
    'VSS'<77>:
      PIN_NUMBER='(0,0,0,0,0,0,0,0,0,0,0,0,BJ33,0)';
      PINUSE='GROUND';
      NO_LOAD_CHECK='Both';
      NO_IO_CHECK='Both';
      NO_ASSERT_CHECK='TRUE';
      NO_DIR_CHECK='TRUE';
      ALLOW_CONNECT='TRUE';
    'VSS'<76>:
      PIN_NUMBER='(0,0,0,0,0,0,0,0,0,0,0,0,BJ52,0)';
      PINUSE='GROUND';
      NO_LOAD_CHECK='Both';
      NO_IO_CHECK='Both';
      NO_ASSERT_CHECK='TRUE';
      NO_DIR_CHECK='TRUE';
      ALLOW_CONNECT='TRUE';
    'VSS'<75>:
      PIN_NUMBER='(0,0,0,0,0,0,0,0,0,0,0,0,BJ68,0)';
      PINUSE='GROUND';
      NO_LOAD_CHECK='Both';
      NO_IO_CHECK='Both';
      NO_ASSERT_CHECK='TRUE';
      NO_DIR_CHECK='TRUE';
      ALLOW_CONNECT='TRUE';
    'VSS'<74>:
      PIN_NUMBER='(0,0,0,0,0,0,0,0,0,0,0,0,0,BK24)';
      PINUSE='GROUND';
      NO_LOAD_CHECK='Both';
      NO_IO_CHECK='Both';
      NO_ASSERT_CHECK='TRUE';
      NO_DIR_CHECK='TRUE';
      ALLOW_CONNECT='TRUE';
    'VSS'<73>:
      PIN_NUMBER='(0,0,0,0,0,0,0,0,0,0,0,0,0,BK27)';
      PINUSE='GROUND';
      NO_LOAD_CHECK='Both';
      NO_IO_CHECK='Both';
      NO_ASSERT_CHECK='TRUE';
      NO_DIR_CHECK='TRUE';
      ALLOW_CONNECT='TRUE';
    'VSS'<72>:
      PIN_NUMBER='(0,0,0,0,0,0,0,0,0,0,0,0,0,BK31)';
      PINUSE='GROUND';
      NO_LOAD_CHECK='Both';
      NO_IO_CHECK='Both';
      NO_ASSERT_CHECK='TRUE';
      NO_DIR_CHECK='TRUE';
      ALLOW_CONNECT='TRUE';
    'VSS'<71>:
      PIN_NUMBER='(0,0,0,0,0,0,0,0,0,0,0,0,0,BK35)';
      PINUSE='GROUND';
      NO_LOAD_CHECK='Both';
      NO_IO_CHECK='Both';
      NO_ASSERT_CHECK='TRUE';
      NO_DIR_CHECK='TRUE';
      ALLOW_CONNECT='TRUE';
    'VSS'<70>:
      PIN_NUMBER='(0,0,0,0,0,0,0,0,0,0,0,0,0,BK38)';
      PINUSE='GROUND';
      NO_LOAD_CHECK='Both';
      NO_IO_CHECK='Both';
      NO_ASSERT_CHECK='TRUE';
      NO_DIR_CHECK='TRUE';
      ALLOW_CONNECT='TRUE';
    'VSS'<69>:
      PIN_NUMBER='(0,0,0,0,0,0,0,0,0,0,0,0,0,BK42)';
      PINUSE='GROUND';
      NO_LOAD_CHECK='Both';
      NO_IO_CHECK='Both';
      NO_ASSERT_CHECK='TRUE';
      NO_DIR_CHECK='TRUE';
      ALLOW_CONNECT='TRUE';
    'VSS'<68>:
      PIN_NUMBER='(0,0,0,0,0,0,0,0,0,0,0,0,0,BK50)';
      PINUSE='GROUND';
      NO_LOAD_CHECK='Both';
      NO_IO_CHECK='Both';
      NO_ASSERT_CHECK='TRUE';
      NO_DIR_CHECK='TRUE';
      ALLOW_CONNECT='TRUE';
    'VSS'<67>:
      PIN_NUMBER='(0,0,0,0,0,0,0,0,0,0,0,0,0,BL22)';
      PINUSE='GROUND';
      NO_LOAD_CHECK='Both';
      NO_IO_CHECK='Both';
      NO_ASSERT_CHECK='TRUE';
      NO_DIR_CHECK='TRUE';
      ALLOW_CONNECT='TRUE';
    'VSS'<66>:
      PIN_NUMBER='(0,0,0,0,0,0,0,0,0,0,0,0,0,BL40)';
      PINUSE='GROUND';
      NO_LOAD_CHECK='Both';
      NO_IO_CHECK='Both';
      NO_ASSERT_CHECK='TRUE';
      NO_DIR_CHECK='TRUE';
      ALLOW_CONNECT='TRUE';
    'VSS'<65>:
      PIN_NUMBER='(0,0,0,0,0,0,0,0,0,0,0,0,0,BL68)';
      PINUSE='GROUND';
      NO_LOAD_CHECK='Both';
      NO_IO_CHECK='Both';
      NO_ASSERT_CHECK='TRUE';
      NO_DIR_CHECK='TRUE';
      ALLOW_CONNECT='TRUE';
    'VSS'<64>:
      PIN_NUMBER='(0,0,0,0,0,0,0,0,0,0,0,0,0,BL37)';
      PINUSE='GROUND';
      NO_LOAD_CHECK='Both';
      NO_IO_CHECK='Both';
      NO_ASSERT_CHECK='TRUE';
      NO_DIR_CHECK='TRUE';
      ALLOW_CONNECT='TRUE';
    'VSS'<63>:
      PIN_NUMBER='(0,0,0,0,0,0,0,0,0,0,0,0,0,BL5)';
      PINUSE='GROUND';
      NO_LOAD_CHECK='Both';
      NO_IO_CHECK='Both';
      NO_ASSERT_CHECK='TRUE';
      NO_DIR_CHECK='TRUE';
      ALLOW_CONNECT='TRUE';
    'VSS'<62>:
      PIN_NUMBER='(0,0,0,0,0,0,0,0,0,0,0,0,0,BL63)';
      PINUSE='GROUND';
      NO_LOAD_CHECK='Both';
      NO_IO_CHECK='Both';
      NO_ASSERT_CHECK='TRUE';
      NO_DIR_CHECK='TRUE';
      ALLOW_CONNECT='TRUE';
    'VSS'<61>:
      PIN_NUMBER='(0,0,0,0,0,0,0,0,0,0,0,0,0,BL70)';
      PINUSE='GROUND';
      NO_LOAD_CHECK='Both';
      NO_IO_CHECK='Both';
      NO_ASSERT_CHECK='TRUE';
      NO_DIR_CHECK='TRUE';
      ALLOW_CONNECT='TRUE';
    'VSS'<60>:
      PIN_NUMBER='(0,0,0,0,0,0,0,0,0,0,0,0,0,BL72)';
      PINUSE='GROUND';
      NO_LOAD_CHECK='Both';
      NO_IO_CHECK='Both';
      NO_ASSERT_CHECK='TRUE';
      NO_DIR_CHECK='TRUE';
      ALLOW_CONNECT='TRUE';
    'VSS'<59>:
      PIN_NUMBER='(0,0,0,0,0,0,0,0,0,0,0,0,0,BM13)';
      PINUSE='GROUND';
      NO_LOAD_CHECK='Both';
      NO_IO_CHECK='Both';
      NO_ASSERT_CHECK='TRUE';
      NO_DIR_CHECK='TRUE';
      ALLOW_CONNECT='TRUE';
    'VSS'<58>:
      PIN_NUMBER='(0,0,0,0,0,0,0,0,0,0,0,0,0,BM17)';
      PINUSE='GROUND';
      NO_LOAD_CHECK='Both';
      NO_IO_CHECK='Both';
      NO_ASSERT_CHECK='TRUE';
      NO_DIR_CHECK='TRUE';
      ALLOW_CONNECT='TRUE';
    'VSS'<57>:
      PIN_NUMBER='(0,0,0,0,0,0,0,0,0,0,0,0,0,BN37)';
      PINUSE='GROUND';
      NO_LOAD_CHECK='Both';
      NO_IO_CHECK='Both';
      NO_ASSERT_CHECK='TRUE';
      NO_DIR_CHECK='TRUE';
      ALLOW_CONNECT='TRUE';
    'VSS'<56>:
      PIN_NUMBER='(0,0,0,0,0,0,0,0,0,0,0,0,0,BM46)';
      PINUSE='GROUND';
      NO_LOAD_CHECK='Both';
      NO_IO_CHECK='Both';
      NO_ASSERT_CHECK='TRUE';
      NO_DIR_CHECK='TRUE';
      ALLOW_CONNECT='TRUE';
    'VSS'<55>:
      PIN_NUMBER='(0,0,0,0,0,0,0,0,0,0,0,0,0,BM50)';
      PINUSE='GROUND';
      NO_LOAD_CHECK='Both';
      NO_IO_CHECK='Both';
      NO_ASSERT_CHECK='TRUE';
      NO_DIR_CHECK='TRUE';
      ALLOW_CONNECT='TRUE';
    'VSS'<54>:
      PIN_NUMBER='(0,0,0,0,0,0,0,0,0,0,0,0,0,BM58)';
      PINUSE='GROUND';
      NO_LOAD_CHECK='Both';
      NO_IO_CHECK='Both';
      NO_ASSERT_CHECK='TRUE';
      NO_DIR_CHECK='TRUE';
      ALLOW_CONNECT='TRUE';
    'VSS'<53>:
      PIN_NUMBER='(0,0,0,0,0,0,0,0,0,0,0,0,0,BM69)';
      PINUSE='GROUND';
      NO_LOAD_CHECK='Both';
      NO_IO_CHECK='Both';
      NO_ASSERT_CHECK='TRUE';
      NO_DIR_CHECK='TRUE';
      ALLOW_CONNECT='TRUE';
    'VSS'<52>:
      PIN_NUMBER='(0,0,0,0,0,0,0,0,0,0,0,0,0,BM71)';
      PINUSE='GROUND';
      NO_LOAD_CHECK='Both';
      NO_IO_CHECK='Both';
      NO_ASSERT_CHECK='TRUE';
      NO_DIR_CHECK='TRUE';
      ALLOW_CONNECT='TRUE';
    'VSS'<51>:
      PIN_NUMBER='(0,0,0,0,0,0,0,0,0,0,0,0,0,BM9)';
      PINUSE='GROUND';
      NO_LOAD_CHECK='Both';
      NO_IO_CHECK='Both';
      NO_ASSERT_CHECK='TRUE';
      NO_DIR_CHECK='TRUE';
      ALLOW_CONNECT='TRUE';
    'VSS'<50>:
      PIN_NUMBER='(0,0,0,0,0,0,0,0,0,0,0,0,0,BN22)';
      PINUSE='GROUND';
      NO_LOAD_CHECK='Both';
      NO_IO_CHECK='Both';
      NO_ASSERT_CHECK='TRUE';
      NO_DIR_CHECK='TRUE';
      ALLOW_CONNECT='TRUE';
    'VSS'<49>:
      PIN_NUMBER='(0,0,0,0,0,0,0,0,0,0,0,0,0,BN59)';
      PINUSE='GROUND';
      NO_LOAD_CHECK='Both';
      NO_IO_CHECK='Both';
      NO_ASSERT_CHECK='TRUE';
      NO_DIR_CHECK='TRUE';
      ALLOW_CONNECT='TRUE';
    'VSS'<48>:
      PIN_NUMBER='(0,0,0,0,0,0,0,0,0,0,0,0,0,BN5)';
      PINUSE='GROUND';
      NO_LOAD_CHECK='Both';
      NO_IO_CHECK='Both';
      NO_ASSERT_CHECK='TRUE';
      NO_DIR_CHECK='TRUE';
      ALLOW_CONNECT='TRUE';
    'VSS'<47>:
      PIN_NUMBER='(0,0,0,0,0,0,0,0,0,0,0,0,0,BN52)';
      PINUSE='GROUND';
      NO_LOAD_CHECK='Both';
      NO_IO_CHECK='Both';
      NO_ASSERT_CHECK='TRUE';
      NO_DIR_CHECK='TRUE';
      ALLOW_CONNECT='TRUE';
    'VSS'<46>:
      PIN_NUMBER='(0,0,0,0,0,0,0,0,0,0,0,0,0,BN66)';
      PINUSE='GROUND';
      NO_LOAD_CHECK='Both';
      NO_IO_CHECK='Both';
      NO_ASSERT_CHECK='TRUE';
      NO_DIR_CHECK='TRUE';
      ALLOW_CONNECT='TRUE';
    'VSS'<45>:
      PIN_NUMBER='(0,0,0,0,0,0,0,0,0,0,0,0,0,BR20)';
      PINUSE='GROUND';
      NO_LOAD_CHECK='Both';
      NO_IO_CHECK='Both';
      NO_ASSERT_CHECK='TRUE';
      NO_DIR_CHECK='TRUE';
      ALLOW_CONNECT='TRUE';
    'VSS'<44>:
      PIN_NUMBER='(0,0,0,0,0,0,0,0,0,0,0,0,0,BR50)';
      PINUSE='GROUND';
      NO_LOAD_CHECK='Both';
      NO_IO_CHECK='Both';
      NO_ASSERT_CHECK='TRUE';
      NO_DIR_CHECK='TRUE';
      ALLOW_CONNECT='TRUE';
    'VSS'<43>:
      PIN_NUMBER='(0,0,0,0,0,0,0,0,0,0,0,0,0,BT8)';
      PINUSE='GROUND';
      NO_LOAD_CHECK='Both';
      NO_IO_CHECK='Both';
      NO_ASSERT_CHECK='TRUE';
      NO_DIR_CHECK='TRUE';
      ALLOW_CONNECT='TRUE';
    'VSS'<42>:
      PIN_NUMBER='(0,0,0,0,0,0,0,0,0,0,0,0,0,BR54)';
      PINUSE='GROUND';
      NO_LOAD_CHECK='Both';
      NO_IO_CHECK='Both';
      NO_ASSERT_CHECK='TRUE';
      NO_DIR_CHECK='TRUE';
      ALLOW_CONNECT='TRUE';
    'VSS'<41>:
      PIN_NUMBER='(0,0,0,0,0,0,0,0,0,0,0,0,0,BR58)';
      PINUSE='GROUND';
      NO_LOAD_CHECK='Both';
      NO_IO_CHECK='Both';
      NO_ASSERT_CHECK='TRUE';
      NO_DIR_CHECK='TRUE';
      ALLOW_CONNECT='TRUE';
    'VSS'<40>:
      PIN_NUMBER='(0,0,0,0,0,0,0,0,0,0,0,0,0,BR6)';
      PINUSE='GROUND';
      NO_LOAD_CHECK='Both';
      NO_IO_CHECK='Both';
      NO_ASSERT_CHECK='TRUE';
      NO_DIR_CHECK='TRUE';
      ALLOW_CONNECT='TRUE';
    'VSS'<39>:
      PIN_NUMBER='(0,0,0,0,0,0,0,0,0,0,0,0,0,BT66)';
      PINUSE='GROUND';
      NO_LOAD_CHECK='Both';
      NO_IO_CHECK='Both';
      NO_ASSERT_CHECK='TRUE';
      NO_DIR_CHECK='TRUE';
      ALLOW_CONNECT='TRUE';
    'VSS'<38>:
      PIN_NUMBER='(0,0,0,0,0,0,0,0,0,0,0,0,0,BU13)';
      PINUSE='GROUND';
      NO_LOAD_CHECK='Both';
      NO_IO_CHECK='Both';
      NO_ASSERT_CHECK='TRUE';
      NO_DIR_CHECK='TRUE';
      ALLOW_CONNECT='TRUE';
    'VSS'<37>:
      PIN_NUMBER='(0,0,0,0,0,0,0,0,0,0,0,0,0,BU11)';
      PINUSE='GROUND';
      NO_LOAD_CHECK='Both';
      NO_IO_CHECK='Both';
      NO_ASSERT_CHECK='TRUE';
      NO_DIR_CHECK='TRUE';
      ALLOW_CONNECT='TRUE';
    'VSS'<36>:
      PIN_NUMBER='(0,0,0,0,0,0,0,0,0,0,0,0,0,BV49)';
      PINUSE='GROUND';
      NO_LOAD_CHECK='Both';
      NO_IO_CHECK='Both';
      NO_ASSERT_CHECK='TRUE';
      NO_DIR_CHECK='TRUE';
      ALLOW_CONNECT='TRUE';
    'VSS'<35>:
      PIN_NUMBER='(0,0,0,0,0,0,0,0,0,0,0,0,0,BU15)';
      PINUSE='GROUND';
      NO_LOAD_CHECK='Both';
      NO_IO_CHECK='Both';
      NO_ASSERT_CHECK='TRUE';
      NO_DIR_CHECK='TRUE';
      ALLOW_CONNECT='TRUE';
    'VSS'<34>:
      PIN_NUMBER='(0,0,0,0,0,0,0,0,0,0,0,0,0,BU18)';
      PINUSE='GROUND';
      NO_LOAD_CHECK='Both';
      NO_IO_CHECK='Both';
      NO_ASSERT_CHECK='TRUE';
      NO_DIR_CHECK='TRUE';
      ALLOW_CONNECT='TRUE';
    'VSS'<33>:
      PIN_NUMBER='(0,0,0,0,0,0,0,0,0,0,0,0,0,BU20)';
      PINUSE='GROUND';
      NO_LOAD_CHECK='Both';
      NO_IO_CHECK='Both';
      NO_ASSERT_CHECK='TRUE';
      NO_DIR_CHECK='TRUE';
      ALLOW_CONNECT='TRUE';
    'VSS'<32>:
      PIN_NUMBER='(0,0,0,0,0,0,0,0,0,0,0,0,0,BU22)';
      PINUSE='GROUND';
      NO_LOAD_CHECK='Both';
      NO_IO_CHECK='Both';
      NO_ASSERT_CHECK='TRUE';
      NO_DIR_CHECK='TRUE';
      ALLOW_CONNECT='TRUE';
    'VSS'<31>:
      PIN_NUMBER='(0,0,0,0,0,0,0,0,0,0,0,0,0,BU24)';
      PINUSE='GROUND';
      NO_LOAD_CHECK='Both';
      NO_IO_CHECK='Both';
      NO_ASSERT_CHECK='TRUE';
      NO_DIR_CHECK='TRUE';
      ALLOW_CONNECT='TRUE';
    'VSS'<30>:
      PIN_NUMBER='(0,0,0,0,0,0,0,0,0,0,0,0,0,BU26)';
      PINUSE='GROUND';
      NO_LOAD_CHECK='Both';
      NO_IO_CHECK='Both';
      NO_ASSERT_CHECK='TRUE';
      NO_DIR_CHECK='TRUE';
      ALLOW_CONNECT='TRUE';
    'VSS'<29>:
      PIN_NUMBER='(0,0,0,0,0,0,0,0,0,0,0,0,0,BU28)';
      PINUSE='GROUND';
      NO_LOAD_CHECK='Both';
      NO_IO_CHECK='Both';
      NO_ASSERT_CHECK='TRUE';
      NO_DIR_CHECK='TRUE';
      ALLOW_CONNECT='TRUE';
    'VSS'<28>:
      PIN_NUMBER='(0,0,0,0,0,0,0,0,0,0,0,0,0,BU30)';
      PINUSE='GROUND';
      NO_LOAD_CHECK='Both';
      NO_IO_CHECK='Both';
      NO_ASSERT_CHECK='TRUE';
      NO_DIR_CHECK='TRUE';
      ALLOW_CONNECT='TRUE';
    'VSS'<27>:
      PIN_NUMBER='(0,0,0,0,0,0,0,0,0,0,0,0,0,BU32)';
      PINUSE='GROUND';
      NO_LOAD_CHECK='Both';
      NO_IO_CHECK='Both';
      NO_ASSERT_CHECK='TRUE';
      NO_DIR_CHECK='TRUE';
      ALLOW_CONNECT='TRUE';
    'VSS'<26>:
      PIN_NUMBER='(0,0,0,0,0,0,0,0,0,0,0,0,0,BU34)';
      PINUSE='GROUND';
      NO_LOAD_CHECK='Both';
      NO_IO_CHECK='Both';
      NO_ASSERT_CHECK='TRUE';
      NO_DIR_CHECK='TRUE';
      ALLOW_CONNECT='TRUE';
    'VSS'<25>:
      PIN_NUMBER='(0,0,0,0,0,0,0,0,0,0,0,0,0,BU37)';
      PINUSE='GROUND';
      NO_LOAD_CHECK='Both';
      NO_IO_CHECK='Both';
      NO_ASSERT_CHECK='TRUE';
      NO_DIR_CHECK='TRUE';
      ALLOW_CONNECT='TRUE';
    'VSS'<24>:
      PIN_NUMBER='(0,0,0,0,0,0,0,0,0,0,0,0,0,BU39)';
      PINUSE='GROUND';
      NO_LOAD_CHECK='Both';
      NO_IO_CHECK='Both';
      NO_ASSERT_CHECK='TRUE';
      NO_DIR_CHECK='TRUE';
      ALLOW_CONNECT='TRUE';
    'VSS'<23>:
      PIN_NUMBER='(0,0,0,0,0,0,0,0,0,0,0,0,0,BU41)';
      PINUSE='GROUND';
      NO_LOAD_CHECK='Both';
      NO_IO_CHECK='Both';
      NO_ASSERT_CHECK='TRUE';
      NO_DIR_CHECK='TRUE';
      ALLOW_CONNECT='TRUE';
    'VSS'<22>:
      PIN_NUMBER='(0,0,0,0,0,0,0,0,0,0,0,0,0,BU43)';
      PINUSE='GROUND';
      NO_LOAD_CHECK='Both';
      NO_IO_CHECK='Both';
      NO_ASSERT_CHECK='TRUE';
      NO_DIR_CHECK='TRUE';
      ALLOW_CONNECT='TRUE';
    'VSS'<21>:
      PIN_NUMBER='(0,0,0,0,0,0,0,0,0,0,0,0,0,BU45)';
      PINUSE='GROUND';
      NO_LOAD_CHECK='Both';
      NO_IO_CHECK='Both';
      NO_ASSERT_CHECK='TRUE';
      NO_DIR_CHECK='TRUE';
      ALLOW_CONNECT='TRUE';
    'VSS'<20>:
      PIN_NUMBER='(0,0,0,0,0,0,0,0,0,0,0,0,0,BU48)';
      PINUSE='GROUND';
      NO_LOAD_CHECK='Both';
      NO_IO_CHECK='Both';
      NO_ASSERT_CHECK='TRUE';
      NO_DIR_CHECK='TRUE';
      ALLOW_CONNECT='TRUE';
    'VSS'<19>:
      PIN_NUMBER='(0,0,0,0,0,0,0,0,0,0,0,0,0,BU50)';
      PINUSE='GROUND';
      NO_LOAD_CHECK='Both';
      NO_IO_CHECK='Both';
      NO_ASSERT_CHECK='TRUE';
      NO_DIR_CHECK='TRUE';
      ALLOW_CONNECT='TRUE';
    'VSS'<18>:
      PIN_NUMBER='(0,0,0,0,0,0,0,0,0,0,0,0,0,BU52)';
      PINUSE='GROUND';
      NO_LOAD_CHECK='Both';
      NO_IO_CHECK='Both';
      NO_ASSERT_CHECK='TRUE';
      NO_DIR_CHECK='TRUE';
      ALLOW_CONNECT='TRUE';
    'VSS'<17>:
      PIN_NUMBER='(0,0,0,0,0,0,0,0,0,0,0,0,0,BU54)';
      PINUSE='GROUND';
      NO_LOAD_CHECK='Both';
      NO_IO_CHECK='Both';
      NO_ASSERT_CHECK='TRUE';
      NO_DIR_CHECK='TRUE';
      ALLOW_CONNECT='TRUE';
    'VSS'<16>:
      PIN_NUMBER='(0,0,0,0,0,0,0,0,0,0,0,0,0,BU57)';
      PINUSE='GROUND';
      NO_LOAD_CHECK='Both';
      NO_IO_CHECK='Both';
      NO_ASSERT_CHECK='TRUE';
      NO_DIR_CHECK='TRUE';
      ALLOW_CONNECT='TRUE';
    'VSS'<15>:
      PIN_NUMBER='(0,0,0,0,0,0,0,0,0,0,0,0,0,BU59)';
      PINUSE='GROUND';
      NO_LOAD_CHECK='Both';
      NO_IO_CHECK='Both';
      NO_ASSERT_CHECK='TRUE';
      NO_DIR_CHECK='TRUE';
      ALLOW_CONNECT='TRUE';
    'VSS'<14>:
      PIN_NUMBER='(0,0,0,0,0,0,0,0,0,0,0,0,0,BU61)';
      PINUSE='GROUND';
      NO_LOAD_CHECK='Both';
      NO_IO_CHECK='Both';
      NO_ASSERT_CHECK='TRUE';
      NO_DIR_CHECK='TRUE';
      ALLOW_CONNECT='TRUE';
    'VSS'<13>:
      PIN_NUMBER='(0,0,0,0,0,0,0,0,0,0,0,0,0,BU63)';
      PINUSE='GROUND';
      NO_LOAD_CHECK='Both';
      NO_IO_CHECK='Both';
      NO_ASSERT_CHECK='TRUE';
      NO_DIR_CHECK='TRUE';
      ALLOW_CONNECT='TRUE';
    'VSS'<12>:
      PIN_NUMBER='(0,0,0,0,0,0,0,0,0,0,0,0,0,BU9)';
      PINUSE='GROUND';
      NO_LOAD_CHECK='Both';
      NO_IO_CHECK='Both';
      NO_ASSERT_CHECK='TRUE';
      NO_DIR_CHECK='TRUE';
      ALLOW_CONNECT='TRUE';
    'VSS'<11>:
      PIN_NUMBER='(0,0,0,0,0,0,0,0,0,0,0,0,0,BV40)';
      PINUSE='GROUND';
      NO_LOAD_CHECK='Both';
      NO_IO_CHECK='Both';
      NO_ASSERT_CHECK='TRUE';
      NO_DIR_CHECK='TRUE';
      ALLOW_CONNECT='TRUE';
    'VSS'<10>:
      PIN_NUMBER='(0,0,0,0,0,0,0,0,0,0,0,0,0,BW15)';
      PINUSE='GROUND';
      NO_LOAD_CHECK='Both';
      NO_IO_CHECK='Both';
      NO_ASSERT_CHECK='TRUE';
      NO_DIR_CHECK='TRUE';
      ALLOW_CONNECT='TRUE';
    'VSS'<9>:
      PIN_NUMBER='(0,0,0,0,0,0,0,0,0,0,0,0,0,BW18)';
      PINUSE='GROUND';
      NO_LOAD_CHECK='Both';
      NO_IO_CHECK='Both';
      NO_ASSERT_CHECK='TRUE';
      NO_DIR_CHECK='TRUE';
      ALLOW_CONNECT='TRUE';
    'VSS'<8>:
      PIN_NUMBER='(0,0,0,0,0,0,0,0,0,0,0,0,0,BW26)';
      PINUSE='GROUND';
      NO_LOAD_CHECK='Both';
      NO_IO_CHECK='Both';
      NO_ASSERT_CHECK='TRUE';
      NO_DIR_CHECK='TRUE';
      ALLOW_CONNECT='TRUE';
    'VSS'<7>:
      PIN_NUMBER='(0,0,0,0,0,0,0,0,0,0,0,0,0,BW52)';
      PINUSE='GROUND';
      NO_LOAD_CHECK='Both';
      NO_IO_CHECK='Both';
      NO_ASSERT_CHECK='TRUE';
      NO_DIR_CHECK='TRUE';
      ALLOW_CONNECT='TRUE';
    'VSS'<6>:
      PIN_NUMBER='(0,0,0,0,0,0,0,0,0,0,0,0,0,BY40)';
      PINUSE='GROUND';
      NO_LOAD_CHECK='Both';
      NO_IO_CHECK='Both';
      NO_ASSERT_CHECK='TRUE';
      NO_DIR_CHECK='TRUE';
      ALLOW_CONNECT='TRUE';
    'VSS'<5>:
      PIN_NUMBER='(0,0,0,0,0,0,0,0,0,0,0,0,0,BY49)';
      PINUSE='GROUND';
      NO_LOAD_CHECK='Both';
      NO_IO_CHECK='Both';
      NO_ASSERT_CHECK='TRUE';
      NO_DIR_CHECK='TRUE';
      ALLOW_CONNECT='TRUE';
    'VSS'<4>:
      PIN_NUMBER='(0,0,0,0,0,0,0,0,0,0,0,0,0,CA15)';
      PINUSE='GROUND';
      NO_LOAD_CHECK='Both';
      NO_IO_CHECK='Both';
      NO_ASSERT_CHECK='TRUE';
      NO_DIR_CHECK='TRUE';
      ALLOW_CONNECT='TRUE';
    'VSS'<3>:
      PIN_NUMBER='(0,0,0,0,0,0,0,0,0,0,0,0,0,CA18)';
      PINUSE='GROUND';
      NO_LOAD_CHECK='Both';
      NO_IO_CHECK='Both';
      NO_ASSERT_CHECK='TRUE';
      NO_DIR_CHECK='TRUE';
      ALLOW_CONNECT='TRUE';
    'VSS'<2>:
      PIN_NUMBER='(0,0,0,0,0,0,0,0,0,0,0,0,0,CA26)';
      PINUSE='GROUND';
      NO_LOAD_CHECK='Both';
      NO_IO_CHECK='Both';
      NO_ASSERT_CHECK='TRUE';
      NO_DIR_CHECK='TRUE';
      ALLOW_CONNECT='TRUE';
    'VSS'<1>:
      PIN_NUMBER='(0,0,0,0,0,0,0,0,0,0,0,0,0,CA50)';
      PINUSE='GROUND';
      NO_LOAD_CHECK='Both';
      NO_IO_CHECK='Both';
      NO_ASSERT_CHECK='TRUE';
      NO_DIR_CHECK='TRUE';
      ALLOW_CONNECT='TRUE';
    'VSS'<0>:
      PIN_NUMBER='(0,0,0,0,0,0,0,0,0,0,0,0,0,CA52)';
      PINUSE='GROUND';
      NO_LOAD_CHECK='Both';
      NO_IO_CHECK='Both';
      NO_ASSERT_CHECK='TRUE';
      NO_DIR_CHECK='TRUE';
      ALLOW_CONNECT='TRUE';
    'WAKE_N':
      PIN_NUMBER='(0,0,0,0,K9,0,0,0,0,0,0,0,0,0)';
      BIDIRECTIONAL='TRUE';
      INPUT_LOAD='(-0.01,0.01)';
      OUTPUT_LOAD='(1.0,-1.0)';
      PINUSE='BI';
    'XCLK_BIASREF':
      PIN_NUMBER='(G44,0,0,0,0,0,0,0,0,0,0,0,0,0)';
      BIDIRECTIONAL='TRUE';
      INPUT_LOAD='(-0.01,0.01)';
      OUTPUT_LOAD='(1.0,-1.0)';
      PINUSE='BI';
    'XTAL_IN':
      PIN_NUMBER='(B35,0,0,0,0,0,0,0,0,0,0,0,0,0)';
      BIDIRECTIONAL='TRUE';
      INPUT_LOAD='(-0.01,0.01)';
      OUTPUT_LOAD='(1.0,-1.0)';
      PINUSE='BI';
    'XTAL_OUT':
      PIN_NUMBER='(D35,0,0,0,0,0,0,0,0,0,0,0,0,0)';
      BIDIRECTIONAL='TRUE';
      INPUT_LOAD='(-0.01,0.01)';
      OUTPUT_LOAD='(1.0,-1.0)';
      PINUSE='BI';
  end_pin;
  body
      PART_NAME='LBG_CORE_QAT_EXT_D';
      PHYS_DES_PREFIX='U';
      ENVCOMP='';
      PART_NUMBER='H91415-002';
      JEDEC_TYPE='BGA1310_5_LBGA';
      DESCRIPTION='(USE SYMBOL 1-14) (Physical with OS SM)Lewisburg NS, new Purl~
ey PCH, pkg. size 34 x 28mm, pitch 0.65mm';
      CLASS='IC';
      COMPONENT_TYPE='BGA';
      HEIGHT='0.102 IN';
      LPID='3403';
      SPEED_URL='http://speed.intel.com:8081/speed/module/pdm/item/pdm_item_deta~
il_direct.asp?item_cde=H91415-002&item_rev=01&url_param=unused';
      STATUS='';
      RPL='';
      AML='';
      BUS_UNIT='';
      DAYS='';
      PARENT_PART_TYPE='LBG_CORE_QAT_EXT_D';
      PARENT_PPT='LBG_CORE_QAT_EXT_D';
      PARENT_PPT_PART='LBG_CORE_QAT_EXT_D_BGA1-IC,H91415-002';
  end_body;
end_primitive;
primitive 'LCMXO2_A_256BGA-IC,H63395-001';
  pin
    'PB3A':
      PIN_NUMBER='(P4,0,0)';
      BIDIRECTIONAL='TRUE';
      INPUT_LOAD='(-0.01,0.01)';
      OUTPUT_LOAD='(1.0,-1.0)';
      PINUSE='BI';
    'PB3B':
      PIN_NUMBER='(T4,0,0)';
      BIDIRECTIONAL='TRUE';
      INPUT_LOAD='(-0.01,0.01)';
      OUTPUT_LOAD='(1.0,-1.0)';
      PINUSE='BI';
    'PB3C':
      PIN_NUMBER='(T2,0,0)';
      BIDIRECTIONAL='TRUE';
      INPUT_LOAD='(-0.01,0.01)';
      OUTPUT_LOAD='(1.0,-1.0)';
      PINUSE='BI';
    'PB3D':
      PIN_NUMBER='(R3,0,0)';
      BIDIRECTIONAL='TRUE';
      INPUT_LOAD='(-0.01,0.01)';
      OUTPUT_LOAD='(1.0,-1.0)';
      PINUSE='BI';
    'PB5A_CSSPIN':
      PIN_NUMBER='(R5,0,0)';
      BIDIRECTIONAL='TRUE';
      INPUT_LOAD='(-0.01,0.01)';
      OUTPUT_LOAD='(1.0,-1.0)';
      PINUSE='BI';
    'PB5B':
      PIN_NUMBER='(P5,0,0)';
      BIDIRECTIONAL='TRUE';
      INPUT_LOAD='(-0.01,0.01)';
      OUTPUT_LOAD='(1.0,-1.0)';
      PINUSE='BI';
    'PB6A':
      PIN_NUMBER='(T5,0,0)';
      BIDIRECTIONAL='TRUE';
      INPUT_LOAD='(-0.01,0.01)';
      OUTPUT_LOAD='(1.0,-1.0)';
      PINUSE='BI';
    'PB6B':
      PIN_NUMBER='(R6,0,0)';
      BIDIRECTIONAL='TRUE';
      INPUT_LOAD='(-0.01,0.01)';
      OUTPUT_LOAD='(1.0,-1.0)';
      PINUSE='BI';
    'PB6C':
      PIN_NUMBER='(T3,0,0)';
      BIDIRECTIONAL='TRUE';
      INPUT_LOAD='(-0.01,0.01)';
      OUTPUT_LOAD='(1.0,-1.0)';
      PINUSE='BI';
    'PB6D':
      PIN_NUMBER='(R4,0,0)';
      BIDIRECTIONAL='TRUE';
      INPUT_LOAD='(-0.01,0.01)';
      OUTPUT_LOAD='(1.0,-1.0)';
      PINUSE='BI';
    'PB8A_MCLK_CCLK':
      PIN_NUMBER='(P6,0,0)';
      BIDIRECTIONAL='TRUE';
      INPUT_LOAD='(-0.01,0.01)';
      OUTPUT_LOAD='(1.0,-1.0)';
      PINUSE='BI';
    'PB8B_SO_SPISO':
      PIN_NUMBER='(T6,0,0)';
      BIDIRECTIONAL='TRUE';
      INPUT_LOAD='(-0.01,0.01)';
      OUTPUT_LOAD='(1.0,-1.0)';
      PINUSE='BI';
    'PB8C':
      PIN_NUMBER='(N6,0,0)';
      BIDIRECTIONAL='TRUE';
      INPUT_LOAD='(-0.01,0.01)';
      OUTPUT_LOAD='(1.0,-1.0)';
      PINUSE='BI';
    'PB8D':
      PIN_NUMBER='(L7,0,0)';
      BIDIRECTIONAL='TRUE';
      INPUT_LOAD='(-0.01,0.01)';
      OUTPUT_LOAD='(1.0,-1.0)';
      PINUSE='BI';
    'PB9A':
      PIN_NUMBER='(R7,0,0)';
      BIDIRECTIONAL='TRUE';
      INPUT_LOAD='(-0.01,0.01)';
      OUTPUT_LOAD='(1.0,-1.0)';
      PINUSE='BI';
    'PB9B':
      PIN_NUMBER='(P7,0,0)';
      BIDIRECTIONAL='TRUE';
      INPUT_LOAD='(-0.01,0.01)';
      OUTPUT_LOAD='(1.0,-1.0)';
      PINUSE='BI';
    'PB9C':
      PIN_NUMBER='(M7,0,0)';
      BIDIRECTIONAL='TRUE';
      INPUT_LOAD='(-0.01,0.01)';
      OUTPUT_LOAD='(1.0,-1.0)';
      PINUSE='BI';
    'PB9D':
      PIN_NUMBER='(N7,0,0)';
      BIDIRECTIONAL='TRUE';
      INPUT_LOAD='(-0.01,0.01)';
      OUTPUT_LOAD='(1.0,-1.0)';
      PINUSE='BI';
    'PB11A_PCLKT2_0':
      PIN_NUMBER='(T7,0,0)';
      BIDIRECTIONAL='TRUE';
      INPUT_LOAD='(-0.01,0.01)';
      OUTPUT_LOAD='(1.0,-1.0)';
      PINUSE='BI';
    'PB11B_PCLKC2_0':
      PIN_NUMBER='(R8,0,0)';
      BIDIRECTIONAL='TRUE';
      INPUT_LOAD='(-0.01,0.01)';
      OUTPUT_LOAD='(1.0,-1.0)';
      PINUSE='BI';
    'PB11C':
      PIN_NUMBER='(M6,0,0)';
      BIDIRECTIONAL='TRUE';
      INPUT_LOAD='(-0.01,0.01)';
      OUTPUT_LOAD='(1.0,-1.0)';
      PINUSE='BI';
    'PB11D':
      PIN_NUMBER='(L8,0,0)';
      BIDIRECTIONAL='TRUE';
      INPUT_LOAD='(-0.01,0.01)';
      OUTPUT_LOAD='(1.0,-1.0)';
      PINUSE='BI';
    'PB12A':
      PIN_NUMBER='(P8,0,0)';
      BIDIRECTIONAL='TRUE';
      INPUT_LOAD='(-0.01,0.01)';
      OUTPUT_LOAD='(1.0,-1.0)';
      PINUSE='BI';
    'PB12B':
      PIN_NUMBER='(T8,0,0)';
      BIDIRECTIONAL='TRUE';
      INPUT_LOAD='(-0.01,0.01)';
      OUTPUT_LOAD='(1.0,-1.0)';
      PINUSE='BI';
    'PB12C':
      PIN_NUMBER='(N8,0,0)';
      BIDIRECTIONAL='TRUE';
      INPUT_LOAD='(-0.01,0.01)';
      OUTPUT_LOAD='(1.0,-1.0)';
      PINUSE='BI';
    'PB12D':
      PIN_NUMBER='(L9,0,0)';
      BIDIRECTIONAL='TRUE';
      INPUT_LOAD='(-0.01,0.01)';
      OUTPUT_LOAD='(1.0,-1.0)';
      PINUSE='BI';
    'PB16A_PCLKT2_1':
      PIN_NUMBER='(T9,0,0)';
      BIDIRECTIONAL='TRUE';
      INPUT_LOAD='(-0.01,0.01)';
      OUTPUT_LOAD='(1.0,-1.0)';
      PINUSE='BI';
    'PB16B_PCLKC2_1':
      PIN_NUMBER='(P9,0,0)';
      BIDIRECTIONAL='TRUE';
      INPUT_LOAD='(-0.01,0.01)';
      OUTPUT_LOAD='(1.0,-1.0)';
      PINUSE='BI';
    'PB16C':
      PIN_NUMBER='(M8,0,0)';
      BIDIRECTIONAL='TRUE';
      INPUT_LOAD='(-0.01,0.01)';
      OUTPUT_LOAD='(1.0,-1.0)';
      PINUSE='BI';
    'PB16D':
      PIN_NUMBER='(N9,0,0)';
      BIDIRECTIONAL='TRUE';
      INPUT_LOAD='(-0.01,0.01)';
      OUTPUT_LOAD='(1.0,-1.0)';
      PINUSE='BI';
    'PB18A':
      PIN_NUMBER='(R9,0,0)';
      BIDIRECTIONAL='TRUE';
      INPUT_LOAD='(-0.01,0.01)';
      OUTPUT_LOAD='(1.0,-1.0)';
      PINUSE='BI';
    'PB18B':
      PIN_NUMBER='(T10,0,0)';
      BIDIRECTIONAL='TRUE';
      INPUT_LOAD='(-0.01,0.01)';
      OUTPUT_LOAD='(1.0,-1.0)';
      PINUSE='BI';
    'PB18C':
      PIN_NUMBER='(M9,0,0)';
      BIDIRECTIONAL='TRUE';
      INPUT_LOAD='(-0.01,0.01)';
      OUTPUT_LOAD='(1.0,-1.0)';
      PINUSE='BI';
    'PB18D':
      PIN_NUMBER='(L10,0,0)';
      BIDIRECTIONAL='TRUE';
      INPUT_LOAD='(-0.01,0.01)';
      OUTPUT_LOAD='(1.0,-1.0)';
      PINUSE='BI';
    'PB19A':
      PIN_NUMBER='(P10,0,0)';
      BIDIRECTIONAL='TRUE';
      INPUT_LOAD='(-0.01,0.01)';
      OUTPUT_LOAD='(1.0,-1.0)';
      PINUSE='BI';
    'PB19B':
      PIN_NUMBER='(R10,0,0)';
      BIDIRECTIONAL='TRUE';
      INPUT_LOAD='(-0.01,0.01)';
      OUTPUT_LOAD='(1.0,-1.0)';
      PINUSE='BI';
    'PB19C':
      PIN_NUMBER='(N10,0,0)';
      BIDIRECTIONAL='TRUE';
      INPUT_LOAD='(-0.01,0.01)';
      OUTPUT_LOAD='(1.0,-1.0)';
      PINUSE='BI';
    'PB19D':
      PIN_NUMBER='(M11,0,0)';
      BIDIRECTIONAL='TRUE';
      INPUT_LOAD='(-0.01,0.01)';
      OUTPUT_LOAD='(1.0,-1.0)';
      PINUSE='BI';
    'PB21A':
      PIN_NUMBER='(T11,0,0)';
      BIDIRECTIONAL='TRUE';
      INPUT_LOAD='(-0.01,0.01)';
      OUTPUT_LOAD='(1.0,-1.0)';
      PINUSE='BI';
    'PB21B':
      PIN_NUMBER='(P11,0,0)';
      BIDIRECTIONAL='TRUE';
      INPUT_LOAD='(-0.01,0.01)';
      OUTPUT_LOAD='(1.0,-1.0)';
      PINUSE='BI';
    'PB21C':
      PIN_NUMBER='(M10,0,0)';
      BIDIRECTIONAL='TRUE';
      INPUT_LOAD='(-0.01,0.01)';
      OUTPUT_LOAD='(1.0,-1.0)';
      PINUSE='BI';
    'PB21D':
      PIN_NUMBER='(N11,0,0)';
      BIDIRECTIONAL='TRUE';
      INPUT_LOAD='(-0.01,0.01)';
      OUTPUT_LOAD='(1.0,-1.0)';
      PINUSE='BI';
    'PB22A':
      PIN_NUMBER='(R11,0,0)';
      BIDIRECTIONAL='TRUE';
      INPUT_LOAD='(-0.01,0.01)';
      OUTPUT_LOAD='(1.0,-1.0)';
      PINUSE='BI';
    'PB22B':
      PIN_NUMBER='(T12,0,0)';
      BIDIRECTIONAL='TRUE';
      INPUT_LOAD='(-0.01,0.01)';
      OUTPUT_LOAD='(1.0,-1.0)';
      PINUSE='BI';
    'PB22C':
      PIN_NUMBER='(R13,0,0)';
      BIDIRECTIONAL='TRUE';
      INPUT_LOAD='(-0.01,0.01)';
      OUTPUT_LOAD='(1.0,-1.0)';
      PINUSE='BI';
    'PB22D':
      PIN_NUMBER='(T14,0,0)';
      BIDIRECTIONAL='TRUE';
      INPUT_LOAD='(-0.01,0.01)';
      OUTPUT_LOAD='(1.0,-1.0)';
      PINUSE='BI';
    'PB24A':
      PIN_NUMBER='(P12,0,0)';
      BIDIRECTIONAL='TRUE';
      INPUT_LOAD='(-0.01,0.01)';
      OUTPUT_LOAD='(1.0,-1.0)';
      PINUSE='BI';
    'PB24B':
      PIN_NUMBER='(T13,0,0)';
      BIDIRECTIONAL='TRUE';
      INPUT_LOAD='(-0.01,0.01)';
      OUTPUT_LOAD='(1.0,-1.0)';
      PINUSE='BI';
    'PB25A_SN':
      PIN_NUMBER='(R12,0,0)';
      BIDIRECTIONAL='TRUE';
      INPUT_LOAD='(-0.01,0.01)';
      OUTPUT_LOAD='(1.0,-1.0)';
      PINUSE='BI';
    'PB25B_SI_SISPI':
      PIN_NUMBER='(P13,0,0)';
      BIDIRECTIONAL='TRUE';
      INPUT_LOAD='(-0.01,0.01)';
      OUTPUT_LOAD='(1.0,-1.0)';
      PINUSE='BI';
    'PB25C':
      PIN_NUMBER='(T15,0,0)';
      BIDIRECTIONAL='TRUE';
      INPUT_LOAD='(-0.01,0.01)';
      OUTPUT_LOAD='(1.0,-1.0)';
      PINUSE='BI';
    'PB25D':
      PIN_NUMBER='(R14,0,0)';
      BIDIRECTIONAL='TRUE';
      INPUT_LOAD='(-0.01,0.01)';
      OUTPUT_LOAD='(1.0,-1.0)';
      PINUSE='BI';
    'PL1A_L_GPLLT_FB':
      PIN_NUMBER='(D3,0,0)';
      BIDIRECTIONAL='TRUE';
      INPUT_LOAD='(-0.01,0.01)';
      OUTPUT_LOAD='(1.0,-1.0)';
      PINUSE='BI';
    'PL1B_L_GPLLC_FB':
      PIN_NUMBER='(D1,0,0)';
      BIDIRECTIONAL='TRUE';
      INPUT_LOAD='(-0.01,0.01)';
      OUTPUT_LOAD='(1.0,-1.0)';
      PINUSE='BI';
    'PL1C':
      PIN_NUMBER='(B1,0,0)';
      BIDIRECTIONAL='TRUE';
      INPUT_LOAD='(-0.01,0.01)';
      OUTPUT_LOAD='(1.0,-1.0)';
      PINUSE='BI';
    'PL1D':
      PIN_NUMBER='(C2,0,0)';
      BIDIRECTIONAL='TRUE';
      INPUT_LOAD='(-0.01,0.01)';
      OUTPUT_LOAD='(1.0,-1.0)';
      PINUSE='BI';
    'PL2A_L_GPLLT_IN':
      PIN_NUMBER='(E2,0,0)';
      BIDIRECTIONAL='TRUE';
      INPUT_LOAD='(-0.01,0.01)';
      OUTPUT_LOAD='(1.0,-1.0)';
      PINUSE='BI';
    'PL2B_L_GPLLC_IN':
      PIN_NUMBER='(E3,0,0)';
      BIDIRECTIONAL='TRUE';
      INPUT_LOAD='(-0.01,0.01)';
      OUTPUT_LOAD='(1.0,-1.0)';
      PINUSE='BI';
    'PL2C':
      PIN_NUMBER='(C1,0,0)';
      BIDIRECTIONAL='TRUE';
      INPUT_LOAD='(-0.01,0.01)';
      OUTPUT_LOAD='(1.0,-1.0)';
      PINUSE='BI';
    'PL2D':
      PIN_NUMBER='(D2,0,0)';
      BIDIRECTIONAL='TRUE';
      INPUT_LOAD='(-0.01,0.01)';
      OUTPUT_LOAD='(1.0,-1.0)';
      PINUSE='BI';
    'PL3A_PCLKT5_0':
      PIN_NUMBER='(E1,0,0)';
      BIDIRECTIONAL='TRUE';
      INPUT_LOAD='(-0.01,0.01)';
      OUTPUT_LOAD='(1.0,-1.0)';
      PINUSE='BI';
    'PL3B_PCLKC5_0':
      PIN_NUMBER='(F2,0,0)';
      BIDIRECTIONAL='TRUE';
      INPUT_LOAD='(-0.01,0.01)';
      OUTPUT_LOAD='(1.0,-1.0)';
      PINUSE='BI';
    'PL3C':
      PIN_NUMBER='(F4,0,0)';
      BIDIRECTIONAL='TRUE';
      INPUT_LOAD='(-0.01,0.01)';
      OUTPUT_LOAD='(1.0,-1.0)';
      PINUSE='BI';
    'PL3D':
      PIN_NUMBER='(G6,0,0)';
      BIDIRECTIONAL='TRUE';
      INPUT_LOAD='(-0.01,0.01)';
      OUTPUT_LOAD='(1.0,-1.0)';
      PINUSE='BI';
    'PL4A':
      PIN_NUMBER='(F3,0,0)';
      BIDIRECTIONAL='TRUE';
      INPUT_LOAD='(-0.01,0.01)';
      OUTPUT_LOAD='(1.0,-1.0)';
      PINUSE='BI';
    'PL4B':
      PIN_NUMBER='(F1,0,0)';
      BIDIRECTIONAL='TRUE';
      INPUT_LOAD='(-0.01,0.01)';
      OUTPUT_LOAD='(1.0,-1.0)';
      PINUSE='BI';
    'PL4C':
      PIN_NUMBER='(G5,0,0)';
      BIDIRECTIONAL='TRUE';
      INPUT_LOAD='(-0.01,0.01)';
      OUTPUT_LOAD='(1.0,-1.0)';
      PINUSE='BI';
    'PL4D':
      PIN_NUMBER='(G4,0,0)';
      BIDIRECTIONAL='TRUE';
      INPUT_LOAD='(-0.01,0.01)';
      OUTPUT_LOAD='(1.0,-1.0)';
      PINUSE='BI';
    'PL5A':
      PIN_NUMBER='(G2,0,0)';
      BIDIRECTIONAL='TRUE';
      INPUT_LOAD='(-0.01,0.01)';
      OUTPUT_LOAD='(1.0,-1.0)';
      PINUSE='BI';
    'PL5B':
      PIN_NUMBER='(G3,0,0)';
      BIDIRECTIONAL='TRUE';
      INPUT_LOAD='(-0.01,0.01)';
      OUTPUT_LOAD='(1.0,-1.0)';
      PINUSE='BI';
    'PL5C':
      PIN_NUMBER='(F5,0,0)';
      BIDIRECTIONAL='TRUE';
      INPUT_LOAD='(-0.01,0.01)';
      OUTPUT_LOAD='(1.0,-1.0)';
      PINUSE='BI';
    'PL5D':
      PIN_NUMBER='(H6,0,0)';
      BIDIRECTIONAL='TRUE';
      INPUT_LOAD='(-0.01,0.01)';
      OUTPUT_LOAD='(1.0,-1.0)';
      PINUSE='BI';
    'PL6A':
      PIN_NUMBER='(G1,0,0)';
      BIDIRECTIONAL='TRUE';
      INPUT_LOAD='(-0.01,0.01)';
      OUTPUT_LOAD='(1.0,-1.0)';
      PINUSE='BI';
    'PL6B':
      PIN_NUMBER='(H2,0,0)';
      BIDIRECTIONAL='TRUE';
      INPUT_LOAD='(-0.01,0.01)';
      OUTPUT_LOAD='(1.0,-1.0)';
      PINUSE='BI';
    'PL6C':
      PIN_NUMBER='(H4,0,0)';
      BIDIRECTIONAL='TRUE';
      INPUT_LOAD='(-0.01,0.01)';
      OUTPUT_LOAD='(1.0,-1.0)';
      PINUSE='BI';
    'PL6D':
      PIN_NUMBER='(J6,0,0)';
      BIDIRECTIONAL='TRUE';
      INPUT_LOAD='(-0.01,0.01)';
      OUTPUT_LOAD='(1.0,-1.0)';
      PINUSE='BI';
    'PL7A':
      PIN_NUMBER='(H3,0,0)';
      BIDIRECTIONAL='TRUE';
      INPUT_LOAD='(-0.01,0.01)';
      OUTPUT_LOAD='(1.0,-1.0)';
      PINUSE='BI';
    'PL7B':
      PIN_NUMBER='(H1,0,0)';
      BIDIRECTIONAL='TRUE';
      INPUT_LOAD='(-0.01,0.01)';
      OUTPUT_LOAD='(1.0,-1.0)';
      PINUSE='BI';
    'PL7C_PCLKT4_0':
      PIN_NUMBER='(J1,0,0)';
      BIDIRECTIONAL='TRUE';
      INPUT_LOAD='(-0.01,0.01)';
      OUTPUT_LOAD='(1.0,-1.0)';
      PINUSE='BI';
    'PL7D_PCLKC4_0':
      PIN_NUMBER='(J3,0,0)';
      BIDIRECTIONAL='TRUE';
      INPUT_LOAD='(-0.01,0.01)';
      OUTPUT_LOAD='(1.0,-1.0)';
      PINUSE='BI';
    'PL9A':
      PIN_NUMBER='(J2,0,0)';
      BIDIRECTIONAL='TRUE';
      INPUT_LOAD='(-0.01,0.01)';
      OUTPUT_LOAD='(1.0,-1.0)';
      PINUSE='BI';
    'PL9B':
      PIN_NUMBER='(K1,0,0)';
      BIDIRECTIONAL='TRUE';
      INPUT_LOAD='(-0.01,0.01)';
      OUTPUT_LOAD='(1.0,-1.0)';
      PINUSE='BI';
    'PL9C':
      PIN_NUMBER='(H5,0,0)';
      BIDIRECTIONAL='TRUE';
      INPUT_LOAD='(-0.01,0.01)';
      OUTPUT_LOAD='(1.0,-1.0)';
      PINUSE='BI';
    'PL9D':
      PIN_NUMBER='(J4,0,0)';
      BIDIRECTIONAL='TRUE';
      INPUT_LOAD='(-0.01,0.01)';
      OUTPUT_LOAD='(1.0,-1.0)';
      PINUSE='BI';
    'PL10A':
      PIN_NUMBER='(K3,0,0)';
      BIDIRECTIONAL='TRUE';
      INPUT_LOAD='(-0.01,0.01)';
      OUTPUT_LOAD='(1.0,-1.0)';
      PINUSE='BI';
    'PL10B':
      PIN_NUMBER='(K2,0,0)';
      BIDIRECTIONAL='TRUE';
      INPUT_LOAD='(-0.01,0.01)';
      OUTPUT_LOAD='(1.0,-1.0)';
      PINUSE='BI';
    'PL10C':
      PIN_NUMBER='(J5,0,0)';
      BIDIRECTIONAL='TRUE';
      INPUT_LOAD='(-0.01,0.01)';
      OUTPUT_LOAD='(1.0,-1.0)';
      PINUSE='BI';
    'PL10D':
      PIN_NUMBER='(K6,0,0)';
      BIDIRECTIONAL='TRUE';
      INPUT_LOAD='(-0.01,0.01)';
      OUTPUT_LOAD='(1.0,-1.0)';
      PINUSE='BI';
    'PL11A':
      PIN_NUMBER='(L1,0,0)';
      BIDIRECTIONAL='TRUE';
      INPUT_LOAD='(-0.01,0.01)';
      OUTPUT_LOAD='(1.0,-1.0)';
      PINUSE='BI';
    'PL11B':
      PIN_NUMBER='(L3,0,0)';
      BIDIRECTIONAL='TRUE';
      INPUT_LOAD='(-0.01,0.01)';
      OUTPUT_LOAD='(1.0,-1.0)';
      PINUSE='BI';
    'PL11C':
      PIN_NUMBER='(K4,0,0)';
      BIDIRECTIONAL='TRUE';
      INPUT_LOAD='(-0.01,0.01)';
      OUTPUT_LOAD='(1.0,-1.0)';
      PINUSE='BI';
    'PL11D':
      PIN_NUMBER='(L5,0,0)';
      BIDIRECTIONAL='TRUE';
      INPUT_LOAD='(-0.01,0.01)';
      OUTPUT_LOAD='(1.0,-1.0)';
      PINUSE='BI';
    'PL12A_PCLKT3_0':
      PIN_NUMBER='(L2,0,0)';
      BIDIRECTIONAL='TRUE';
      INPUT_LOAD='(-0.01,0.01)';
      OUTPUT_LOAD='(1.0,-1.0)';
      PINUSE='BI';
    'PL12B_PCLKC3_0':
      PIN_NUMBER='(M1,0,0)';
      BIDIRECTIONAL='TRUE';
      INPUT_LOAD='(-0.01,0.01)';
      OUTPUT_LOAD='(1.0,-1.0)';
      PINUSE='BI';
    'PL12C':
      PIN_NUMBER='(K5,0,0)';
      BIDIRECTIONAL='TRUE';
      INPUT_LOAD='(-0.01,0.01)';
      OUTPUT_LOAD='(1.0,-1.0)';
      PINUSE='BI';
    'PL12D':
      PIN_NUMBER='(L4,0,0)';
      BIDIRECTIONAL='TRUE';
      INPUT_LOAD='(-0.01,0.01)';
      OUTPUT_LOAD='(1.0,-1.0)';
      PINUSE='BI';
    'PL13A':
      PIN_NUMBER='(M3,0,0)';
      BIDIRECTIONAL='TRUE';
      INPUT_LOAD='(-0.01,0.01)';
      OUTPUT_LOAD='(1.0,-1.0)';
      PINUSE='BI';
    'PL13B':
      PIN_NUMBER='(N1,0,0)';
      BIDIRECTIONAL='TRUE';
      INPUT_LOAD='(-0.01,0.01)';
      OUTPUT_LOAD='(1.0,-1.0)';
      PINUSE='BI';
    'PL13C':
      PIN_NUMBER='(N2,0,0)';
      BIDIRECTIONAL='TRUE';
      INPUT_LOAD='(-0.01,0.01)';
      OUTPUT_LOAD='(1.0,-1.0)';
      PINUSE='BI';
    'PL13D':
      PIN_NUMBER='(P1,0,0)';
      BIDIRECTIONAL='TRUE';
      INPUT_LOAD='(-0.01,0.01)';
      OUTPUT_LOAD='(1.0,-1.0)';
      PINUSE='BI';
    'PL14A':
      PIN_NUMBER='(M2,0,0)';
      BIDIRECTIONAL='TRUE';
      INPUT_LOAD='(-0.01,0.01)';
      OUTPUT_LOAD='(1.0,-1.0)';
      PINUSE='BI';
    'PL14B':
      PIN_NUMBER='(N3,0,0)';
      BIDIRECTIONAL='TRUE';
      INPUT_LOAD='(-0.01,0.01)';
      OUTPUT_LOAD='(1.0,-1.0)';
      PINUSE='BI';
    'PL14C':
      PIN_NUMBER='(R1,0,0)';
      BIDIRECTIONAL='TRUE';
      INPUT_LOAD='(-0.01,0.01)';
      OUTPUT_LOAD='(1.0,-1.0)';
      PINUSE='BI';
    'PL14D':
      PIN_NUMBER='(P2,0,0)';
      BIDIRECTIONAL='TRUE';
      INPUT_LOAD='(-0.01,0.01)';
      OUTPUT_LOAD='(1.0,-1.0)';
      PINUSE='BI';
    'PR1A':
      PIN_NUMBER='(0,D14,0)';
      BIDIRECTIONAL='TRUE';
      INPUT_LOAD='(-0.01,0.01)';
      OUTPUT_LOAD='(1.0,-1.0)';
      PINUSE='BI';
    'PR1B':
      PIN_NUMBER='(0,E15,0)';
      BIDIRECTIONAL='TRUE';
      INPUT_LOAD='(-0.01,0.01)';
      OUTPUT_LOAD='(1.0,-1.0)';
      PINUSE='BI';
    'PR1C':
      PIN_NUMBER='(0,C15,0)';
      BIDIRECTIONAL='TRUE';
      INPUT_LOAD='(-0.01,0.01)';
      OUTPUT_LOAD='(1.0,-1.0)';
      PINUSE='BI';
    'PR1D':
      PIN_NUMBER='(0,B16,0)';
      BIDIRECTIONAL='TRUE';
      INPUT_LOAD='(-0.01,0.01)';
      OUTPUT_LOAD='(1.0,-1.0)';
      PINUSE='BI';
    'PR2A':
      PIN_NUMBER='(0,D16,0)';
      BIDIRECTIONAL='TRUE';
      INPUT_LOAD='(-0.01,0.01)';
      OUTPUT_LOAD='(1.0,-1.0)';
      PINUSE='BI';
    'PR2B':
      PIN_NUMBER='(0,E14,0)';
      BIDIRECTIONAL='TRUE';
      INPUT_LOAD='(-0.01,0.01)';
      OUTPUT_LOAD='(1.0,-1.0)';
      PINUSE='BI';
    'PR2C':
      PIN_NUMBER='(0,C16,0)';
      BIDIRECTIONAL='TRUE';
      INPUT_LOAD='(-0.01,0.01)';
      OUTPUT_LOAD='(1.0,-1.0)';
      PINUSE='BI';
    'PR2D':
      PIN_NUMBER='(0,D15,0)';
      BIDIRECTIONAL='TRUE';
      INPUT_LOAD='(-0.01,0.01)';
      OUTPUT_LOAD='(1.0,-1.0)';
      PINUSE='BI';
    'PR3A':
      PIN_NUMBER='(0,E16,0)';
      BIDIRECTIONAL='TRUE';
      INPUT_LOAD='(-0.01,0.01)';
      OUTPUT_LOAD='(1.0,-1.0)';
      PINUSE='BI';
    'PR3B':
      PIN_NUMBER='(0,F15,0)';
      BIDIRECTIONAL='TRUE';
      INPUT_LOAD='(-0.01,0.01)';
      OUTPUT_LOAD='(1.0,-1.0)';
      PINUSE='BI';
    'PR3C':
      PIN_NUMBER='(0,F13,0)';
      BIDIRECTIONAL='TRUE';
      INPUT_LOAD='(-0.01,0.01)';
      OUTPUT_LOAD='(1.0,-1.0)';
      PINUSE='BI';
    'PR3D':
      PIN_NUMBER='(0,G12,0)';
      BIDIRECTIONAL='TRUE';
      INPUT_LOAD='(-0.01,0.01)';
      OUTPUT_LOAD='(1.0,-1.0)';
      PINUSE='BI';
    'PR4A':
      PIN_NUMBER='(0,F14,0)';
      BIDIRECTIONAL='TRUE';
      INPUT_LOAD='(-0.01,0.01)';
      OUTPUT_LOAD='(1.0,-1.0)';
      PINUSE='BI';
    'PR4B':
      PIN_NUMBER='(0,F16,0)';
      BIDIRECTIONAL='TRUE';
      INPUT_LOAD='(-0.01,0.01)';
      OUTPUT_LOAD='(1.0,-1.0)';
      PINUSE='BI';
    'PR4C':
      PIN_NUMBER='(0,F12,0)';
      BIDIRECTIONAL='TRUE';
      INPUT_LOAD='(-0.01,0.01)';
      OUTPUT_LOAD='(1.0,-1.0)';
      PINUSE='BI';
    'PR4D':
      PIN_NUMBER='(0,G13,0)';
      BIDIRECTIONAL='TRUE';
      INPUT_LOAD='(-0.01,0.01)';
      OUTPUT_LOAD='(1.0,-1.0)';
      PINUSE='BI';
    'PR5A':
      PIN_NUMBER='(0,G15,0)';
      BIDIRECTIONAL='TRUE';
      INPUT_LOAD='(-0.01,0.01)';
      OUTPUT_LOAD='(1.0,-1.0)';
      PINUSE='BI';
    'PR5B':
      PIN_NUMBER='(0,G14,0)';
      BIDIRECTIONAL='TRUE';
      INPUT_LOAD='(-0.01,0.01)';
      OUTPUT_LOAD='(1.0,-1.0)';
      PINUSE='BI';
    'PR5C':
      PIN_NUMBER='(0,G11,0)';
      BIDIRECTIONAL='TRUE';
      INPUT_LOAD='(-0.01,0.01)';
      OUTPUT_LOAD='(1.0,-1.0)';
      PINUSE='BI';
    'PR5D':
      PIN_NUMBER='(0,H12,0)';
      BIDIRECTIONAL='TRUE';
      INPUT_LOAD='(-0.01,0.01)';
      OUTPUT_LOAD='(1.0,-1.0)';
      PINUSE='BI';
    'PR6A':
      PIN_NUMBER='(0,G16,0)';
      BIDIRECTIONAL='TRUE';
      INPUT_LOAD='(-0.01,0.01)';
      OUTPUT_LOAD='(1.0,-1.0)';
      PINUSE='BI';
    'PR6B':
      PIN_NUMBER='(0,H15,0)';
      BIDIRECTIONAL='TRUE';
      INPUT_LOAD='(-0.01,0.01)';
      OUTPUT_LOAD='(1.0,-1.0)';
      PINUSE='BI';
    'PR6C':
      PIN_NUMBER='(0,H13,0)';
      BIDIRECTIONAL='TRUE';
      INPUT_LOAD='(-0.01,0.01)';
      OUTPUT_LOAD='(1.0,-1.0)';
      PINUSE='BI';
    'PR6D':
      PIN_NUMBER='(0,J12,0)';
      BIDIRECTIONAL='TRUE';
      INPUT_LOAD='(-0.01,0.01)';
      OUTPUT_LOAD='(1.0,-1.0)';
      PINUSE='BI';
    'PR7A_PCLKT1_0':
      PIN_NUMBER='(0,H14,0)';
      BIDIRECTIONAL='TRUE';
      INPUT_LOAD='(-0.01,0.01)';
      OUTPUT_LOAD='(1.0,-1.0)';
      PINUSE='BI';
    'PR7B_PCLKC1_0':
      PIN_NUMBER='(0,H16,0)';
      BIDIRECTIONAL='TRUE';
      INPUT_LOAD='(-0.01,0.01)';
      OUTPUT_LOAD='(1.0,-1.0)';
      PINUSE='BI';
    'PR7C':
      PIN_NUMBER='(0,J16,0)';
      BIDIRECTIONAL='TRUE';
      INPUT_LOAD='(-0.01,0.01)';
      OUTPUT_LOAD='(1.0,-1.0)';
      PINUSE='BI';
    'PR7D':
      PIN_NUMBER='(0,J14,0)';
      BIDIRECTIONAL='TRUE';
      INPUT_LOAD='(-0.01,0.01)';
      OUTPUT_LOAD='(1.0,-1.0)';
      PINUSE='BI';
    'PR9A':
      PIN_NUMBER='(0,J15,0)';
      BIDIRECTIONAL='TRUE';
      INPUT_LOAD='(-0.01,0.01)';
      OUTPUT_LOAD='(1.0,-1.0)';
      PINUSE='BI';
    'PR9B':
      PIN_NUMBER='(0,K16,0)';
      BIDIRECTIONAL='TRUE';
      INPUT_LOAD='(-0.01,0.01)';
      OUTPUT_LOAD='(1.0,-1.0)';
      PINUSE='BI';
    'PR9C':
      PIN_NUMBER='(0,H11,0)';
      BIDIRECTIONAL='TRUE';
      INPUT_LOAD='(-0.01,0.01)';
      OUTPUT_LOAD='(1.0,-1.0)';
      PINUSE='BI';
    'PR9D':
      PIN_NUMBER='(0,J13,0)';
      BIDIRECTIONAL='TRUE';
      INPUT_LOAD='(-0.01,0.01)';
      OUTPUT_LOAD='(1.0,-1.0)';
      PINUSE='BI';
    'PR10A':
      PIN_NUMBER='(0,K14,0)';
      BIDIRECTIONAL='TRUE';
      INPUT_LOAD='(-0.01,0.01)';
      OUTPUT_LOAD='(1.0,-1.0)';
      PINUSE='BI';
    'PR10B':
      PIN_NUMBER='(0,K15,0)';
      BIDIRECTIONAL='TRUE';
      INPUT_LOAD='(-0.01,0.01)';
      OUTPUT_LOAD='(1.0,-1.0)';
      PINUSE='BI';
    'PR10C':
      PIN_NUMBER='(0,J11,0)';
      BIDIRECTIONAL='TRUE';
      INPUT_LOAD='(-0.01,0.01)';
      OUTPUT_LOAD='(1.0,-1.0)';
      PINUSE='BI';
    'PR10D':
      PIN_NUMBER='(0,L12,0)';
      BIDIRECTIONAL='TRUE';
      INPUT_LOAD='(-0.01,0.01)';
      OUTPUT_LOAD='(1.0,-1.0)';
      PINUSE='BI';
    'PR11A':
      PIN_NUMBER='(0,L16,0)';
      BIDIRECTIONAL='TRUE';
      INPUT_LOAD='(-0.01,0.01)';
      OUTPUT_LOAD='(1.0,-1.0)';
      PINUSE='BI';
    'PR11B':
      PIN_NUMBER='(0,L14,0)';
      BIDIRECTIONAL='TRUE';
      INPUT_LOAD='(-0.01,0.01)';
      OUTPUT_LOAD='(1.0,-1.0)';
      PINUSE='BI';
    'PR11C':
      PIN_NUMBER='(0,K13,0)';
      BIDIRECTIONAL='TRUE';
      INPUT_LOAD='(-0.01,0.01)';
      OUTPUT_LOAD='(1.0,-1.0)';
      PINUSE='BI';
    'PR11D':
      PIN_NUMBER='(0,K12,0)';
      BIDIRECTIONAL='TRUE';
      INPUT_LOAD='(-0.01,0.01)';
      OUTPUT_LOAD='(1.0,-1.0)';
      PINUSE='BI';
    'PR12A':
      PIN_NUMBER='(0,L15,0)';
      BIDIRECTIONAL='TRUE';
      INPUT_LOAD='(-0.01,0.01)';
      OUTPUT_LOAD='(1.0,-1.0)';
      PINUSE='BI';
    'PR12B':
      PIN_NUMBER='(0,M16,0)';
      BIDIRECTIONAL='TRUE';
      INPUT_LOAD='(-0.01,0.01)';
      OUTPUT_LOAD='(1.0,-1.0)';
      PINUSE='BI';
    'PR12C':
      PIN_NUMBER='(0,K11,0)';
      BIDIRECTIONAL='TRUE';
      INPUT_LOAD='(-0.01,0.01)';
      OUTPUT_LOAD='(1.0,-1.0)';
      PINUSE='BI';
    'PR12D':
      PIN_NUMBER='(0,L13,0)';
      BIDIRECTIONAL='TRUE';
      INPUT_LOAD='(-0.01,0.01)';
      OUTPUT_LOAD='(1.0,-1.0)';
      PINUSE='BI';
    'PR13A':
      PIN_NUMBER='(0,M14,0)';
      BIDIRECTIONAL='TRUE';
      INPUT_LOAD='(-0.01,0.01)';
      OUTPUT_LOAD='(1.0,-1.0)';
      PINUSE='BI';
    'PR13B':
      PIN_NUMBER='(0,M15,0)';
      BIDIRECTIONAL='TRUE';
      INPUT_LOAD='(-0.01,0.01)';
      OUTPUT_LOAD='(1.0,-1.0)';
      PINUSE='BI';
    'PR13C':
      PIN_NUMBER='(0,N15,0)';
      BIDIRECTIONAL='TRUE';
      INPUT_LOAD='(-0.01,0.01)';
      OUTPUT_LOAD='(1.0,-1.0)';
      PINUSE='BI';
    'PR13D':
      PIN_NUMBER='(0,P16,0)';
      BIDIRECTIONAL='TRUE';
      INPUT_LOAD='(-0.01,0.01)';
      OUTPUT_LOAD='(1.0,-1.0)';
      PINUSE='BI';
    'PR14A':
      PIN_NUMBER='(0,N16,0)';
      BIDIRECTIONAL='TRUE';
      INPUT_LOAD='(-0.01,0.01)';
      OUTPUT_LOAD='(1.0,-1.0)';
      PINUSE='BI';
    'PR14B':
      PIN_NUMBER='(0,N14,0)';
      BIDIRECTIONAL='TRUE';
      INPUT_LOAD='(-0.01,0.01)';
      OUTPUT_LOAD='(1.0,-1.0)';
      PINUSE='BI';
    'PR14C':
      PIN_NUMBER='(0,P15,0)';
      BIDIRECTIONAL='TRUE';
      INPUT_LOAD='(-0.01,0.01)';
      OUTPUT_LOAD='(1.0,-1.0)';
      PINUSE='BI';
    'PR14D':
      PIN_NUMBER='(0,R16,0)';
      BIDIRECTIONAL='TRUE';
      INPUT_LOAD='(-0.01,0.01)';
      OUTPUT_LOAD='(1.0,-1.0)';
      PINUSE='BI';
    'PT9A':
      PIN_NUMBER='(0,C4,0)';
      BIDIRECTIONAL='TRUE';
      INPUT_LOAD='(-0.01,0.01)';
      OUTPUT_LOAD='(1.0,-1.0)';
      PINUSE='BI';
    'PT9B':
      PIN_NUMBER='(0,B5,0)';
      BIDIRECTIONAL='TRUE';
      INPUT_LOAD='(-0.01,0.01)';
      OUTPUT_LOAD='(1.0,-1.0)';
      PINUSE='BI';
    'PT9C':
      PIN_NUMBER='(0,B3,0)';
      BIDIRECTIONAL='TRUE';
      INPUT_LOAD='(-0.01,0.01)';
      OUTPUT_LOAD='(1.0,-1.0)';
      PINUSE='BI';
    'PT10A':
      PIN_NUMBER='(0,A4,0)';
      BIDIRECTIONAL='TRUE';
      INPUT_LOAD='(-0.01,0.01)';
      OUTPUT_LOAD='(1.0,-1.0)';
      PINUSE='BI';
    'PT10B':
      PIN_NUMBER='(0,C5,0)';
      BIDIRECTIONAL='TRUE';
      INPUT_LOAD='(-0.01,0.01)';
      OUTPUT_LOAD='(1.0,-1.0)';
      PINUSE='BI';
    'PT11A':
      PIN_NUMBER='(0,A5,0)';
      BIDIRECTIONAL='TRUE';
      INPUT_LOAD='(-0.01,0.01)';
      OUTPUT_LOAD='(1.0,-1.0)';
      PINUSE='BI';
    'PT11B':
      PIN_NUMBER='(0,B6,0)';
      BIDIRECTIONAL='TRUE';
      INPUT_LOAD='(-0.01,0.01)';
      OUTPUT_LOAD='(1.0,-1.0)';
      PINUSE='BI';
    'PT11C':
      PIN_NUMBER='(0,A3,0)';
      BIDIRECTIONAL='TRUE';
      INPUT_LOAD='(-0.01,0.01)';
      OUTPUT_LOAD='(1.0,-1.0)';
      PINUSE='BI';
    'PT11D':
      PIN_NUMBER='(0,B4,0)';
      BIDIRECTIONAL='TRUE';
      INPUT_LOAD='(-0.01,0.01)';
      OUTPUT_LOAD='(1.0,-1.0)';
      PINUSE='BI';
    'PT12A':
      PIN_NUMBER='(0,D6,0)';
      BIDIRECTIONAL='TRUE';
      INPUT_LOAD='(-0.01,0.01)';
      OUTPUT_LOAD='(1.0,-1.0)';
      PINUSE='BI';
    'PT12B':
      PIN_NUMBER='(0,E7,0)';
      BIDIRECTIONAL='TRUE';
      INPUT_LOAD='(-0.01,0.01)';
      OUTPUT_LOAD='(1.0,-1.0)';
      PINUSE='BI';
    'PT12C_TDO':
      PIN_NUMBER='(0,C6,0)';
      BIDIRECTIONAL='TRUE';
      INPUT_LOAD='(-0.01,0.01)';
      OUTPUT_LOAD='(1.0,-1.0)';
      PINUSE='BI';
    'PT12D_TDI':
      PIN_NUMBER='(0,A6,0)';
      BIDIRECTIONAL='TRUE';
      INPUT_LOAD='(-0.01,0.01)';
      OUTPUT_LOAD='(1.0,-1.0)';
      PINUSE='BI';
    'PT13A':
      PIN_NUMBER='(0,B7,0)';
      BIDIRECTIONAL='TRUE';
      INPUT_LOAD='(-0.01,0.01)';
      OUTPUT_LOAD='(1.0,-1.0)';
      PINUSE='BI';
    'PT13B':
      PIN_NUMBER='(0,C7,0)';
      BIDIRECTIONAL='TRUE';
      INPUT_LOAD='(-0.01,0.01)';
      OUTPUT_LOAD='(1.0,-1.0)';
      PINUSE='BI';
    'PT13C':
      PIN_NUMBER='(0,E6,0)';
      BIDIRECTIONAL='TRUE';
      INPUT_LOAD='(-0.01,0.01)';
      OUTPUT_LOAD='(1.0,-1.0)';
      PINUSE='BI';
    'PT13D':
      PIN_NUMBER='(0,D7,0)';
      BIDIRECTIONAL='TRUE';
      INPUT_LOAD='(-0.01,0.01)';
      OUTPUT_LOAD='(1.0,-1.0)';
      PINUSE='BI';
    'PT16A':
      PIN_NUMBER='(0,F7,0)';
      BIDIRECTIONAL='TRUE';
      INPUT_LOAD='(-0.01,0.01)';
      OUTPUT_LOAD='(1.0,-1.0)';
      PINUSE='BI';
    'PT16B':
      PIN_NUMBER='(0,E8,0)';
      BIDIRECTIONAL='TRUE';
      INPUT_LOAD='(-0.01,0.01)';
      OUTPUT_LOAD='(1.0,-1.0)';
      PINUSE='BI';
    'PT16C_TCK':
      PIN_NUMBER='(0,A7,0)';
      BIDIRECTIONAL='TRUE';
      INPUT_LOAD='(-0.01,0.01)';
      OUTPUT_LOAD='(1.0,-1.0)';
      PINUSE='BI';
    'PT16D_TMS':
      PIN_NUMBER='(0,B8,0)';
      BIDIRECTIONAL='TRUE';
      INPUT_LOAD='(-0.01,0.01)';
      OUTPUT_LOAD='(1.0,-1.0)';
      PINUSE='BI';
    'PT17A_PCLKT0_1':
      PIN_NUMBER='(0,C8,0)';
      BIDIRECTIONAL='TRUE';
      INPUT_LOAD='(-0.01,0.01)';
      OUTPUT_LOAD='(1.0,-1.0)';
      PINUSE='BI';
    'PT17B_PCLKC0_1':
      PIN_NUMBER='(0,A8,0)';
      BIDIRECTIONAL='TRUE';
      INPUT_LOAD='(-0.01,0.01)';
      OUTPUT_LOAD='(1.0,-1.0)';
      PINUSE='BI';
    'PT17C':
      PIN_NUMBER='(0,D8,0)';
      BIDIRECTIONAL='TRUE';
      INPUT_LOAD='(-0.01,0.01)';
      OUTPUT_LOAD='(1.0,-1.0)';
      PINUSE='BI';
    'PT17D':
      PIN_NUMBER='(0,E9,0)';
      BIDIRECTIONAL='TRUE';
      INPUT_LOAD='(-0.01,0.01)';
      OUTPUT_LOAD='(1.0,-1.0)';
      PINUSE='BI';
    'PT18A':
      PIN_NUMBER='(0,F8,0)';
      BIDIRECTIONAL='TRUE';
      INPUT_LOAD='(-0.01,0.01)';
      OUTPUT_LOAD='(1.0,-1.0)';
      PINUSE='BI';
    'PT18B':
      PIN_NUMBER='(0,D9,0)';
      BIDIRECTIONAL='TRUE';
      INPUT_LOAD='(-0.01,0.01)';
      OUTPUT_LOAD='(1.0,-1.0)';
      PINUSE='BI';
    'PT18C_SCL_PCLKT0_0':
      PIN_NUMBER='(0,A9,0)';
      BIDIRECTIONAL='TRUE';
      INPUT_LOAD='(-0.01,0.01)';
      OUTPUT_LOAD='(1.0,-1.0)';
      PINUSE='BI';
    'PT18D_SDA_PCLKC0_0':
      PIN_NUMBER='(0,C9,0)';
      BIDIRECTIONAL='TRUE';
      INPUT_LOAD='(-0.01,0.01)';
      OUTPUT_LOAD='(1.0,-1.0)';
      PINUSE='BI';
    'PT19A':
      PIN_NUMBER='(0,B9,0)';
      BIDIRECTIONAL='TRUE';
      INPUT_LOAD='(-0.01,0.01)';
      OUTPUT_LOAD='(1.0,-1.0)';
      PINUSE='BI';
    'PT19B':
      PIN_NUMBER='(0,A10,0)';
      BIDIRECTIONAL='TRUE';
      INPUT_LOAD='(-0.01,0.01)';
      OUTPUT_LOAD='(1.0,-1.0)';
      PINUSE='BI';
    'PT19C':
      PIN_NUMBER='(0,F9,0)';
      BIDIRECTIONAL='TRUE';
      INPUT_LOAD='(-0.01,0.01)';
      OUTPUT_LOAD='(1.0,-1.0)';
      PINUSE='BI';
    'PT19D':
      PIN_NUMBER='(0,E11,0)';
      BIDIRECTIONAL='TRUE';
      INPUT_LOAD='(-0.01,0.01)';
      OUTPUT_LOAD='(1.0,-1.0)';
      PINUSE='BI';
    'PT20A':
      PIN_NUMBER='(0,D10,0)';
      BIDIRECTIONAL='TRUE';
      INPUT_LOAD='(-0.01,0.01)';
      OUTPUT_LOAD='(1.0,-1.0)';
      PINUSE='BI';
    'PT20B':
      PIN_NUMBER='(0,E10,0)';
      BIDIRECTIONAL='TRUE';
      INPUT_LOAD='(-0.01,0.01)';
      OUTPUT_LOAD='(1.0,-1.0)';
      PINUSE='BI';
    'PT20C_JTAGENB':
      PIN_NUMBER='(0,C10,0)';
      BIDIRECTIONAL='TRUE';
      INPUT_LOAD='(-0.01,0.01)';
      OUTPUT_LOAD='(1.0,-1.0)';
      PINUSE='BI';
    'PT20D_PROGRAMN':
      PIN_NUMBER='(0,B10,0)';
      BIDIRECTIONAL='TRUE';
      INPUT_LOAD='(-0.01,0.01)';
      OUTPUT_LOAD='(1.0,-1.0)';
      PINUSE='BI';
    'PT21A':
      PIN_NUMBER='(0,A11,0)';
      BIDIRECTIONAL='TRUE';
      INPUT_LOAD='(-0.01,0.01)';
      OUTPUT_LOAD='(1.0,-1.0)';
      PINUSE='BI';
    'PT21B':
      PIN_NUMBER='(0,C11,0)';
      BIDIRECTIONAL='TRUE';
      INPUT_LOAD='(-0.01,0.01)';
      OUTPUT_LOAD='(1.0,-1.0)';
      PINUSE='BI';
    'PT21C':
      PIN_NUMBER='(0,F10,0)';
      BIDIRECTIONAL='TRUE';
      INPUT_LOAD='(-0.01,0.01)';
      OUTPUT_LOAD='(1.0,-1.0)';
      PINUSE='BI';
    'PT21D':
      PIN_NUMBER='(0,D11,0)';
      BIDIRECTIONAL='TRUE';
      INPUT_LOAD='(-0.01,0.01)';
      OUTPUT_LOAD='(1.0,-1.0)';
      PINUSE='BI';
    'PT22A':
      PIN_NUMBER='(0,B11,0)';
      BIDIRECTIONAL='TRUE';
      INPUT_LOAD='(-0.01,0.01)';
      OUTPUT_LOAD='(1.0,-1.0)';
      PINUSE='BI';
    'PT22B':
      PIN_NUMBER='(0,A12,0)';
      BIDIRECTIONAL='TRUE';
      INPUT_LOAD='(-0.01,0.01)';
      OUTPUT_LOAD='(1.0,-1.0)';
      PINUSE='BI';
    'PT22C':
      PIN_NUMBER='(0,B13,0)';
      BIDIRECTIONAL='TRUE';
      INPUT_LOAD='(-0.01,0.01)';
      OUTPUT_LOAD='(1.0,-1.0)';
      PINUSE='BI';
    'PT22D':
      PIN_NUMBER='(0,A14,0)';
      BIDIRECTIONAL='TRUE';
      INPUT_LOAD='(-0.01,0.01)';
      OUTPUT_LOAD='(1.0,-1.0)';
      PINUSE='BI';
    'PT23A':
      PIN_NUMBER='(0,C12,0)';
      BIDIRECTIONAL='TRUE';
      INPUT_LOAD='(-0.01,0.01)';
      OUTPUT_LOAD='(1.0,-1.0)';
      PINUSE='BI';
    'PT23B':
      PIN_NUMBER='(0,B12,0)';
      BIDIRECTIONAL='TRUE';
      INPUT_LOAD='(-0.01,0.01)';
      OUTPUT_LOAD='(1.0,-1.0)';
      PINUSE='BI';
    'PT24A':
      PIN_NUMBER='(0,B14,0)';
      BIDIRECTIONAL='TRUE';
      INPUT_LOAD='(-0.01,0.01)';
      OUTPUT_LOAD='(1.0,-1.0)';
      PINUSE='BI';
    'PT24B':
      PIN_NUMBER='(0,A15,0)';
      BIDIRECTIONAL='TRUE';
      INPUT_LOAD='(-0.01,0.01)';
      OUTPUT_LOAD='(1.0,-1.0)';
      PINUSE='BI';
    'PT24C_INITN':
      PIN_NUMBER='(0,A13,0)';
      BIDIRECTIONAL='TRUE';
      INPUT_LOAD='(-0.01,0.01)';
      OUTPUT_LOAD='(1.0,-1.0)';
      PINUSE='BI';
    'PT24D_DONE':
      PIN_NUMBER='(0,C13,0)';
      BIDIRECTIONAL='TRUE';
      INPUT_LOAD='(-0.01,0.01)';
      OUTPUT_LOAD='(1.0,-1.0)';
      PINUSE='BI';
    'GND'<0>:
      PIN_NUMBER='(0,0,B2)';
      PINUSE='GROUND';
      NO_LOAD_CHECK='Both';
      NO_IO_CHECK='Both';
      NO_ASSERT_CHECK='TRUE';
      NO_DIR_CHECK='TRUE';
      ALLOW_CONNECT='TRUE';
    'GND'<1>:
      PIN_NUMBER='(0,0,B15)';
      PINUSE='GROUND';
      NO_LOAD_CHECK='Both';
      NO_IO_CHECK='Both';
      NO_ASSERT_CHECK='TRUE';
      NO_DIR_CHECK='TRUE';
      ALLOW_CONNECT='TRUE';
    'GND'<2>:
      PIN_NUMBER='(0,0,C3)';
      PINUSE='GROUND';
      NO_LOAD_CHECK='Both';
      NO_IO_CHECK='Both';
      NO_ASSERT_CHECK='TRUE';
      NO_DIR_CHECK='TRUE';
      ALLOW_CONNECT='TRUE';
    'GND'<3>:
      PIN_NUMBER='(0,0,C14)';
      PINUSE='GROUND';
      NO_LOAD_CHECK='Both';
      NO_IO_CHECK='Both';
      NO_ASSERT_CHECK='TRUE';
      NO_DIR_CHECK='TRUE';
      ALLOW_CONNECT='TRUE';
    'GND'<4>:
      PIN_NUMBER='(0,0,D4)';
      PINUSE='GROUND';
      NO_LOAD_CHECK='Both';
      NO_IO_CHECK='Both';
      NO_ASSERT_CHECK='TRUE';
      NO_DIR_CHECK='TRUE';
      ALLOW_CONNECT='TRUE';
    'GND'<5>:
      PIN_NUMBER='(0,0,D13)';
      PINUSE='GROUND';
      NO_LOAD_CHECK='Both';
      NO_IO_CHECK='Both';
      NO_ASSERT_CHECK='TRUE';
      NO_DIR_CHECK='TRUE';
      ALLOW_CONNECT='TRUE';
    'GND'<6>:
      PIN_NUMBER='(0,0,E5)';
      PINUSE='GROUND';
      NO_LOAD_CHECK='Both';
      NO_IO_CHECK='Both';
      NO_ASSERT_CHECK='TRUE';
      NO_DIR_CHECK='TRUE';
      ALLOW_CONNECT='TRUE';
    'GND'<7>:
      PIN_NUMBER='(0,0,E12)';
      PINUSE='GROUND';
      NO_LOAD_CHECK='Both';
      NO_IO_CHECK='Both';
      NO_ASSERT_CHECK='TRUE';
      NO_DIR_CHECK='TRUE';
      ALLOW_CONNECT='TRUE';
    'GND'<8>:
      PIN_NUMBER='(0,0,F6)';
      PINUSE='GROUND';
      NO_LOAD_CHECK='Both';
      NO_IO_CHECK='Both';
      NO_ASSERT_CHECK='TRUE';
      NO_DIR_CHECK='TRUE';
      ALLOW_CONNECT='TRUE';
    'GND'<9>:
      PIN_NUMBER='(0,0,F11)';
      PINUSE='GROUND';
      NO_LOAD_CHECK='Both';
      NO_IO_CHECK='Both';
      NO_ASSERT_CHECK='TRUE';
      NO_DIR_CHECK='TRUE';
      ALLOW_CONNECT='TRUE';
    'GND'<10>:
      PIN_NUMBER='(0,0,H8)';
      PINUSE='GROUND';
      NO_LOAD_CHECK='Both';
      NO_IO_CHECK='Both';
      NO_ASSERT_CHECK='TRUE';
      NO_DIR_CHECK='TRUE';
      ALLOW_CONNECT='TRUE';
    'GND'<11>:
      PIN_NUMBER='(0,0,H9)';
      PINUSE='GROUND';
      NO_LOAD_CHECK='Both';
      NO_IO_CHECK='Both';
      NO_ASSERT_CHECK='TRUE';
      NO_DIR_CHECK='TRUE';
      ALLOW_CONNECT='TRUE';
    'GND'<12>:
      PIN_NUMBER='(0,0,J8)';
      PINUSE='GROUND';
      NO_LOAD_CHECK='Both';
      NO_IO_CHECK='Both';
      NO_ASSERT_CHECK='TRUE';
      NO_DIR_CHECK='TRUE';
      ALLOW_CONNECT='TRUE';
    'GND'<13>:
      PIN_NUMBER='(0,0,J9)';
      PINUSE='GROUND';
      NO_LOAD_CHECK='Both';
      NO_IO_CHECK='Both';
      NO_ASSERT_CHECK='TRUE';
      NO_DIR_CHECK='TRUE';
      ALLOW_CONNECT='TRUE';
    'GND'<14>:
      PIN_NUMBER='(0,0,L6)';
      PINUSE='GROUND';
      NO_LOAD_CHECK='Both';
      NO_IO_CHECK='Both';
      NO_ASSERT_CHECK='TRUE';
      NO_DIR_CHECK='TRUE';
      ALLOW_CONNECT='TRUE';
    'GND'<15>:
      PIN_NUMBER='(0,0,L11)';
      PINUSE='GROUND';
      NO_LOAD_CHECK='Both';
      NO_IO_CHECK='Both';
      NO_ASSERT_CHECK='TRUE';
      NO_DIR_CHECK='TRUE';
      ALLOW_CONNECT='TRUE';
    'GND'<16>:
      PIN_NUMBER='(0,0,M5)';
      PINUSE='GROUND';
      NO_LOAD_CHECK='Both';
      NO_IO_CHECK='Both';
      NO_ASSERT_CHECK='TRUE';
      NO_DIR_CHECK='TRUE';
      ALLOW_CONNECT='TRUE';
    'GND'<17>:
      PIN_NUMBER='(0,0,M12)';
      PINUSE='GROUND';
      NO_LOAD_CHECK='Both';
      NO_IO_CHECK='Both';
      NO_ASSERT_CHECK='TRUE';
      NO_DIR_CHECK='TRUE';
      ALLOW_CONNECT='TRUE';
    'GND'<18>:
      PIN_NUMBER='(0,0,N4)';
      PINUSE='GROUND';
      NO_LOAD_CHECK='Both';
      NO_IO_CHECK='Both';
      NO_ASSERT_CHECK='TRUE';
      NO_DIR_CHECK='TRUE';
      ALLOW_CONNECT='TRUE';
    'GND'<19>:
      PIN_NUMBER='(0,0,N13)';
      PINUSE='GROUND';
      NO_LOAD_CHECK='Both';
      NO_IO_CHECK='Both';
      NO_ASSERT_CHECK='TRUE';
      NO_DIR_CHECK='TRUE';
      ALLOW_CONNECT='TRUE';
    'GND'<20>:
      PIN_NUMBER='(0,0,P3)';
      PINUSE='GROUND';
      NO_LOAD_CHECK='Both';
      NO_IO_CHECK='Both';
      NO_ASSERT_CHECK='TRUE';
      NO_DIR_CHECK='TRUE';
      ALLOW_CONNECT='TRUE';
    'GND'<21>:
      PIN_NUMBER='(0,0,P14)';
      PINUSE='GROUND';
      NO_LOAD_CHECK='Both';
      NO_IO_CHECK='Both';
      NO_ASSERT_CHECK='TRUE';
      NO_DIR_CHECK='TRUE';
      ALLOW_CONNECT='TRUE';
    'GND'<22>:
      PIN_NUMBER='(0,0,R2)';
      PINUSE='GROUND';
      NO_LOAD_CHECK='Both';
      NO_IO_CHECK='Both';
      NO_ASSERT_CHECK='TRUE';
      NO_DIR_CHECK='TRUE';
      ALLOW_CONNECT='TRUE';
    'GND'<23>:
      PIN_NUMBER='(0,0,R15)';
      PINUSE='GROUND';
      NO_LOAD_CHECK='Both';
      NO_IO_CHECK='Both';
      NO_ASSERT_CHECK='TRUE';
      NO_DIR_CHECK='TRUE';
      ALLOW_CONNECT='TRUE';
    'VCC'<0>:
      PIN_NUMBER='(0,0,A1)';
      PINUSE='POWER';
      NO_LOAD_CHECK='Both';
      NO_IO_CHECK='Both';
      NO_ASSERT_CHECK='TRUE';
      NO_DIR_CHECK='TRUE';
      ALLOW_CONNECT='TRUE';
    'VCC'<1>:
      PIN_NUMBER='(0,0,A16)';
      PINUSE='POWER';
      NO_LOAD_CHECK='Both';
      NO_IO_CHECK='Both';
      NO_ASSERT_CHECK='TRUE';
      NO_DIR_CHECK='TRUE';
      ALLOW_CONNECT='TRUE';
    'VCC'<2>:
      PIN_NUMBER='(0,0,T1)';
      PINUSE='POWER';
      NO_LOAD_CHECK='Both';
      NO_IO_CHECK='Both';
      NO_ASSERT_CHECK='TRUE';
      NO_DIR_CHECK='TRUE';
      ALLOW_CONNECT='TRUE';
    'VCC'<3>:
      PIN_NUMBER='(0,0,T16)';
      PINUSE='POWER';
      NO_LOAD_CHECK='Both';
      NO_IO_CHECK='Both';
      NO_ASSERT_CHECK='TRUE';
      NO_DIR_CHECK='TRUE';
      ALLOW_CONNECT='TRUE';
    'VCC'<4>:
      PIN_NUMBER='(0,0,G7)';
      PINUSE='POWER';
      NO_LOAD_CHECK='Both';
      NO_IO_CHECK='Both';
      NO_ASSERT_CHECK='TRUE';
      NO_DIR_CHECK='TRUE';
      ALLOW_CONNECT='TRUE';
    'VCC'<5>:
      PIN_NUMBER='(0,0,G10)';
      PINUSE='POWER';
      NO_LOAD_CHECK='Both';
      NO_IO_CHECK='Both';
      NO_ASSERT_CHECK='TRUE';
      NO_DIR_CHECK='TRUE';
      ALLOW_CONNECT='TRUE';
    'VCC'<6>:
      PIN_NUMBER='(0,0,K7)';
      PINUSE='POWER';
      NO_LOAD_CHECK='Both';
      NO_IO_CHECK='Both';
      NO_ASSERT_CHECK='TRUE';
      NO_DIR_CHECK='TRUE';
      ALLOW_CONNECT='TRUE';
    'VCC'<7>:
      PIN_NUMBER='(0,0,K10)';
      PINUSE='POWER';
      NO_LOAD_CHECK='Both';
      NO_IO_CHECK='Both';
      NO_ASSERT_CHECK='TRUE';
      NO_DIR_CHECK='TRUE';
      ALLOW_CONNECT='TRUE';
    'VCCIO0'<0>:
      PIN_NUMBER='(0,0,G8)';
      PINUSE='POWER';
      NO_LOAD_CHECK='Both';
      NO_IO_CHECK='Both';
      NO_ASSERT_CHECK='TRUE';
      NO_DIR_CHECK='TRUE';
      ALLOW_CONNECT='TRUE';
    'VCCIO0'<1>:
      PIN_NUMBER='(0,0,D12)';
      PINUSE='POWER';
      NO_LOAD_CHECK='Both';
      NO_IO_CHECK='Both';
      NO_ASSERT_CHECK='TRUE';
      NO_DIR_CHECK='TRUE';
      ALLOW_CONNECT='TRUE';
    'VCCIO0'<2>:
      PIN_NUMBER='(0,0,G9)';
      PINUSE='POWER';
      NO_LOAD_CHECK='Both';
      NO_IO_CHECK='Both';
      NO_ASSERT_CHECK='TRUE';
      NO_DIR_CHECK='TRUE';
      ALLOW_CONNECT='TRUE';
    'VCCIO1'<0>:
      PIN_NUMBER='(0,0,E13)';
      PINUSE='POWER';
      NO_LOAD_CHECK='Both';
      NO_IO_CHECK='Both';
      NO_ASSERT_CHECK='TRUE';
      NO_DIR_CHECK='TRUE';
      ALLOW_CONNECT='TRUE';
    'VCCIO1'<1>:
      PIN_NUMBER='(0,0,H10)';
      PINUSE='POWER';
      NO_LOAD_CHECK='Both';
      NO_IO_CHECK='Both';
      NO_ASSERT_CHECK='TRUE';
      NO_DIR_CHECK='TRUE';
      ALLOW_CONNECT='TRUE';
    'VCCIO1'<2>:
      PIN_NUMBER='(0,0,J10)';
      PINUSE='POWER';
      NO_LOAD_CHECK='Both';
      NO_IO_CHECK='Both';
      NO_ASSERT_CHECK='TRUE';
      NO_DIR_CHECK='TRUE';
      ALLOW_CONNECT='TRUE';
    'VCCIO1'<3>:
      PIN_NUMBER='(0,0,M13)';
      PINUSE='POWER';
      NO_LOAD_CHECK='Both';
      NO_IO_CHECK='Both';
      NO_ASSERT_CHECK='TRUE';
      NO_DIR_CHECK='TRUE';
      ALLOW_CONNECT='TRUE';
    'VCCIO2'<0>:
      PIN_NUMBER='(0,0,K9)';
      PINUSE='POWER';
      NO_LOAD_CHECK='Both';
      NO_IO_CHECK='Both';
      NO_ASSERT_CHECK='TRUE';
      NO_DIR_CHECK='TRUE';
      ALLOW_CONNECT='TRUE';
    'VCCIO2'<1>:
      PIN_NUMBER='(0,0,N12)';
      PINUSE='POWER';
      NO_LOAD_CHECK='Both';
      NO_IO_CHECK='Both';
      NO_ASSERT_CHECK='TRUE';
      NO_DIR_CHECK='TRUE';
      ALLOW_CONNECT='TRUE';
    'VCCIO2'<2>:
      PIN_NUMBER='(0,0,K8)';
      PINUSE='POWER';
      NO_LOAD_CHECK='Both';
      NO_IO_CHECK='Both';
      NO_ASSERT_CHECK='TRUE';
      NO_DIR_CHECK='TRUE';
      ALLOW_CONNECT='TRUE';
    'VCCIO2'<3>:
      PIN_NUMBER='(0,0,N5)';
      PINUSE='POWER';
      NO_LOAD_CHECK='Both';
      NO_IO_CHECK='Both';
      NO_ASSERT_CHECK='TRUE';
      NO_DIR_CHECK='TRUE';
      ALLOW_CONNECT='TRUE';
    'VCCIO4'<0>:
      PIN_NUMBER='(0,0,J7)';
      PINUSE='POWER';
      NO_LOAD_CHECK='Both';
      NO_IO_CHECK='Both';
      NO_ASSERT_CHECK='TRUE';
      NO_DIR_CHECK='TRUE';
      ALLOW_CONNECT='TRUE';
    'VCCIO4'<1>:
      PIN_NUMBER='(0,0,H7)';
      PINUSE='POWER';
      NO_LOAD_CHECK='Both';
      NO_IO_CHECK='Both';
      NO_ASSERT_CHECK='TRUE';
      NO_DIR_CHECK='TRUE';
      ALLOW_CONNECT='TRUE';
    'VCCIO5'<0>:
      PIN_NUMBER='(0,0,E4)';
      PINUSE='POWER';
      NO_LOAD_CHECK='Both';
      NO_IO_CHECK='Both';
      NO_ASSERT_CHECK='TRUE';
      NO_DIR_CHECK='TRUE';
      ALLOW_CONNECT='TRUE';
    'VCCIO0'<3>:
      PIN_NUMBER='(0,0,D5)';
      PINUSE='POWER';
      NO_LOAD_CHECK='Both';
      NO_IO_CHECK='Both';
      NO_ASSERT_CHECK='TRUE';
      NO_DIR_CHECK='TRUE';
      ALLOW_CONNECT='TRUE';
    'NC'<0>:
      PIN_NUMBER='(0,0,A2)';
      PINUSE='NC';
      NO_LOAD_CHECK='Both';
      NO_IO_CHECK='Both';
      NO_ASSERT_CHECK='TRUE';
      NO_DIR_CHECK='TRUE';
      ALLOW_CONNECT='TRUE';
    'VCCIO3'<0>:
      PIN_NUMBER='(0,0,M4)';
      PINUSE='POWER';
      NO_LOAD_CHECK='Both';
      NO_IO_CHECK='Both';
      NO_ASSERT_CHECK='TRUE';
      NO_DIR_CHECK='TRUE';
      ALLOW_CONNECT='TRUE';
  end_pin;
  body
      PART_NAME='LCMXO2_A';
      PHYS_DES_PREFIX='U';
      ENVCOMP='';
      PART_NUMBER='H63395-001';
      JEDEC_TYPE='BGA256_1_8MA';
      CLASS='IC';
      DESCRIPTION='(USE SYM_4-6)IC,PLD,BLANK,256FBGA,LCMXO2,4GRD,3.3V';
      HEIGHT='0.067 IN';
      COMPONENT_TYPE='BGA';
      LPID='3782';
      SPEED_URL='http://speed.intel.com:8081/speed/module/pdm/item/pdm_item_deta~
il_direct.asp?item_cde=H63395-001&item_rev=01&url_param=unused';
      STATUS='';
      RPL='';
      AML='';
      BUS_UNIT='';
      DAYS='';
      PARENT_PART_TYPE='LCMXO2_A_256BGA';
      PARENT_PPT='LCMXO2_A';
      PARENT_PPT_PART='LCMXO2_A_256BGA-IC,H63395-001';
  end_body;
end_primitive;
primitive 'LED_1NC-BLUE,IC,C96565-012';
  pin
    'C':
      PIN_NUMBER='(1)';
      PINUSE='UNSPEC';
      NO_LOAD_CHECK='BOTH';
      NO_IO_CHECK='BOTH';
      ALLOW_CONNECT='TRUE';
    'A':
      PIN_NUMBER='(2)';
      PINUSE='UNSPEC';
      NO_LOAD_CHECK='BOTH';
      NO_IO_CHECK='BOTH';
      ALLOW_CONNECT='TRUE';
  end_pin;
  body
      NC_PINS='(3)';
      PART_NAME='LED';
      PHYS_DES_PREFIX='DS';
      ENVCOMP='YES;YES;UNK;UNK;ok;VLD';
      PART_NUMBER='C96565-012';
      JEDEC_TYPE='SLEDA1208A';
      CLASS='IC';
      DESCRIPTION='LED,3010,SM,BLU,RA,1.00,RD,1';
      HEIGHT='0.045 IN';
      COMPONENT_TYPE='SMTOTHER';
      LEAD_LENGTH='';
      LPID='1793';
      SPEED_URL='http://speed.intel.com:8081/speed/module/pdm/item/pdm_item_deta~
il_direct.asp?item_cde=C96565-012&item_rev=01&url_param=unused';
      STATUS='Design';
      RPL='YES';
      AML='1';
      BUS_UNIT='SMO_BOARDS';
      DAYS='???';
      PARENT_PART_TYPE='LED_1NC';
      PARENT_PPT='LED';
      PARENT_PPT_PART='LED_1NC-BLUE,IC,C96565-012';
  end_body;
end_primitive;
primitive 'LED_1NCLF-GREEN,IC,C96565-011';
  pin
    'C':
      PIN_NUMBER='(1)';
      PINUSE='UNSPEC';
      NO_LOAD_CHECK='BOTH';
      NO_IO_CHECK='BOTH';
      ALLOW_CONNECT='TRUE';
    'A':
      PIN_NUMBER='(2)';
      PINUSE='UNSPEC';
      NO_LOAD_CHECK='BOTH';
      NO_IO_CHECK='BOTH';
      ALLOW_CONNECT='TRUE';
  end_pin;
  body
      NC_PINS='(3)';
      PART_NAME='LED';
      PHYS_DES_PREFIX='DS';
      ENVCOMP='YES;YES;UNK;UNK;ok;VLD';
      PART_NUMBER='C96565-011';
      JEDEC_TYPE='SLEDA1208A';
      CLASS='IC';
      DESCRIPTION='LED,3010,SM,GRN,RA,2.00,RC,1';
      HEIGHT='0.046 IN';
      COMPONENT_TYPE='SMTOTHER';
      LEAD_LENGTH='';
      LPID='1793';
      SPEED_URL='http://speed.intel.com:8081/speed/module/pdm/item/pdm_item_deta~
il_direct.asp?item_cde=C96565-011&item_rev=01&url_param=unused';
      STATUS='Design';
      RPL='YES';
      AML='1';
      BUS_UNIT='SMO_BOARDS';
      DAYS='???';
      PARENT_PART_TYPE='LED_1NCLF';
      PARENT_PPT='LED';
      PARENT_PPT_PART='LED_1NCLF-GREEN,IC,C96565-011';
  end_body;
end_primitive;
primitive 'LED_1NCLF-YELLOW,IC,C96565-003';
  pin
    'C':
      PIN_NUMBER='(1)';
      PINUSE='UNSPEC';
      NO_LOAD_CHECK='BOTH';
      NO_IO_CHECK='BOTH';
      ALLOW_CONNECT='TRUE';
    'A':
      PIN_NUMBER='(2)';
      PINUSE='UNSPEC';
      NO_LOAD_CHECK='BOTH';
      NO_IO_CHECK='BOTH';
      ALLOW_CONNECT='TRUE';
  end_pin;
  body
      NC_PINS='(3)';
      PART_NAME='LED';
      PHYS_DES_PREFIX='DS';
      ENVCOMP='YES;YES;UNK;UNK;ok;VLD';
      PART_NUMBER='C96565-003';
      JEDEC_TYPE='SLEDA1208A';
      CLASS='IC';
      DESCRIPTION='LED,SM,YELLOW,RA,1.00,RD,1';
      HEIGHT='0.045 IN';
      COMPONENT_TYPE='SMTOTHER';
      LEAD_LENGTH='';
      LPID='1793';
      SPEED_URL='http://speed.intel.com:8081/speed/module/pdm/item/pdm_item_deta~
il_direct.asp?item_cde=C96565-003&item_rev=01&url_param=unused';
      STATUS='Design';
      RPL='NO';
      AML='2';
      BUS_UNIT='SMO_BOARDS';
      DAYS='???';
      PARENT_PART_TYPE='LED_1NCLF';
      PARENT_PPT='LED';
      PARENT_PPT_PART='LED_1NCLF-YELLOW,IC,C96565-003';
  end_body;
end_primitive;
primitive 'LED_A1-RED,IC,D14725-005';
  pin
    'C':
      PIN_NUMBER='(2)';
      PINUSE='UNSPEC';
      NO_LOAD_CHECK='BOTH';
      NO_IO_CHECK='BOTH';
      ALLOW_CONNECT='TRUE';
    'A':
      PIN_NUMBER='(1)';
      PINUSE='UNSPEC';
      NO_LOAD_CHECK='BOTH';
      NO_IO_CHECK='BOTH';
      ALLOW_CONNECT='TRUE';
  end_pin;
  body
      PART_NAME='LED';
      PHYS_DES_PREFIX='DS';
      ENVCOMP='YES;YES;YES;UNK;ok;VLD';
      PART_NUMBER='D14725-005';
      JEDEC_TYPE='SLEDR0603A';
      CLASS='IC';
      DESCRIPTION='LED,SM,RED,V,1.00,RC,1';
      HEIGHT='0.033 IN';
      COMPONENT_TYPE='CHIP0603';
      LEAD_LENGTH='';
      LPID='553';
      SPEED_URL='http://speed.intel.com:8081/speed/module/pdm/item/pdm_item_deta~
il_direct.asp?item_cde=D14725-005&item_rev=01&url_param=unused';
      STATUS='Approved';
      RPL='YES';
      AML='2';
      BUS_UNIT='SMO_BOARDS';
      DAYS='56';
      PARENT_PART_TYPE='LED_A1';
      PARENT_PPT='LED';
      PARENT_PPT_PART='LED_A1-RED,IC,D14725-005';
  end_body;
end_primitive;
primitive 'LED_A1LF-GREEN,IC,C97278-010';
  pin
    'C':
      PIN_NUMBER='(2)';
      PINUSE='UNSPEC';
      NO_LOAD_CHECK='BOTH';
      NO_IO_CHECK='BOTH';
      ALLOW_CONNECT='TRUE';
    'A':
      PIN_NUMBER='(1)';
      PINUSE='UNSPEC';
      NO_LOAD_CHECK='BOTH';
      NO_IO_CHECK='BOTH';
      ALLOW_CONNECT='TRUE';
  end_pin;
  body
      PART_NAME='LED';
      PHYS_DES_PREFIX='DS';
      ENVCOMP='YES;YES;UNK;UNK;ok;VLD';
      PART_NUMBER='C97278-010';
      JEDEC_TYPE='SLEDR0805B';
      CLASS='IC';
      DESCRIPTION='LED,2012,SM,GRN,V,1.00,RC,1';
      HEIGHT='0.033 IN';
      COMPONENT_TYPE='CHIP0805';
      LEAD_LENGTH='';
      LPID='557';
      SPEED_URL='http://speed.intel.com:8081/speed/module/pdm/item/pdm_item_deta~
il_direct.asp?item_cde=C97278-010&item_rev=01&url_param=unused';
      STATUS='Design';
      RPL='YES';
      AML='1';
      BUS_UNIT='SMO_BOARDS';
      DAYS='???';
      PARENT_PART_TYPE='LED_A1LF';
      PARENT_PPT='LED';
      PARENT_PPT_PART='LED_A1LF-GREEN,IC,C97278-010';
  end_body;
end_primitive;
primitive 'LED_A1LF-GREEN,IC,D14725-022';
  pin
    'C':
      PIN_NUMBER='(2)';
      PINUSE='UNSPEC';
      NO_LOAD_CHECK='BOTH';
      NO_IO_CHECK='BOTH';
      ALLOW_CONNECT='TRUE';
    'A':
      PIN_NUMBER='(1)';
      PINUSE='UNSPEC';
      NO_LOAD_CHECK='BOTH';
      NO_IO_CHECK='BOTH';
      ALLOW_CONNECT='TRUE';
  end_pin;
  body
      PART_NAME='LED';
      PHYS_DES_PREFIX='DS';
      ENVCOMP='YES;YES;YES;UNK;ok;VLD';
      PART_NUMBER='D14725-022';
      JEDEC_TYPE='SLEDR0603A';
      CLASS='IC';
      DESCRIPTION='LED,1608,SM,GRN,V,1.00,RC,1';
      HEIGHT='0.035 IN';
      COMPONENT_TYPE='CHIP0603';
      LEAD_LENGTH='';
      LPID='553';
      SPEED_URL='http://speed.intel.com:8081/speed/module/pdm/item/pdm_item_deta~
il_direct.asp?item_cde=D14725-022&item_rev=01&url_param=unused';
      STATUS='Conditional';
      RPL='YES';
      AML='3';
      BUS_UNIT='SMO_BOARDS';
      DAYS='???';
      PARENT_PART_TYPE='LED_A1LF';
      PARENT_PPT='LED';
      PARENT_PPT_PART='LED_A1LF-GREEN,IC,D14725-022';
  end_body;
end_primitive;
primitive 'LMV331IDCKRG4-GP_DISCRET-G-LMVA';
  pin
    '+IN':
      PIN_NUMBER='(1)';
      INPUT_LOAD='(-0.01,0.01)';
      PINUSE='IN';
    '-IN':
      PIN_NUMBER='(3)';
      INPUT_LOAD='(-0.01,0.01)';
      PINUSE='IN';
    'OUT':
      PIN_NUMBER='(4)';
      OUTPUT_LOAD='(1.0,-1.0)';
      PINUSE='OUT';
    'VCC':
      PIN_NUMBER='(5)';
      PINUSE='POWER';
      NO_LOAD_CHECK='Both';
      NO_IO_CHECK='Both';
      NO_ASSERT_CHECK='TRUE';
      NO_DIR_CHECK='TRUE';
      ALLOW_CONNECT='TRUE';
    'GND':
      PIN_NUMBER='(2)';
      PINUSE='POWER';
      NO_LOAD_CHECK='Both';
      NO_IO_CHECK='Both';
      NO_ASSERT_CHECK='TRUE';
      NO_DIR_CHECK='TRUE';
      ALLOW_CONNECT='TRUE';
  end_pin;
  body
      PART_NAME='LMV331IDCKRG4-GP';
      BODY_NAME='LMV331IDCKRG4-GP';
      PHYS_DES_PREFIX='U';
      CLASS='DISCRETE';
      DESCRIPTION='IC V.R LMV331IDCKRG4 SC-70 5P';
      JEDEC_TYPE='SC70-5H44';
      PARENT_PART_TYPE='LMV331IDCKRG4-GP';
      PARENT_PPT='LMV331IDCKRG4-GP';
      PARENT_PPT_PART='LMV331IDCKRG4-GP_DISCRET-G-LMV331IDCKRG4-GP,74.00331.A2F';
  end_body;
end_primitive;
primitive 'LMV431AIMFX-GP_DISCRET-G5-LMV4A';
  pin
    'REF':
      PIN_NUMBER='(1)';
      PIN_TYPE='ANALOG';
      NO_LOAD_CHECK='Both';
      NO_IO_CHECK='Both';
      NO_ASSERT_CHECK='TRUE';
      NO_DIR_CHECK='TRUE';
      ALLOW_CONNECT='TRUE';
      PINUSE='UNSPEC';
    'CATHODE':
      PIN_NUMBER='(2)';
      PIN_TYPE='ANALOG';
      NO_LOAD_CHECK='Both';
      NO_IO_CHECK='Both';
      NO_ASSERT_CHECK='TRUE';
      NO_DIR_CHECK='TRUE';
      ALLOW_CONNECT='TRUE';
      PINUSE='UNSPEC';
    'ANODE':
      PIN_NUMBER='(3)';
      PIN_TYPE='ANALOG';
      NO_LOAD_CHECK='Both';
      NO_IO_CHECK='Both';
      NO_ASSERT_CHECK='TRUE';
      NO_DIR_CHECK='TRUE';
      ALLOW_CONNECT='TRUE';
      PINUSE='UNSPEC';
  end_pin;
  body
      PART_NAME='LMV431AIMFX-GP';
      BODY_NAME='LMV431AIMFX-GP';
      PHYS_DES_PREFIX='U';
      CLASS='IC';
      DESCRIPTION='IC A.R LMV431AIMFX 1% SOT23-3';
      JEDEC_TYPE='SOT-23-1H45';
      PARENT_PART_TYPE='LMV431AIMFX-GP';
      PARENT_PPT='LMV431AIMFX-GP';
      PARENT_PPT_PART='LMV431AIMFX-GP_DISCRET-G5-LMV431AIMFX-GP,74.MV431.031';
  end_body;
end_primitive;
primitive 'LOTES-CON4-S1-GP_CONN-G7-LOTESA';
  pin
    '1':
      PIN_NUMBER='(1)';
      PIN_TYPE='ANALOG';
      NO_LOAD_CHECK='Both';
      NO_IO_CHECK='Both';
      NO_ASSERT_CHECK='TRUE';
      NO_DIR_CHECK='TRUE';
      ALLOW_CONNECT='TRUE';
      PINUSE='UNSPEC';
    '2':
      PIN_NUMBER='(2)';
      PIN_TYPE='ANALOG';
      NO_LOAD_CHECK='Both';
      NO_IO_CHECK='Both';
      NO_ASSERT_CHECK='TRUE';
      NO_DIR_CHECK='TRUE';
      ALLOW_CONNECT='TRUE';
      PINUSE='UNSPEC';
    '3':
      PIN_NUMBER='(3)';
      PIN_TYPE='ANALOG';
      NO_LOAD_CHECK='Both';
      NO_IO_CHECK='Both';
      NO_ASSERT_CHECK='TRUE';
      NO_DIR_CHECK='TRUE';
      ALLOW_CONNECT='TRUE';
      PINUSE='UNSPEC';
    '4':
      PIN_NUMBER='(4)';
      PIN_TYPE='ANALOG';
      NO_LOAD_CHECK='Both';
      NO_IO_CHECK='Both';
      NO_ASSERT_CHECK='TRUE';
      NO_DIR_CHECK='TRUE';
      ALLOW_CONNECT='TRUE';
      PINUSE='UNSPEC';
    'NP1':
      PIN_NUMBER='(NP1)';
      PIN_TYPE='ANALOG';
      NO_LOAD_CHECK='Both';
      NO_IO_CHECK='Both';
      NO_ASSERT_CHECK='TRUE';
      NO_DIR_CHECK='TRUE';
      ALLOW_CONNECT='TRUE';
      PINUSE='UNSPEC';
  end_pin;
  body
      PART_NAME='LOTES-CON4-S1-GP';
      BODY_NAME='LOTES-CON4-S1-GP';
      PHYS_DES_PREFIX='CN';
      CLASS='DISCRETE';
      DESCRIPTION='HEAD ML 1R4P ST APHD0020-P001E';
      JEDEC_TYPE='ABA-PHD-054-K05';
      PARENT_PART_TYPE='LOTES-CON4-S1-GP';
      PARENT_PPT='LOTES-CON4-S1-GP';
      PARENT_PPT_PART='LOTES-CON4-S1-GP_CONN-G7-LOTES-CON4-S1-GP,021.60521.0104';
  end_body;
end_primitive;
primitive 'M25PE16_SM-IC,H77797-001';
  pin
    'S_N':
      PIN_NUMBER='(1)';
      INPUT_LOAD='(-0.01,0.01)';
      PINUSE='IN';
    'RESET_N':
      PIN_NUMBER='(7)';
      INPUT_LOAD='(-0.01,0.01)';
      PINUSE='IN';
    'C':
      PIN_NUMBER='(6)';
      INPUT_LOAD='(-0.01,0.01)';
      PINUSE='IN';
    'DQ0':
      PIN_NUMBER='(5)';
      INPUT_LOAD='(-0.01,0.01)';
      PINUSE='IN';
    'DQ1':
      PIN_NUMBER='(2)';
      OUTPUT_LOAD='(1.0,-1.0)';
      PINUSE='OUT';
    'VCC':
      PIN_NUMBER='(8)';
      PINUSE='POWER';
      NO_LOAD_CHECK='Both';
      NO_IO_CHECK='Both';
      NO_ASSERT_CHECK='TRUE';
      NO_DIR_CHECK='TRUE';
      ALLOW_CONNECT='TRUE';
    'VSS':
      PIN_NUMBER='(4)';
      PINUSE='GROUND';
      NO_LOAD_CHECK='Both';
      NO_IO_CHECK='Both';
      NO_ASSERT_CHECK='TRUE';
      NO_DIR_CHECK='TRUE';
      ALLOW_CONNECT='TRUE';
    'W_N':
      PIN_NUMBER='(3)';
      INPUT_LOAD='(-0.01,0.01)';
      PINUSE='IN';
  end_pin;
  body
      PART_NAME='M25PE16';
      PHYS_DES_PREFIX='U';
      ENVCOMP='';
      PART_NUMBER='H77797-001';
      JEDEC_TYPE='SOI8_20_50IA';
      DESCRIPTION='IC,FLASH,SPI SERIAL FLASH,SOIC,8,16 MBIT';
      CLASS='IC';
      COMPONENT_TYPE='SOIC';
      HEIGHT='0.085 IN';
      LPID='323';
      SPEED_URL='http://speed.intel.com:8081/speed/module/pdm/item/pdm_item_deta~
il_direct.asp?item_cde=H77797-001&item_rev=01&url_param=unused';
      STATUS='';
      RPL='';
      AML='';
      BUS_UNIT='';
      DAYS='';
      PARENT_PART_TYPE='M25PE16_SM';
      PARENT_PPT='M25PE16';
      PARENT_PPT_PART='M25PE16_SM-IC,H77797-001';
  end_body;
end_primitive;
primitive 'MAX4564EKA-GP_SCRET-GC1-MAX456A';
  pin
    'NC':
      PIN_NUMBER='(1)';
      PIN_TYPE='ANALOG';
      NO_LOAD_CHECK='Both';
      NO_IO_CHECK='Both';
      NO_ASSERT_CHECK='TRUE';
      NO_DIR_CHECK='TRUE';
      ALLOW_CONNECT='TRUE';
      PINUSE='UNSPEC';
    'V+':
      PIN_NUMBER='(2)';
      PINUSE='POWER';
      NO_LOAD_CHECK='Both';
      NO_IO_CHECK='Both';
      NO_ASSERT_CHECK='TRUE';
      NO_DIR_CHECK='TRUE';
      ALLOW_CONNECT='TRUE';
    'IN':
      PIN_NUMBER='(3)';
      INPUT_LOAD='(-0.01,0.01)';
      PINUSE='IN';
    'NO':
      PIN_NUMBER='(4)';
      PIN_TYPE='ANALOG';
      NO_LOAD_CHECK='Both';
      NO_IO_CHECK='Both';
      NO_ASSERT_CHECK='TRUE';
      NO_DIR_CHECK='TRUE';
      ALLOW_CONNECT='TRUE';
      PINUSE='UNSPEC';
    'GND':
      PIN_NUMBER='(5)';
      PINUSE='POWER';
      NO_LOAD_CHECK='Both';
      NO_IO_CHECK='Both';
      NO_ASSERT_CHECK='TRUE';
      NO_DIR_CHECK='TRUE';
      ALLOW_CONNECT='TRUE';
    'V-':
      PIN_NUMBER='(6)';
      PINUSE='POWER';
      NO_LOAD_CHECK='Both';
      NO_IO_CHECK='Both';
      NO_ASSERT_CHECK='TRUE';
      NO_DIR_CHECK='TRUE';
      ALLOW_CONNECT='TRUE';
    'EN#':
      PIN_NUMBER='(7)';
      PIN_TYPE='ANALOG';
      NO_LOAD_CHECK='Both';
      NO_IO_CHECK='Both';
      NO_ASSERT_CHECK='TRUE';
      NO_DIR_CHECK='TRUE';
      ALLOW_CONNECT='TRUE';
      PINUSE='UNSPEC';
    'COM':
      PIN_NUMBER='(8)';
      PIN_TYPE='ANALOG';
      NO_LOAD_CHECK='Both';
      NO_IO_CHECK='Both';
      NO_ASSERT_CHECK='TRUE';
      NO_DIR_CHECK='TRUE';
      ALLOW_CONNECT='TRUE';
      PINUSE='UNSPEC';
  end_pin;
  body
      PART_NAME='MAX4564EKA-GP';
      BODY_NAME='MAX4564EKA-GP';
      PHYS_DES_PREFIX='U';
      CLASS='IC';
      DESCRIPTION='IC ANALOG SWITCH MAX4564EKA+ SOT23 8PIN';
      JEDEC_TYPE='SOT23-8PH58';
      PARENT_PART_TYPE='MAX4564EKA-GP';
      PARENT_PPT='MAX4564EKA-GP';
      PARENT_PPT_PART='MAX4564EKA-GP_SCRET-GC1-MAX4564EKA-GP,074.04564.0099';
  end_body;
end_primitive;
primitive 'MIC5166_DFN-IC,H55101-001';
  pin
    'EN':
      PIN_NUMBER='(7)';
      INPUT_LOAD='(-0.01,0.01)';
      PINUSE='IN';
    'VIN':
      PIN_NUMBER='(10)';
      PINUSE='POWER';
      NO_LOAD_CHECK='Both';
      NO_IO_CHECK='Both';
      NO_ASSERT_CHECK='TRUE';
      NO_DIR_CHECK='TRUE';
      ALLOW_CONNECT='TRUE';
    'VREF':
      PIN_NUMBER='(1)';
      OUTPUT_LOAD='(1.0,-1.0)';
      PINUSE='OUT';
    'BIAS':
      PIN_NUMBER='(2)';
      BIDIRECTIONAL='TRUE';
      INPUT_LOAD='(-0.01,0.01)';
      OUTPUT_LOAD='(1.0,-1.0)';
      PINUSE='BI';
    'AGND':
      PIN_NUMBER='(3)';
      PINUSE='GROUND';
      NO_LOAD_CHECK='Both';
      NO_IO_CHECK='Both';
      NO_ASSERT_CHECK='TRUE';
      NO_DIR_CHECK='TRUE';
      ALLOW_CONNECT='TRUE';
    'PG':
      PIN_NUMBER='(5)';
      OUTPUT_LOAD='(1.0,-1.0)';
      PINUSE='OUT';
    'VDDQ':
      PIN_NUMBER='(4)';
      PINUSE='POWER';
      NO_LOAD_CHECK='Both';
      NO_IO_CHECK='Both';
      NO_ASSERT_CHECK='TRUE';
      NO_DIR_CHECK='TRUE';
      ALLOW_CONNECT='TRUE';
    'SNS':
      PIN_NUMBER='(6)';
      INPUT_LOAD='(-0.01,0.01)';
      PINUSE='IN';
    'PGND':
      PIN_NUMBER='(8)';
      PINUSE='GROUND';
      NO_LOAD_CHECK='Both';
      NO_IO_CHECK='Both';
      NO_ASSERT_CHECK='TRUE';
      NO_DIR_CHECK='TRUE';
      ALLOW_CONNECT='TRUE';
    'VTT':
      PIN_NUMBER='(9)';
      OUTPUT_LOAD='(1.0,-1.0)';
      PINUSE='OUT';
    'THPAD':
      PIN_NUMBER='(11)';
      PINUSE='GROUND';
      NO_LOAD_CHECK='Both';
      NO_IO_CHECK='Both';
      NO_ASSERT_CHECK='TRUE';
      NO_DIR_CHECK='TRUE';
      ALLOW_CONNECT='TRUE';
  end_pin;
  body
      PART_NAME='MIC5166';
      BODY_NAME='MIC5166';
      PHYS_DES_PREFIX='EU';
      ENVCOMP='';
      PART_NUMBER='H55101-001';
      JEDEC_TYPE='DFN10_12_50MF';
      CLASS='IC';
      DESCRIPTION='IC,LIN,MLF,MIC5166,VREG';
      HEIGHT='0.035 IN';
      COMPONENT_TYPE='LCC';
      LPID='3373';
      SPEED_URL='http://speed.intel.com:8081/speed/module/pdm/item/pdm_item_deta~
il_direct.asp?item_cde=H55101-001&item_rev=01&url_param=unused';
      STATUS='';
      RPL='';
      AML='';
      BUS_UNIT='';
      DAYS='';
      PARENT_PART_TYPE='MIC5166_DFN';
      PARENT_PPT='MIC5166';
      PARENT_PPT_PART='MIC5166_DFN-IC,H55101-001';
  end_body;
end_primitive;
primitive 'MOSFETN_1D3S_SOT5-IC,G68777-001';
  pin
    'S1':
      PIN_NUMBER='(1)';
      PINUSE='UNSPEC';
      NO_LOAD_CHECK='BOTH';
      NO_IO_CHECK='BOTH';
      ALLOW_CONNECT='TRUE';
    'S2':
      PIN_NUMBER='(2)';
      PINUSE='UNSPEC';
      NO_LOAD_CHECK='BOTH';
      NO_IO_CHECK='BOTH';
      ALLOW_CONNECT='TRUE';
    'S3':
      PIN_NUMBER='(3)';
      PINUSE='UNSPEC';
      NO_LOAD_CHECK='BOTH';
      NO_IO_CHECK='BOTH';
      ALLOW_CONNECT='TRUE';
    'D':
      PIN_NUMBER='(5)';
      PINUSE='UNSPEC';
      NO_LOAD_CHECK='BOTH';
      NO_IO_CHECK='BOTH';
      ALLOW_CONNECT='TRUE';
    'G':
      PIN_NUMBER='(4)';
      INPUT_LOAD='(-0.01,0.01)';
      PINUSE='IN';
  end_pin;
  body
      PART_NAME='MOSFETN_1D3S';
      PHYS_DES_PREFIX='EU';
      ENVCOMP='Y/E;Y/E;YES;UNK;ok;VLD';
      PART_NUMBER='G68777-001';
      JEDEC_TYPE='SOT669A';
      CLASS='IC';
      DESCRIPTION='IC,DS,FET N,LFPAK,PH0925CL';
      HEIGHT='0.047 IN';
      COMPONENT_TYPE='SMTOTHER';
      LPID='2457';
      SPEED_URL='http://speed.intel.com:8081/speed/module/pdm/item/pdm_item_deta~
il_direct.asp?item_cde=G68777-001&item_rev=01&url_param=unused';
      STATUS='Design';
      RPL='NO';
      AML='1';
      BUS_UNIT='SMO_IC';
      DAYS='???';
      PARENT_PART_TYPE='MOSFETN_1D3S_SOT5';
      PARENT_PPT='MOSFETN_1D3S';
      PARENT_PPT_PART='MOSFETN_1D3S_SOT5-IC,G68777-001';
  end_body;
end_primitive;
primitive 'MOSFET_N_LCC3-BSZ019N03LS,NFETA';
  pin
    'GATE':
      PIN_NUMBER='(4)';
      PINUSE='UNSPEC';
      NO_LOAD_CHECK='BOTH';
      NO_IO_CHECK='BOTH';
      ALLOW_CONNECT='TRUE';
    'SRC':
      PIN_NUMBER='(1)';
      PINUSE='UNSPEC';
      NO_LOAD_CHECK='BOTH';
      NO_IO_CHECK='BOTH';
      ALLOW_CONNECT='TRUE';
    'DRN':
      PIN_NUMBER='(5)';
      PINUSE='UNSPEC';
      NO_LOAD_CHECK='BOTH';
      NO_IO_CHECK='BOTH';
      ALLOW_CONNECT='TRUE';
  end_pin;
  body
      PART_NAME='MOSFET_N';
      PHYS_DES_PREFIX='EU';
      ENVCOMP='';
      PART_NUMBER='G26762-001';
      JEDEC_TYPE='MLFP3_13_65MA';
      ALT_SYMBOLS='';
      CLASS='IC';
      DESCRIPTION='IC,DS,FET N,E-SO8,BSZ019N03L';
      HEIGHT='0.043 IN';
      COMPONENT_TYPE='LCC';
      LEAD_LENGTH='';
      LPID='2389';
      SPEED_URL='http://speed.intel.com:8081/speed/module/pdm/item/pdm_item_deta~
il_direct.asp?item_cde=G26762-001&item_rev=01&url_param=unused';
      STATUS='';
      RPL='';
      AML='';
      BUS_UNIT='';
      DAYS='';
      PARENT_PART_TYPE='MOSFET_N_LCC3';
      PARENT_PPT='MOSFET_N';
      PARENT_PPT_PART='MOSFET_N_LCC3-BSZ019N03LS,NFET,G26762-001';
  end_body;
end_primitive;
primitive 'MTG_KEYHOLE_TH-EMPTY,NA';
  pin
    '1':
      PIN_NUMBER='(1)';
      PINUSE='UNSPEC';
      NO_LOAD_CHECK='BOTH';
      NO_IO_CHECK='BOTH';
      ALLOW_CONNECT='TRUE';
  end_pin;
  body
      PART_NAME='MTG_KEYHOLE';
      PHYS_DES_PREFIX='TH';
      ENVCOMP='';
      PART_NUMBER='NA';
      JEDEC_TYPE='MTG_KEYHOLE_196X295';
      CLASS='IO';
      DESCRIPTION='MTG_KEYHOLE, TOP 0.118IN, BOTTOM 0.196IN, 0.138IN CENTER-CENT~
ER';
      HEIGHT='0.001 IN';
      COMPONENT_TYPE='PSEUDO';
      SPEED_URL='http://speed.intel.com:8081/speed/module/pdm/item/pdm_item_deta~
il_direct.asp?item_cde=NA&item_rev=01&url_param=unused';
      STATUS='';
      RPL='';
      AML='';
      BUS_UNIT='';
      DAYS='';
      PARENT_PART_TYPE='MTG_KEYHOLE_TH';
      PARENT_PPT='MTG_KEYHOLE';
      PARENT_PPT_PART='MTG_KEYHOLE_TH-EMPTY,NA';
  end_body;
end_primitive;
primitive 'NB3W1200L_LCC-IC,H13585-001';
  pin
    'VDDA':
      PIN_NUMBER='(1)';
      PINUSE='POWER';
      NO_LOAD_CHECK='Both';
      NO_IO_CHECK='Both';
      NO_ASSERT_CHECK='TRUE';
      NO_DIR_CHECK='TRUE';
      ALLOW_CONNECT='TRUE';
    'GNDA':
      PIN_NUMBER='(2)';
      PINUSE='GROUND';
      NO_LOAD_CHECK='Both';
      NO_IO_CHECK='Both';
      NO_ASSERT_CHECK='TRUE';
      NO_DIR_CHECK='TRUE';
      ALLOW_CONNECT='TRUE';
    'NC'<0>:
      PIN_NUMBER='(3)';
      PINUSE='NC';
      NO_LOAD_CHECK='Both';
      NO_IO_CHECK='Both';
      ALLOW_CONNECT='TRUE';
    '100M_133M_N':
      PIN_NUMBER='(4)';
      INPUT_LOAD='(-0.01,0.01)';
      PINUSE='IN';
    'HBW_BYPASS_LOBW_N':
      PIN_NUMBER='(5)';
      INPUT_LOAD='(-0.01,0.01)';
      PINUSE='IN';
    'PWRGD_PWRDN_N':
      PIN_NUMBER='(6)';
      INPUT_LOAD='(-0.01,0.01)';
      PINUSE='IN';
    'GND'<0>:
      PIN_NUMBER='(7)';
      PINUSE='GROUND';
      NO_LOAD_CHECK='Both';
      NO_IO_CHECK='Both';
      NO_ASSERT_CHECK='TRUE';
      NO_DIR_CHECK='TRUE';
      ALLOW_CONNECT='TRUE';
    'VDDR':
      PIN_NUMBER='(8)';
      PINUSE='POWER';
      NO_LOAD_CHECK='Both';
      NO_IO_CHECK='Both';
      NO_ASSERT_CHECK='TRUE';
      NO_DIR_CHECK='TRUE';
      ALLOW_CONNECT='TRUE';
    'CLK_INP':
      PIN_NUMBER='(9)';
      INPUT_LOAD='(-0.01,0.01)';
      PINUSE='IN';
    'CLK_INN':
      PIN_NUMBER='(10)';
      INPUT_LOAD='(-0.01,0.01)';
      PINUSE='IN';
    'SA_0':
      PIN_NUMBER='(11)';
      INPUT_LOAD='(-0.01,0.01)';
      PINUSE='IN';
    'SDA':
      PIN_NUMBER='(12)';
      BIDIRECTIONAL='TRUE';
      INPUT_LOAD='(-0.01,0.01)';
      OUTPUT_LOAD='(1.0,-1.0)';
      PINUSE='BI';
    'SCL':
      PIN_NUMBER='(13)';
      BIDIRECTIONAL='TRUE';
      INPUT_LOAD='(-0.01,0.01)';
      OUTPUT_LOAD='(1.0,-1.0)';
      PINUSE='BI';
    'SA_1':
      PIN_NUMBER='(14)';
      INPUT_LOAD='(-0.01,0.01)';
      PINUSE='IN';
    'NC'<2>:
      PIN_NUMBER='(15)';
      PINUSE='NC';
      NO_LOAD_CHECK='Both';
      NO_IO_CHECK='Both';
      ALLOW_CONNECT='TRUE';
    'NC'<1>:
      PIN_NUMBER='(16)';
      PINUSE='NC';
      NO_LOAD_CHECK='Both';
      NO_IO_CHECK='Both';
      ALLOW_CONNECT='TRUE';
    'DIF_0P':
      PIN_NUMBER='(17)';
      OUTPUT_LOAD='(1.0,-1.0)';
      PINUSE='OUT';
    'DIF_0N':
      PIN_NUMBER='(18)';
      OUTPUT_LOAD='(1.0,-1.0)';
      PINUSE='OUT';
    'OE_0_N':
      PIN_NUMBER='(19)';
      INPUT_LOAD='(-0.01,0.01)';
      PINUSE='IN';
    'OE_1_N':
      PIN_NUMBER='(20)';
      INPUT_LOAD='(-0.01,0.01)';
      PINUSE='IN';
    'DIF_1P':
      PIN_NUMBER='(21)';
      OUTPUT_LOAD='(1.0,-1.0)';
      PINUSE='OUT';
    'DIF_1N':
      PIN_NUMBER='(22)';
      OUTPUT_LOAD='(1.0,-1.0)';
      PINUSE='OUT';
    'GND'<1>:
      PIN_NUMBER='(23)';
      PINUSE='GROUND';
      NO_LOAD_CHECK='Both';
      NO_IO_CHECK='Both';
      NO_ASSERT_CHECK='TRUE';
      NO_DIR_CHECK='TRUE';
      ALLOW_CONNECT='TRUE';
    'VDD'<0>:
      PIN_NUMBER='(24)';
      PINUSE='POWER';
      NO_LOAD_CHECK='Both';
      NO_IO_CHECK='Both';
      NO_ASSERT_CHECK='TRUE';
      NO_DIR_CHECK='TRUE';
      ALLOW_CONNECT='TRUE';
    'VDDIO'<0>:
      PIN_NUMBER='(25)';
      PINUSE='POWER';
      NO_LOAD_CHECK='Both';
      NO_IO_CHECK='Both';
      NO_ASSERT_CHECK='TRUE';
      NO_DIR_CHECK='TRUE';
      ALLOW_CONNECT='TRUE';
    'DIF_2P':
      PIN_NUMBER='(26)';
      OUTPUT_LOAD='(1.0,-1.0)';
      PINUSE='OUT';
    'DIF_2N':
      PIN_NUMBER='(27)';
      OUTPUT_LOAD='(1.0,-1.0)';
      PINUSE='OUT';
    'OE_2_N':
      PIN_NUMBER='(28)';
      INPUT_LOAD='(-0.01,0.01)';
      PINUSE='IN';
    'OE_3_N':
      PIN_NUMBER='(29)';
      INPUT_LOAD='(-0.01,0.01)';
      PINUSE='IN';
    'DIF_3P':
      PIN_NUMBER='(30)';
      OUTPUT_LOAD='(1.0,-1.0)';
      PINUSE='OUT';
    'DIF_3N':
      PIN_NUMBER='(31)';
      OUTPUT_LOAD='(1.0,-1.0)';
      PINUSE='OUT';
    'VDDIO'<1>:
      PIN_NUMBER='(32)';
      PINUSE='POWER';
      NO_LOAD_CHECK='Both';
      NO_IO_CHECK='Both';
      NO_ASSERT_CHECK='TRUE';
      NO_DIR_CHECK='TRUE';
      ALLOW_CONNECT='TRUE';
    'GND'<2>:
      PIN_NUMBER='(33)';
      PINUSE='GROUND';
      NO_LOAD_CHECK='Both';
      NO_IO_CHECK='Both';
      NO_ASSERT_CHECK='TRUE';
      NO_DIR_CHECK='TRUE';
      ALLOW_CONNECT='TRUE';
    'DIF_4P':
      PIN_NUMBER='(34)';
      OUTPUT_LOAD='(1.0,-1.0)';
      PINUSE='OUT';
    'DIF_4N':
      PIN_NUMBER='(35)';
      OUTPUT_LOAD='(1.0,-1.0)';
      PINUSE='OUT';
    'OE_4_N':
      PIN_NUMBER='(36)';
      INPUT_LOAD='(-0.01,0.01)';
      PINUSE='IN';
    'OE_5_N':
      PIN_NUMBER='(37)';
      INPUT_LOAD='(-0.01,0.01)';
      PINUSE='IN';
    'DIF_5P':
      PIN_NUMBER='(38)';
      OUTPUT_LOAD='(1.0,-1.0)';
      PINUSE='OUT';
    'DIF_5N':
      PIN_NUMBER='(39)';
      OUTPUT_LOAD='(1.0,-1.0)';
      PINUSE='OUT';
    'VDD'<1>:
      PIN_NUMBER='(40)';
      PINUSE='POWER';
      NO_LOAD_CHECK='Both';
      NO_IO_CHECK='Both';
      NO_ASSERT_CHECK='TRUE';
      NO_DIR_CHECK='TRUE';
      ALLOW_CONNECT='TRUE';
    'GND'<3>:
      PIN_NUMBER='(41)';
      PINUSE='GROUND';
      NO_LOAD_CHECK='Both';
      NO_IO_CHECK='Both';
      NO_ASSERT_CHECK='TRUE';
      NO_DIR_CHECK='TRUE';
      ALLOW_CONNECT='TRUE';
    'DIF_6P':
      PIN_NUMBER='(42)';
      OUTPUT_LOAD='(1.0,-1.0)';
      PINUSE='OUT';
    'DIF_6N':
      PIN_NUMBER='(43)';
      OUTPUT_LOAD='(1.0,-1.0)';
      PINUSE='OUT';
    'OE_6_N':
      PIN_NUMBER='(44)';
      INPUT_LOAD='(-0.01,0.01)';
      PINUSE='IN';
    'OE_7_N':
      PIN_NUMBER='(45)';
      INPUT_LOAD='(-0.01,0.01)';
      PINUSE='IN';
    'DIF_7P':
      PIN_NUMBER='(46)';
      OUTPUT_LOAD='(1.0,-1.0)';
      PINUSE='OUT';
    'DIF_7N':
      PIN_NUMBER='(47)';
      OUTPUT_LOAD='(1.0,-1.0)';
      PINUSE='OUT';
    'GND'<4>:
      PIN_NUMBER='(48)';
      PINUSE='GROUND';
      NO_LOAD_CHECK='Both';
      NO_IO_CHECK='Both';
      NO_ASSERT_CHECK='TRUE';
      NO_DIR_CHECK='TRUE';
      ALLOW_CONNECT='TRUE';
    'VDDIO'<2>:
      PIN_NUMBER='(49)';
      PINUSE='POWER';
      NO_LOAD_CHECK='Both';
      NO_IO_CHECK='Both';
      NO_ASSERT_CHECK='TRUE';
      NO_DIR_CHECK='TRUE';
      ALLOW_CONNECT='TRUE';
    'DIF_8P':
      PIN_NUMBER='(50)';
      OUTPUT_LOAD='(1.0,-1.0)';
      PINUSE='OUT';
    'DIF_8N':
      PIN_NUMBER='(51)';
      OUTPUT_LOAD='(1.0,-1.0)';
      PINUSE='OUT';
    'OE_8_N':
      PIN_NUMBER='(52)';
      INPUT_LOAD='(-0.01,0.01)';
      PINUSE='IN';
    'OE_9_N':
      PIN_NUMBER='(53)';
      INPUT_LOAD='(-0.01,0.01)';
      PINUSE='IN';
    'DIF_9P':
      PIN_NUMBER='(54)';
      OUTPUT_LOAD='(1.0,-1.0)';
      PINUSE='OUT';
    'DIF_9N':
      PIN_NUMBER='(55)';
      OUTPUT_LOAD='(1.0,-1.0)';
      PINUSE='OUT';
    'VDDIO'<3>:
      PIN_NUMBER='(56)';
      PINUSE='POWER';
      NO_LOAD_CHECK='Both';
      NO_IO_CHECK='Both';
      NO_ASSERT_CHECK='TRUE';
      NO_DIR_CHECK='TRUE';
      ALLOW_CONNECT='TRUE';
    'VDD'<2>:
      PIN_NUMBER='(57)';
      PINUSE='POWER';
      NO_LOAD_CHECK='Both';
      NO_IO_CHECK='Both';
      NO_ASSERT_CHECK='TRUE';
      NO_DIR_CHECK='TRUE';
      ALLOW_CONNECT='TRUE';
    'GND'<5>:
      PIN_NUMBER='(58)';
      PINUSE='GROUND';
      NO_LOAD_CHECK='Both';
      NO_IO_CHECK='Both';
      NO_ASSERT_CHECK='TRUE';
      NO_DIR_CHECK='TRUE';
      ALLOW_CONNECT='TRUE';
    'DIF_10P':
      PIN_NUMBER='(59)';
      OUTPUT_LOAD='(1.0,-1.0)';
      PINUSE='OUT';
    'DIF_10N':
      PIN_NUMBER='(60)';
      OUTPUT_LOAD='(1.0,-1.0)';
      PINUSE='OUT';
    'OE_10_N':
      PIN_NUMBER='(61)';
      INPUT_LOAD='(-0.01,0.01)';
      PINUSE='IN';
    'OE_11_N':
      PIN_NUMBER='(62)';
      INPUT_LOAD='(-0.01,0.01)';
      PINUSE='IN';
    'DIF_11P':
      PIN_NUMBER='(63)';
      OUTPUT_LOAD='(1.0,-1.0)';
      PINUSE='OUT';
    'DIF_11N':
      PIN_NUMBER='(64)';
      OUTPUT_LOAD='(1.0,-1.0)';
      PINUSE='OUT';
    'THPAD':
      PIN_NUMBER='(65)';
      PINUSE='GROUND';
      NO_LOAD_CHECK='Both';
      NO_IO_CHECK='Both';
      NO_ASSERT_CHECK='TRUE';
      NO_DIR_CHECK='TRUE';
      ALLOW_CONNECT='TRUE';
  end_pin;
  body
      PART_NAME='NB3W1200L';
      BODY_NAME='NB3W1200L';
      PHYS_DES_PREFIX='EU';
      ENVCOMP='YES;YES;YES;UNK;ok;VLD';
      PART_NUMBER='H13585-001';
      JEDEC_TYPE='PQFP64_36_5MC';
      DESCRIPTION='IC,CLK_DRVR,64MLF,BUFDR,PLL';
      CLASS='IC';
      COMPONENT_TYPE='LCC';
      HEIGHT='0.039 IN';
      LPID='2659';
      SPEED_URL='http://speed.intel.com:8081/speed/module/pdm/item/pdm_item_deta~
il_direct.asp?item_cde=H13585-001&item_rev=01&url_param=unused';
      STATUS='Design';
      RPL='NO';
      AML='2';
      BUS_UNIT='SMO_IC';
      DAYS='???';
      PARENT_PART_TYPE='NB3W1200L_LCC';
      PARENT_PPT='NB3W1200L';
      PARENT_PPT_PART='NB3W1200L_LCC-IC,H13585-001';
  end_body;
end_primitive;
primitive 'NC7SB3157_SMLF-IC,C99406-001';
  pin
    'S':
      PIN_NUMBER='(6)';
      PIN_TYPE='ANALOG';
      NO_LOAD_CHECK='BOTH';
      NO_IO_CHECK='BOTH';
      ALLOW_CONNECT='TRUE';
      PINUSE='UNSPEC';
    'B0':
      PIN_NUMBER='(3)';
      PIN_TYPE='ANALOG';
      NO_LOAD_CHECK='BOTH';
      NO_IO_CHECK='BOTH';
      ALLOW_CONNECT='TRUE';
      PINUSE='UNSPEC';
    'B1':
      PIN_NUMBER='(1)';
      PIN_TYPE='ANALOG';
      NO_LOAD_CHECK='BOTH';
      NO_IO_CHECK='BOTH';
      ALLOW_CONNECT='TRUE';
      PINUSE='UNSPEC';
    'A':
      PIN_NUMBER='(4)';
      PIN_TYPE='ANALOG';
      NO_LOAD_CHECK='BOTH';
      NO_IO_CHECK='BOTH';
      ALLOW_CONNECT='TRUE';
      PINUSE='UNSPEC';
    'VCC':
      PIN_NUMBER='(5)';
      PIN_TYPE='ANALOG';
      NO_LOAD_CHECK='BOTH';
      NO_IO_CHECK='BOTH';
      ALLOW_CONNECT='TRUE';
      PINUSE='UNSPEC';
    'GND':
      PIN_NUMBER='(2)';
      PIN_TYPE='ANALOG';
      NO_LOAD_CHECK='BOTH';
      NO_IO_CHECK='BOTH';
      ALLOW_CONNECT='TRUE';
      PINUSE='UNSPEC';
  end_pin;
  body
      PART_NAME='NC7SB3157';
      CLASS='IC';
      PHYS_DES_PREFIX='U';
      ENVCOMP='YES;YES;YES;UNK;ok;VLD';
      PART_NUMBER='C99406-001';
      JEDEC_TYPE='SSOP6_53_65MA';
      DESCRIPTION='SPDT ANALOG SW';
      HEIGHT='.037 IN';
      COMPONENT_TYPE='SMALLSMT';
      LEAD_LENGTH='';
      LPID='';
      SPEED_URL='http://speed.intel.com:8081/speed/module/pdm/item/pdm_item_deta~
il_direct.asp?item_cde=C99406-001&item_rev=01&url_param=unused';
      STATUS='Conditional';
      RPL='YES';
      AML='2';
      BUS_UNIT='SMO_IC';
      DAYS='70';
      PARENT_PART_TYPE='NC7SB3157';
      PARENT_PPT='NC7SB3157';
      PARENT_PPT_PART='NC7SB3157_SMLF-IC,C99406-001';
  end_body;
end_primitive;
primitive 'NCP3232L_SM-IC,H86355-001';
  pin
    'AGND':
      PIN_NUMBER='(5)';
      PINUSE='GROUND';
      NO_LOAD_CHECK='Both';
      NO_IO_CHECK='Both';
      NO_ASSERT_CHECK='TRUE';
      NO_DIR_CHECK='TRUE';
      ALLOW_CONNECT='TRUE';
    'BST':
      PIN_NUMBER='(36)';
      INPUT_LOAD='(-0.01,0.01)';
      PINUSE='IN';
    'COMP':
      PIN_NUMBER='(3)';
      OUTPUT_LOAD='(1.0,-1.0)';
      PINUSE='OUT';
    'EN':
      PIN_NUMBER='(40)';
      INPUT_LOAD='(-0.01,0.01)';
      PINUSE='IN';
    'FB':
      PIN_NUMBER='(2)';
      BIDIRECTIONAL='TRUE';
      INPUT_LOAD='(-0.01,0.01)';
      OUTPUT_LOAD='(1.0,-1.0)';
      PINUSE='BI';
    'GND':
      PIN_NUMBER='(41)';
      PINUSE='GROUND';
      NO_LOAD_CHECK='Both';
      NO_IO_CHECK='Both';
      NO_ASSERT_CHECK='TRUE';
      NO_DIR_CHECK='TRUE';
      ALLOW_CONNECT='TRUE';
    'ISET':
      PIN_NUMBER='(4)';
      BIDIRECTIONAL='TRUE';
      INPUT_LOAD='(-0.01,0.01)';
      OUTPUT_LOAD='(1.0,-1.0)';
      PINUSE='BI';
    'OTS':
      PIN_NUMBER='(6)';
      INPUT_LOAD='(-0.01,0.01)';
      PINUSE='IN';
    'PG':
      PIN_NUMBER='(7)';
      BIDIRECTIONAL='TRUE';
      INPUT_LOAD='(-0.01,0.01)';
      OUTPUT_LOAD='(1.0,-1.0)';
      PINUSE='BI';
    'PGND'<13>:
      PIN_NUMBER='(37)';
      PINUSE='GROUND';
      NO_LOAD_CHECK='Both';
      NO_IO_CHECK='Both';
      NO_ASSERT_CHECK='TRUE';
      NO_DIR_CHECK='TRUE';
      ALLOW_CONNECT='TRUE';
    'PGND'<12>:
      PIN_NUMBER='(28)';
      PINUSE='GROUND';
      NO_LOAD_CHECK='Both';
      NO_IO_CHECK='Both';
      NO_ASSERT_CHECK='TRUE';
      NO_DIR_CHECK='TRUE';
      ALLOW_CONNECT='TRUE';
    'PGND'<11>:
      PIN_NUMBER='(27)';
      PINUSE='GROUND';
      NO_LOAD_CHECK='Both';
      NO_IO_CHECK='Both';
      NO_ASSERT_CHECK='TRUE';
      NO_DIR_CHECK='TRUE';
      ALLOW_CONNECT='TRUE';
    'PGND'<10>:
      PIN_NUMBER='(26)';
      PINUSE='GROUND';
      NO_LOAD_CHECK='Both';
      NO_IO_CHECK='Both';
      NO_ASSERT_CHECK='TRUE';
      NO_DIR_CHECK='TRUE';
      ALLOW_CONNECT='TRUE';
    'PGND'<9>:
      PIN_NUMBER='(25)';
      PINUSE='GROUND';
      NO_LOAD_CHECK='Both';
      NO_IO_CHECK='Both';
      NO_ASSERT_CHECK='TRUE';
      NO_DIR_CHECK='TRUE';
      ALLOW_CONNECT='TRUE';
    'PGND'<8>:
      PIN_NUMBER='(24)';
      PINUSE='GROUND';
      NO_LOAD_CHECK='Both';
      NO_IO_CHECK='Both';
      NO_ASSERT_CHECK='TRUE';
      NO_DIR_CHECK='TRUE';
      ALLOW_CONNECT='TRUE';
    'PGND'<7>:
      PIN_NUMBER='(23)';
      PINUSE='GROUND';
      NO_LOAD_CHECK='Both';
      NO_IO_CHECK='Both';
      NO_ASSERT_CHECK='TRUE';
      NO_DIR_CHECK='TRUE';
      ALLOW_CONNECT='TRUE';
    'PGND'<6>:
      PIN_NUMBER='(22)';
      PINUSE='GROUND';
      NO_LOAD_CHECK='Both';
      NO_IO_CHECK='Both';
      NO_ASSERT_CHECK='TRUE';
      NO_DIR_CHECK='TRUE';
      ALLOW_CONNECT='TRUE';
    'PGND'<5>:
      PIN_NUMBER='(21)';
      PINUSE='GROUND';
      NO_LOAD_CHECK='Both';
      NO_IO_CHECK='Both';
      NO_ASSERT_CHECK='TRUE';
      NO_DIR_CHECK='TRUE';
      ALLOW_CONNECT='TRUE';
    'PGND'<4>:
      PIN_NUMBER='(20)';
      PINUSE='GROUND';
      NO_LOAD_CHECK='Both';
      NO_IO_CHECK='Both';
      NO_ASSERT_CHECK='TRUE';
      NO_DIR_CHECK='TRUE';
      ALLOW_CONNECT='TRUE';
    'PGND'<3>:
      PIN_NUMBER='(19)';
      PINUSE='GROUND';
      NO_LOAD_CHECK='Both';
      NO_IO_CHECK='Both';
      NO_ASSERT_CHECK='TRUE';
      NO_DIR_CHECK='TRUE';
      ALLOW_CONNECT='TRUE';
    'PGND'<2>:
      PIN_NUMBER='(18)';
      PINUSE='GROUND';
      NO_LOAD_CHECK='Both';
      NO_IO_CHECK='Both';
      NO_ASSERT_CHECK='TRUE';
      NO_DIR_CHECK='TRUE';
      ALLOW_CONNECT='TRUE';
    'PGND'<1>:
      PIN_NUMBER='(17)';
      PINUSE='GROUND';
      NO_LOAD_CHECK='Both';
      NO_IO_CHECK='Both';
      NO_ASSERT_CHECK='TRUE';
      NO_DIR_CHECK='TRUE';
      ALLOW_CONNECT='TRUE';
    'PGND'<0>:
      PIN_NUMBER='(16)';
      PINUSE='GROUND';
      NO_LOAD_CHECK='Both';
      NO_IO_CHECK='Both';
      NO_ASSERT_CHECK='TRUE';
      NO_DIR_CHECK='TRUE';
      ALLOW_CONNECT='TRUE';
    'SS':
      PIN_NUMBER='(1)';
      BIDIRECTIONAL='TRUE';
      INPUT_LOAD='(-0.01,0.01)';
      OUTPUT_LOAD='(1.0,-1.0)';
      PINUSE='BI';
    'VB':
      PIN_NUMBER='(38)';
      OUTPUT_LOAD='(1.0,-1.0)';
      PINUSE='OUT';
    'VCC':
      PIN_NUMBER='(39)';
      PINUSE='POWER';
      NO_LOAD_CHECK='Both';
      NO_IO_CHECK='Both';
      NO_ASSERT_CHECK='TRUE';
      NO_DIR_CHECK='TRUE';
      ALLOW_CONNECT='TRUE';
    'VIN'<7>:
      PIN_NUMBER='(42)';
      INPUT_LOAD='(-0.01,0.01)';
      PINUSE='IN';
    'VIN'<6>:
      PIN_NUMBER='(14)';
      INPUT_LOAD='(-0.01,0.01)';
      PINUSE='IN';
    'VIN'<5>:
      PIN_NUMBER='(13)';
      INPUT_LOAD='(-0.01,0.01)';
      PINUSE='IN';
    'VIN'<4>:
      PIN_NUMBER='(12)';
      INPUT_LOAD='(-0.01,0.01)';
      PINUSE='IN';
    'VIN'<3>:
      PIN_NUMBER='(11)';
      INPUT_LOAD='(-0.01,0.01)';
      PINUSE='IN';
    'VIN'<2>:
      PIN_NUMBER='(10)';
      INPUT_LOAD='(-0.01,0.01)';
      PINUSE='IN';
    'VIN'<1>:
      PIN_NUMBER='(9)';
      INPUT_LOAD='(-0.01,0.01)';
      PINUSE='IN';
    'VIN'<0>:
      PIN_NUMBER='(8)';
      INPUT_LOAD='(-0.01,0.01)';
      PINUSE='IN';
    'VSW':
      PIN_NUMBER='(35)';
      BIDIRECTIONAL='TRUE';
      INPUT_LOAD='(-0.01,0.01)';
      OUTPUT_LOAD='(1.0,-1.0)';
      PINUSE='BI';
    'VSWH'<7>:
      PIN_NUMBER='(43)';
      BIDIRECTIONAL='TRUE';
      INPUT_LOAD='(-0.01,0.01)';
      OUTPUT_LOAD='(1.0,-1.0)';
      PINUSE='BI';
    'VSWH'<6>:
      PIN_NUMBER='(34)';
      BIDIRECTIONAL='TRUE';
      INPUT_LOAD='(-0.01,0.01)';
      OUTPUT_LOAD='(1.0,-1.0)';
      PINUSE='BI';
    'VSWH'<5>:
      PIN_NUMBER='(33)';
      BIDIRECTIONAL='TRUE';
      INPUT_LOAD='(-0.01,0.01)';
      OUTPUT_LOAD='(1.0,-1.0)';
      PINUSE='BI';
    'VSWH'<4>:
      PIN_NUMBER='(32)';
      BIDIRECTIONAL='TRUE';
      INPUT_LOAD='(-0.01,0.01)';
      OUTPUT_LOAD='(1.0,-1.0)';
      PINUSE='BI';
    'VSWH'<3>:
      PIN_NUMBER='(31)';
      BIDIRECTIONAL='TRUE';
      INPUT_LOAD='(-0.01,0.01)';
      OUTPUT_LOAD='(1.0,-1.0)';
      PINUSE='BI';
    'VSWH'<2>:
      PIN_NUMBER='(30)';
      BIDIRECTIONAL='TRUE';
      INPUT_LOAD='(-0.01,0.01)';
      OUTPUT_LOAD='(1.0,-1.0)';
      PINUSE='BI';
    'VSWH'<1>:
      PIN_NUMBER='(29)';
      BIDIRECTIONAL='TRUE';
      INPUT_LOAD='(-0.01,0.01)';
      OUTPUT_LOAD='(1.0,-1.0)';
      PINUSE='BI';
    'VSWH'<0>:
      PIN_NUMBER='(15)';
      BIDIRECTIONAL='TRUE';
      INPUT_LOAD='(-0.01,0.01)';
      OUTPUT_LOAD='(1.0,-1.0)';
      PINUSE='BI';
  end_pin;
  body
      PART_NAME='NCP3232L';
      BODY_NAME='NCP3232L';
      PHYS_DES_PREFIX='EU';
      ENVCOMP='';
      PART_NUMBER='H86355-001';
      JEDEC_TYPE='LCC40_24_5ME';
      CLASS='IC';
      DESCRIPTION='IC,LIN,QFN,NCP3232L,DC/DC';
      COMPONENT_TYPE='LCC';
      HEIGHT='0.039 IN';
      LPID='1960';
      SPEED_URL='http://speed.intel.com:8081/speed/module/pdm/item/pdm_item_deta~
il_direct.asp?item_cde=H86355-001&item_rev=01&url_param=unused';
      STATUS='';
      RPL='';
      AML='';
      BUS_UNIT='';
      DAYS='';
      PARENT_PART_TYPE='NCP3232L_SM';
      PARENT_PPT='NCP3232L';
      PARENT_PPT_PART='NCP3232L_SM-IC,H86355-001';
  end_body;
end_primitive;
primitive 'NPN_DUAL_SSOPLF-MBT3904,EMPTY,A';
  pin
    'B'<0>:
      PIN_NUMBER='(5,2)';
      PINUSE='UNSPEC';
      NO_LOAD_CHECK='BOTH';
      NO_IO_CHECK='BOTH';
      ALLOW_CONNECT='TRUE';
    'C'<0>:
      PIN_NUMBER='(3,6)';
      PINUSE='UNSPEC';
      NO_LOAD_CHECK='BOTH';
      NO_IO_CHECK='BOTH';
      ALLOW_CONNECT='TRUE';
    'E'<0>:
      PIN_NUMBER='(4,1)';
      PINUSE='UNSPEC';
      NO_LOAD_CHECK='BOTH';
      NO_IO_CHECK='BOTH';
      ALLOW_CONNECT='TRUE';
  end_pin;
  body
      PART_NAME='NPN_DUAL';
      PHYS_DES_PREFIX='Q';
      ENVCOMP='YES;YES;YES;UNK;ok;VLD';
      PART_NUMBER='C52264-001';
      JEDEC_TYPE='SSOP6_53_65MA';
      DESCRIPTION='DUAL PURPOSE TRANSISTOR LF';
      HEIGHT='.044 IN';
      COMPONENT_TYPE='SMALLSMT';
      LEAD_LENGTH='';
      CLASS='IO';
      LPID='';
      SPEED_URL='http://speed.intel.com:8081/speed/module/pdm/item/pdm_item_deta~
il_direct.asp?item_cde=C52264-001&item_rev=01&url_param=unused';
      STATUS='Approved';
      RPL='YES';
      AML='2';
      BUS_UNIT='SMO_IC';
      DAYS='56';
      PARENT_PART_TYPE='NPN_DUAL';
      PARENT_PPT='NPN_DUAL';
      PARENT_PPT_PART='NPN_DUAL_SSOPLF-MBT3904,EMPTY,C52264-001';
  end_body;
end_primitive;
primitive 'NPN_DUAL_SSOPLF-MBT3904,XSTR,CA';
  pin
    'B'<0>:
      PIN_NUMBER='(5,2)';
      PINUSE='UNSPEC';
      NO_LOAD_CHECK='BOTH';
      NO_IO_CHECK='BOTH';
      ALLOW_CONNECT='TRUE';
    'C'<0>:
      PIN_NUMBER='(3,6)';
      PINUSE='UNSPEC';
      NO_LOAD_CHECK='BOTH';
      NO_IO_CHECK='BOTH';
      ALLOW_CONNECT='TRUE';
    'E'<0>:
      PIN_NUMBER='(4,1)';
      PINUSE='UNSPEC';
      NO_LOAD_CHECK='BOTH';
      NO_IO_CHECK='BOTH';
      ALLOW_CONNECT='TRUE';
  end_pin;
  body
      PART_NAME='NPN_DUAL';
      PHYS_DES_PREFIX='Q';
      ENVCOMP='YES;YES;YES;UNK;ok;VLD';
      PART_NUMBER='C52264-001';
      JEDEC_TYPE='SSOP6_53_65MA';
      DESCRIPTION='DUAL PURPOSE TRANSISTOR LF';
      HEIGHT='.044 IN';
      COMPONENT_TYPE='SMALLSMT';
      LEAD_LENGTH='';
      CLASS='IC';
      LPID='';
      SPEED_URL='http://speed.intel.com:8081/speed/module/pdm/item/pdm_item_deta~
il_direct.asp?item_cde=C52264-001&item_rev=01&url_param=unused';
      STATUS='Approved';
      RPL='YES';
      AML='2';
      BUS_UNIT='SMO_IC';
      DAYS='56';
      PARENT_PART_TYPE='NPN_DUAL';
      PARENT_PPT='NPN_DUAL';
      PARENT_PPT_PART='NPN_DUAL_SSOPLF-MBT3904,XSTR,C52264-001';
  end_body;
end_primitive;
primitive 'NPN_SM-MMBT3904,IC,C52245-001';
  pin
    'B':
      PIN_NUMBER='(1)';
      PINUSE='UNSPEC';
      NO_LOAD_CHECK='BOTH';
      NO_IO_CHECK='BOTH';
      ALLOW_CONNECT='TRUE';
    'C':
      PIN_NUMBER='(3)';
      PINUSE='UNSPEC';
      NO_LOAD_CHECK='BOTH';
      NO_IO_CHECK='BOTH';
      ALLOW_CONNECT='TRUE';
    'E':
      PIN_NUMBER='(2)';
      PINUSE='UNSPEC';
      NO_LOAD_CHECK='BOTH';
      NO_IO_CHECK='BOTH';
      ALLOW_CONNECT='TRUE';
  end_pin;
  body
      PART_NAME='NPN';
      PHYS_DES_PREFIX='Q';
      ENVCOMP='YES;YES;CNC;CNC;ok;CIP';
      PART_NUMBER='C52245-001';
      JEDEC_TYPE='SOT23B';
      CLASS='IC';
      DESCRIPTION='SWITCHING TRANSISTOR';
      HEIGHT='0.045 IN';
      COMPONENT_TYPE='SMALLSMT';
      LEAD_LENGTH='';
      LPID='801';
      SPEED_URL='http://speed.intel.com:8081/speed/module/pdm/item/pdm_item_deta~
il_direct.asp?item_cde=C52245-001&item_rev=01&url_param=unused';
      STATUS='Approved';
      RPL='YES';
      AML='13';
      BUS_UNIT='SMO_IC';
      DAYS='294';
      PARENT_PART_TYPE='NPN_SM';
      PARENT_PPT='NPN';
      PARENT_PPT_PART='NPN_SM-MMBT3904,IC,C52245-001';
  end_body;
end_primitive;
primitive 'OSC_C_6P10-156.25MHZ,OSC,G6383A';
  pin
    'ENABLE_DISABLE':
      PIN_NUMBER='(1)';
      BIDIRECTIONAL='TRUE';
      INPUT_LOAD='(-0.01,0.01)';
      OUTPUT_LOAD='(1.0,-1.0)';
      PINUSE='BI';
    'NC_GND':
      PIN_NUMBER='(2)';
      PINUSE='NC';
      NO_LOAD_CHECK='Both';
      NO_IO_CHECK='Both';
      NO_ASSERT_CHECK='TRUE';
      NO_DIR_CHECK='TRUE';
      ALLOW_CONNECT='TRUE';
    'GND':
      PIN_NUMBER='(3)';
      PINUSE='GROUND';
      NO_LOAD_CHECK='Both';
      NO_IO_CHECK='Both';
      NO_ASSERT_CHECK='TRUE';
      NO_DIR_CHECK='TRUE';
      ALLOW_CONNECT='TRUE';
    'OUT':
      PIN_NUMBER='(4)';
      OUTPUT_LOAD='(1.0,-1.0)';
      PINUSE='OUT';
    'OUT_N':
      PIN_NUMBER='(5)';
      OUTPUT_LOAD='(1.0,-1.0)';
      PINUSE='OUT';
    'VCC':
      PIN_NUMBER='(6)';
      PINUSE='POWER';
      NO_LOAD_CHECK='Both';
      NO_IO_CHECK='Both';
      NO_ASSERT_CHECK='TRUE';
      NO_DIR_CHECK='TRUE';
      ALLOW_CONNECT='TRUE';
  end_pin;
  body
      PART_NAME='OSC_C';
      PHYS_DES_PREFIX='Y';
      ENVCOMP='';
      PART_NUMBER='G63831-004';
      JEDEC_TYPE='SOSR2013C';
      CLASS='IC';
      DESCRIPTION='(USE SYM 17) OSC,CX0,6,5032,156.25MHZ,50PPM,3.3V,HCSL,SM';
      HEIGHT='0.053 IN';
      COMPONENT_TYPE='SMTOTHER';
      LPID='2535';
      SPEED_URL='http://speed.intel.com:8081/speed/module/pdm/item/pdm_item_deta~
il_direct.asp?item_cde=G63831-004&item_rev=01&url_param=unused';
      STATUS='';
      RPL='';
      AML='';
      BUS_UNIT='';
      DAYS='';
      PARENT_PART_TYPE='OSC_C_6P10';
      PARENT_PPT='OSC_C';
      PARENT_PPT_PART='OSC_C_6P10-156.25MHZ,OSC,G63831-004';
  end_body;
end_primitive;
primitive 'OSC_C_SM4-24MHZ,OSC,D34520-021';
  pin
    'ENABLE_CONTROL':
      PIN_NUMBER='(1)';
      INPUT_LOAD='(-0.01,0.01)';
      PINUSE='IN';
    'GND':
      PIN_NUMBER='(2)';
      PINUSE='GROUND';
      NO_LOAD_CHECK='Both';
      NO_IO_CHECK='Both';
      NO_ASSERT_CHECK='TRUE';
      NO_DIR_CHECK='TRUE';
      ALLOW_CONNECT='TRUE';
    'OUT':
      PIN_NUMBER='(3)';
      OUTPUT_LOAD='(1.0,-1.0)';
      PINUSE='OUT';
    'VDD':
      PIN_NUMBER='(4)';
      PINUSE='POWER';
      NO_LOAD_CHECK='Both';
      NO_IO_CHECK='Both';
      NO_ASSERT_CHECK='TRUE';
      NO_DIR_CHECK='TRUE';
      ALLOW_CONNECT='TRUE';
  end_pin;
  body
      PART_NAME='OSC_C';
      PHYS_DES_PREFIX='Y';
      ENVCOMP='';
      PART_NUMBER='D34520-021';
      JEDEC_TYPE='SMY1310B';
      CLASS='IC';
      DESCRIPTION='(USE SYM 11) OSC,CX0,4,SMD,24.00MHZ,25PPM,3.3V,CMOS,SM';
      HEIGHT='0.043 IN';
      COMPONENT_TYPE='SMTOTHER';
      LPID='3386';
      SPEED_URL='http://speed.intel.com:8081/speed/module/pdm/item/pdm_item_deta~
il_direct.asp?item_cde=D34520-021&item_rev=01&url_param=unused';
      STATUS='';
      RPL='';
      AML='';
      BUS_UNIT='';
      DAYS='';
      PARENT_PART_TYPE='OSC_C_SM4';
      PARENT_PPT='OSC_C';
      PARENT_PPT_PART='OSC_C_SM4-24MHZ,OSC,D34520-021';
  end_body;
end_primitive;
primitive 'PCA9554PWR-GP_DISCRET-G1-PCA95A';
  pin
    'A0':
      PIN_NUMBER='(1)';
      INPUT_LOAD='(-0.01,0.01)';
      PINUSE='IN';
    'A1':
      PIN_NUMBER='(2)';
      INPUT_LOAD='(-0.01,0.01)';
      PINUSE='IN';
    'A2':
      PIN_NUMBER='(3)';
      INPUT_LOAD='(-0.01,0.01)';
      PINUSE='IN';
    'P0':
      PIN_NUMBER='(4)';
      BIDIRECTIONAL='TRUE';
      INPUT_LOAD='(-0.01,0.01)';
      OUTPUT_LOAD='(1.0,-1.0)';
      PINUSE='BI';
    'P1':
      PIN_NUMBER='(5)';
      BIDIRECTIONAL='TRUE';
      INPUT_LOAD='(-0.01,0.01)';
      OUTPUT_LOAD='(1.0,-1.0)';
      PINUSE='BI';
    'P2':
      PIN_NUMBER='(6)';
      BIDIRECTIONAL='TRUE';
      INPUT_LOAD='(-0.01,0.01)';
      OUTPUT_LOAD='(1.0,-1.0)';
      PINUSE='BI';
    'P3':
      PIN_NUMBER='(7)';
      BIDIRECTIONAL='TRUE';
      INPUT_LOAD='(-0.01,0.01)';
      OUTPUT_LOAD='(1.0,-1.0)';
      PINUSE='BI';
    'GND':
      PIN_NUMBER='(8)';
      PINUSE='POWER';
      NO_LOAD_CHECK='Both';
      NO_IO_CHECK='Both';
      NO_ASSERT_CHECK='TRUE';
      NO_DIR_CHECK='TRUE';
      ALLOW_CONNECT='TRUE';
    'P4':
      PIN_NUMBER='(9)';
      BIDIRECTIONAL='TRUE';
      INPUT_LOAD='(-0.01,0.01)';
      OUTPUT_LOAD='(1.0,-1.0)';
      PINUSE='BI';
    'P5':
      PIN_NUMBER='(10)';
      BIDIRECTIONAL='TRUE';
      INPUT_LOAD='(-0.01,0.01)';
      OUTPUT_LOAD='(1.0,-1.0)';
      PINUSE='BI';
    'P6':
      PIN_NUMBER='(11)';
      BIDIRECTIONAL='TRUE';
      INPUT_LOAD='(-0.01,0.01)';
      OUTPUT_LOAD='(1.0,-1.0)';
      PINUSE='BI';
    'P7':
      PIN_NUMBER='(12)';
      BIDIRECTIONAL='TRUE';
      INPUT_LOAD='(-0.01,0.01)';
      OUTPUT_LOAD='(1.0,-1.0)';
      PINUSE='BI';
    'INT#':
      PIN_NUMBER='(13)';
      OUTPUT_LOAD='(1.0,-1.0)';
      PINUSE='OUT';
    'SCL':
      PIN_NUMBER='(14)';
      PIN_TYPE='ANALOG';
      NO_LOAD_CHECK='Both';
      NO_IO_CHECK='Both';
      NO_ASSERT_CHECK='TRUE';
      NO_DIR_CHECK='TRUE';
      ALLOW_CONNECT='TRUE';
      PINUSE='UNSPEC';
    'SDA':
      PIN_NUMBER='(15)';
      INPUT_LOAD='(-0.01,0.01)';
      PINUSE='IN';
    'VCC':
      PIN_NUMBER='(16)';
      PINUSE='POWER';
      NO_LOAD_CHECK='Both';
      NO_IO_CHECK='Both';
      NO_ASSERT_CHECK='TRUE';
      NO_DIR_CHECK='TRUE';
      ALLOW_CONNECT='TRUE';
  end_pin;
  body
      PART_NAME='PCA9554PWR-GP';
      BODY_NAME='PCA9554PWR-GP';
      PHYS_DES_PREFIX='U';
      CLASS='IC';
      DESCRIPTION='IC I/O PCA9554PWR TSSOP 16P';
      JEDEC_TYPE='TSOIC16H48';
      PARENT_PART_TYPE='PCA9554PWR-GP';
      PARENT_PPT='PCA9554PWR-GP';
      PARENT_PPT_PART='PCA9554PWR-GP_DISCRET-G1-PCA9554PWR-GP,71.09554.C0W';
  end_body;
end_primitive;
primitive 'PCA9617_SSOP-IC,G81764-001-GNDA';
  pin
    'EN':
      PIN_NUMBER='(5)';
      INPUT_LOAD='(-0.01,0.01)';
      PINUSE='IN';
    'SCLA':
      PIN_NUMBER='(2)';
      INPUT_LOAD='(-0.01,0.01)';
      PINUSE='IN';
    'SCLB':
      PIN_NUMBER='(7)';
      OUTPUT_LOAD='(1.0,-1.0)';
      PINUSE='OUT';
    'SDAA':
      PIN_NUMBER='(3)';
      INPUT_LOAD='(-0.01,0.01)';
      PINUSE='IN';
    'SDAB':
      PIN_NUMBER='(6)';
      OUTPUT_LOAD='(1.0,-1.0)';
      PINUSE='OUT';
    'VCCA':
      PIN_NUMBER='(1)';
      PIN_TYPE='POWER';
      NO_LOAD_CHECK='BOTH';
      NO_IO_CHECK='BOTH';
      ALLOW_CONNECT='TRUE';
      PINUSE='POWER';
    'VCCB':
      PIN_NUMBER='(8)';
      PIN_TYPE='POWER';
      NO_LOAD_CHECK='BOTH';
      NO_IO_CHECK='BOTH';
      ALLOW_CONNECT='TRUE';
      PINUSE='POWER';
  end_pin;
  body
      PART_NAME='PCA9617';
      PHYS_DES_PREFIX='U';
      ENVCOMP='YES;YES;YES;UNK;ok;VLD';
      PART_NUMBER='G81764-001';
      JEDEC_TYPE='SSOP8_12_65MC';
      DESCRIPTION='IC,BUF/DVR,I2C,SSOP,PCA9617ADP';
      CLASS='IC';
      COMPONENT_TYPE='SUB50';
      HEIGHT='0.043 IN';
      LPID='2481';
      SPEED_URL='http://speed.intel.com:8081/speed/module/pdm/item/pdm_item_deta~
il_direct.asp?item_cde=G81764-001&item_rev=01&url_param=unused';
      STATUS='Design';
      RPL='NO';
      AML='1';
      BUS_UNIT='SMO_IC';
      DAYS='???';
      POWER_PINS='(GND:4)';
      PARENT_PART_TYPE='PCA9617_SSOP';
      SCH_MODIFIED_PART='TRUE';
      PARENT_PPT='PCA9617';
      PARENT_PPT_PART='PCA9617_SSOP-IC,G81764-001';
  end_body;
end_primitive;
primitive 'PI3B3257A_TSSOPLF-IC,E16801-001';
  pin
    'VCC':
      PIN_NUMBER='(16)';
      PIN_TYPE='POWER';
      NO_LOAD_CHECK='BOTH';
      NO_IO_CHECK='BOTH';
      ALLOW_CONNECT='TRUE';
      PINUSE='POWER';
    'GND':
      PIN_NUMBER='(8)';
      PIN_TYPE='POWER';
      NO_LOAD_CHECK='BOTH';
      NO_IO_CHECK='BOTH';
      ALLOW_CONNECT='TRUE';
      PINUSE='POWER';
    'EN':
      PIN_NUMBER='(15)';
      INPUT_LOAD='(-0.01,0.01)';
      PINUSE='IN';
    'S':
      PIN_NUMBER='(1)';
      INPUT_LOAD='(-0.01,0.01)';
      OUTPUT_LOAD='(1.0,-1.0)';
      OUTPUT_TYPE='(TS,TS)';
      BIDIRECTIONAL='TRUE';
      PINUSE='BI';
    'YA':
      PIN_NUMBER='(4)';
      INPUT_LOAD='(-0.01,0.01)';
      OUTPUT_LOAD='(1.0,-1.0)';
      OUTPUT_TYPE='(TS,TS)';
      BIDIRECTIONAL='TRUE';
      PINUSE='BI';
    'YB':
      PIN_NUMBER='(7)';
      INPUT_LOAD='(-0.01,0.01)';
      OUTPUT_LOAD='(1.0,-1.0)';
      OUTPUT_TYPE='(TS,TS)';
      BIDIRECTIONAL='TRUE';
      PINUSE='BI';
    'YC':
      PIN_NUMBER='(9)';
      INPUT_LOAD='(-0.01,0.01)';
      OUTPUT_LOAD='(1.0,-1.0)';
      OUTPUT_TYPE='(TS,TS)';
      BIDIRECTIONAL='TRUE';
      PINUSE='BI';
    'YD':
      PIN_NUMBER='(12)';
      INPUT_LOAD='(-0.01,0.01)';
      OUTPUT_LOAD='(1.0,-1.0)';
      OUTPUT_TYPE='(TS,TS)';
      BIDIRECTIONAL='TRUE';
      PINUSE='BI';
    'IA0':
      PIN_NUMBER='(2)';
      INPUT_LOAD='(-0.01,0.01)';
      OUTPUT_LOAD='(1.0,-1.0)';
      OUTPUT_TYPE='(TS,TS)';
      BIDIRECTIONAL='TRUE';
      PINUSE='BI';
    'IA1':
      PIN_NUMBER='(3)';
      INPUT_LOAD='(-0.01,0.01)';
      OUTPUT_LOAD='(1.0,-1.0)';
      OUTPUT_TYPE='(TS,TS)';
      BIDIRECTIONAL='TRUE';
      PINUSE='BI';
    'IB0':
      PIN_NUMBER='(5)';
      INPUT_LOAD='(-0.01,0.01)';
      OUTPUT_LOAD='(1.0,-1.0)';
      OUTPUT_TYPE='(TS,TS)';
      BIDIRECTIONAL='TRUE';
      PINUSE='BI';
    'IB1':
      PIN_NUMBER='(6)';
      INPUT_LOAD='(-0.01,0.01)';
      OUTPUT_LOAD='(1.0,-1.0)';
      OUTPUT_TYPE='(TS,TS)';
      BIDIRECTIONAL='TRUE';
      PINUSE='BI';
    'IC0':
      PIN_NUMBER='(11)';
      INPUT_LOAD='(-0.01,0.01)';
      OUTPUT_LOAD='(1.0,-1.0)';
      OUTPUT_TYPE='(TS,TS)';
      BIDIRECTIONAL='TRUE';
      PINUSE='BI';
    'IC1':
      PIN_NUMBER='(10)';
      INPUT_LOAD='(-0.01,0.01)';
      OUTPUT_LOAD='(1.0,-1.0)';
      OUTPUT_TYPE='(TS,TS)';
      BIDIRECTIONAL='TRUE';
      PINUSE='BI';
    'ID0':
      PIN_NUMBER='(14)';
      INPUT_LOAD='(-0.01,0.01)';
      OUTPUT_LOAD='(1.0,-1.0)';
      OUTPUT_TYPE='(TS,TS)';
      BIDIRECTIONAL='TRUE';
      PINUSE='BI';
    'ID1':
      PIN_NUMBER='(13)';
      INPUT_LOAD='(-0.01,0.01)';
      OUTPUT_LOAD='(1.0,-1.0)';
      OUTPUT_TYPE='(TS,TS)';
      BIDIRECTIONAL='TRUE';
      PINUSE='BI';
  end_pin;
  body
      CLASS='IC';
      PART_NAME='PI3B3257A';
      PHYS_DES_PREFIX='U';
      ENVCOMP='YES;YES;UNK;UNK;ok;VLD';
      PART_NUMBER='E16801-001';
      JEDEC_TYPE='QSOP16_15_25IA';
      DESCRIPTION='quad mux';
      HEIGHT='0.068 IN';
      COMPONENT_TYPE='SOIC';
      LEAD_LENGTH='';
      LPID='976';
      SPEED_URL='http://speed.intel.com:8081/speed/module/pdm/item/pdm_item_deta~
il_direct.asp?item_cde=E16801-001&item_rev=01&url_param=unused';
      STATUS='Design';
      RPL='NO';
      AML='1';
      BUS_UNIT='SMO_IC';
      DAYS='???';
      PARENT_PART_TYPE='PI3B3257A_TSSOPLF';
      PARENT_PPT='PI3B3257A';
      PARENT_PPT_PART='PI3B3257A_TSSOPLF-IC,E16801-001';
  end_body;
end_primitive;
primitive 'PI5A3157BC6E-GP_DISCRET-GC2-PIA';
  pin
    'B1':
      PIN_NUMBER='(1)';
      PIN_TYPE='ANALOG';
      NO_LOAD_CHECK='Both';
      NO_IO_CHECK='Both';
      NO_ASSERT_CHECK='TRUE';
      NO_DIR_CHECK='TRUE';
      ALLOW_CONNECT='TRUE';
      PINUSE='UNSPEC';
    'GND':
      PIN_NUMBER='(2)';
      PINUSE='POWER';
      NO_LOAD_CHECK='Both';
      NO_IO_CHECK='Both';
      NO_ASSERT_CHECK='TRUE';
      NO_DIR_CHECK='TRUE';
      ALLOW_CONNECT='TRUE';
    'B0':
      PIN_NUMBER='(3)';
      PIN_TYPE='ANALOG';
      NO_LOAD_CHECK='Both';
      NO_IO_CHECK='Both';
      NO_ASSERT_CHECK='TRUE';
      NO_DIR_CHECK='TRUE';
      ALLOW_CONNECT='TRUE';
      PINUSE='UNSPEC';
    'A':
      PIN_NUMBER='(4)';
      PIN_TYPE='ANALOG';
      NO_LOAD_CHECK='Both';
      NO_IO_CHECK='Both';
      NO_ASSERT_CHECK='TRUE';
      NO_DIR_CHECK='TRUE';
      ALLOW_CONNECT='TRUE';
      PINUSE='UNSPEC';
    'VCC':
      PIN_NUMBER='(5)';
      PINUSE='POWER';
      NO_LOAD_CHECK='Both';
      NO_IO_CHECK='Both';
      NO_ASSERT_CHECK='TRUE';
      NO_DIR_CHECK='TRUE';
      ALLOW_CONNECT='TRUE';
    'S':
      PIN_NUMBER='(6)';
      PIN_TYPE='ANALOG';
      NO_LOAD_CHECK='Both';
      NO_IO_CHECK='Both';
      NO_ASSERT_CHECK='TRUE';
      NO_DIR_CHECK='TRUE';
      ALLOW_CONNECT='TRUE';
      PINUSE='UNSPEC';
  end_pin;
  body
      PART_NAME='PI5A3157BC6E-GP';
      BODY_NAME='PI5A3157BC6E-GP';
      PHYS_DES_PREFIX='U';
      CLASS='IC';
      DESCRIPTION='IC SPDT CMOS SW PI5A3157BC6E SC70 6P';
      JEDEC_TYPE='SC70-6H44';
      PARENT_PART_TYPE='PI5A3157BC6E-GP';
      PARENT_PPT='PI5A3157BC6E-GP';
      PARENT_PPT_PART='PI5A3157BC6E-GP_DISCRET-GC2-PI5A3157BC6E-GP,073.53157.000J';
  end_body;
end_primitive;
primitive 'PIN-CON3-27-GP_CONN-G7-PIN-CONA';
  pin
    '1':
      PIN_NUMBER='(1)';
      PIN_TYPE='ANALOG';
      NO_LOAD_CHECK='Both';
      NO_IO_CHECK='Both';
      NO_ASSERT_CHECK='TRUE';
      NO_DIR_CHECK='TRUE';
      ALLOW_CONNECT='TRUE';
      PINUSE='UNSPEC';
    '2':
      PIN_NUMBER='(2)';
      PIN_TYPE='ANALOG';
      NO_LOAD_CHECK='Both';
      NO_IO_CHECK='Both';
      NO_ASSERT_CHECK='TRUE';
      NO_DIR_CHECK='TRUE';
      ALLOW_CONNECT='TRUE';
      PINUSE='UNSPEC';
    '3':
      PIN_NUMBER='(3)';
      PIN_TYPE='ANALOG';
      NO_LOAD_CHECK='Both';
      NO_IO_CHECK='Both';
      NO_ASSERT_CHECK='TRUE';
      NO_DIR_CHECK='TRUE';
      ALLOW_CONNECT='TRUE';
      PINUSE='UNSPEC';
  end_pin;
  body
      PART_NAME='PIN-CON3-27-GP';
      BODY_NAME='PIN-CON3-27-GP';
      PHYS_DES_PREFIX='CN';
      CLASS='DISCRETE';
      DESCRIPTION='HEAD ML 1R3P 210-HP1-03GBEF';
      JEDEC_TYPE='210-HP1-03GBEF';
      PARENT_PART_TYPE='PIN-CON3-27-GP';
      PARENT_PPT='PIN-CON3-27-GP';
      PARENT_PPT_PART='PIN-CON3-27-GP_CONN-G7-PIN-CON3-27-GP,021.60545.0103';
  end_body;
end_primitive;
primitive 'POLYSW-1D1A6V-2-GP-U_DISCRET-GA';
  pin
    '1':
      PIN_NUMBER='(1)';
      PIN_TYPE='ANALOG';
      NO_LOAD_CHECK='Both';
      NO_IO_CHECK='Both';
      NO_ASSERT_CHECK='TRUE';
      NO_DIR_CHECK='TRUE';
      ALLOW_CONNECT='TRUE';
      PINUSE='UNSPEC';
    '2':
      PIN_NUMBER='(2)';
      PIN_TYPE='ANALOG';
      NO_LOAD_CHECK='Both';
      NO_IO_CHECK='Both';
      NO_ASSERT_CHECK='TRUE';
      NO_DIR_CHECK='TRUE';
      ALLOW_CONNECT='TRUE';
      PINUSE='UNSPEC';
  end_pin;
  body
      PART_NAME='POLYSW-1D1A6V-2-GP-U';
      BODY_NAME='POLYSW-1D1A6V-2-GP-U';
      PHYS_DES_PREFIX='F';
      CLASS='DISCRETE';
      DESCRIPTION='POLYSW 8V/1.1A 1206L110THYR PTC SMD';
      JEDEC_TYPE='POLYSW-3217-UH24';
      PARENT_PART_TYPE='POLYSW-1D1A6V-2-GP-U';
      PARENT_PPT='POLYSW-1D1A6V-2-GP-U';
      PARENT_PPT_PART='POLYSW-1D1A6V-2-GP-U_DISCRET-G7-POLYSW-1D1A6V-2-GP-U,69.50007.D81';
  end_body;
end_primitive;
primitive 'POLYSW-D5A6V-2-GP-U_DISCRET-GAA';
  pin
    '1':
      PIN_NUMBER='(1)';
      PIN_TYPE='ANALOG';
      NO_LOAD_CHECK='Both';
      NO_IO_CHECK='Both';
      NO_ASSERT_CHECK='TRUE';
      NO_DIR_CHECK='TRUE';
      ALLOW_CONNECT='TRUE';
      PINUSE='UNSPEC';
    '2':
      PIN_NUMBER='(2)';
      PIN_TYPE='ANALOG';
      NO_LOAD_CHECK='Both';
      NO_IO_CHECK='Both';
      NO_ASSERT_CHECK='TRUE';
      NO_DIR_CHECK='TRUE';
      ALLOW_CONNECT='TRUE';
      PINUSE='UNSPEC';
  end_pin;
  body
      PART_NAME='POLYSW-D5A6V-2-GP-U';
      BODY_NAME='POLYSW-D5A6V-2-GP-U';
      PHYS_DES_PREFIX='F';
      CLASS='DISCRETE';
      DESCRIPTION='POLYSW 0.5A 6V 0805L050WRHF SMD';
      JEDEC_TYPE='POLYSW-2114H50';
      PARENT_PART_TYPE='POLYSW-D5A6V-2-GP-U';
      PARENT_PPT='POLYSW-D5A6V-2-GP-U';
      PARENT_PPT_PART='POLYSW-D5A6V-2-GP-U_DISCRET-GA1-POLYSW-D5A6V-2-GP-U,69.50011.051';
  end_body;
end_primitive;
primitive 'PXE1110B_QFN-IC,H89187-001';
  pin
    'DNC'<0>:
      PIN_NUMBER='(1)';
      PINUSE='NC';
      NO_LOAD_CHECK='Both';
      NO_IO_CHECK='Both';
      NO_ASSERT_CHECK='TRUE';
      NO_DIR_CHECK='TRUE';
      ALLOW_CONNECT='TRUE';
    'DNC'<1>:
      PIN_NUMBER='(2)';
      PINUSE='NC';
      NO_LOAD_CHECK='Both';
      NO_IO_CHECK='Both';
      NO_ASSERT_CHECK='TRUE';
      NO_DIR_CHECK='TRUE';
      ALLOW_CONNECT='TRUE';
    'BPWM1':
      PIN_NUMBER='(3)';
      OUTPUT_LOAD='(1.0,-1.0)';
      PINUSE='OUT';
    'DNC'<2>:
      PIN_NUMBER='(4)';
      PINUSE='NC';
      NO_LOAD_CHECK='Both';
      NO_IO_CHECK='Both';
      NO_ASSERT_CHECK='TRUE';
      NO_DIR_CHECK='TRUE';
      ALLOW_CONNECT='TRUE';
    'APWM1':
      PIN_NUMBER='(5)';
      OUTPUT_LOAD='(1.0,-1.0)';
      PINUSE='OUT';
    'SDA':
      PIN_NUMBER='(6)';
      BIDIRECTIONAL='TRUE';
      INPUT_LOAD='(-0.01,0.01)';
      OUTPUT_LOAD='(1.0,-1.0)';
      PINUSE='BI';
    'SCL':
      PIN_NUMBER='(7)';
      BIDIRECTIONAL='TRUE';
      INPUT_LOAD='(-0.01,0.01)';
      OUTPUT_LOAD='(1.0,-1.0)';
      PINUSE='BI';
    'RESET_N':
      PIN_NUMBER='(8)';
      INPUT_LOAD='(-0.01,0.01)';
      PINUSE='IN';
    'AVRRDY':
      PIN_NUMBER='(9)';
      OUTPUT_LOAD='(1.0,-1.0)';
      PINUSE='OUT';
    'AVREN':
      PIN_NUMBER='(10)';
      INPUT_LOAD='(-0.01,0.01)';
      PINUSE='IN';
    'VRHOT_N':
      PIN_NUMBER='(11)';
      OUTPUT_LOAD='(1.0,-1.0)';
      PINUSE='OUT';
    'PINALRT_N':
      PIN_NUMBER='(12)';
      OUTPUT_LOAD='(1.0,-1.0)';
      PINUSE='OUT';
    'MP0':
      PIN_NUMBER='(13)';
      BIDIRECTIONAL='TRUE';
      INPUT_LOAD='(-0.01,0.01)';
      OUTPUT_LOAD='(1.0,-1.0)';
      PINUSE='BI';
    'MP1':
      PIN_NUMBER='(14)';
      BIDIRECTIONAL='TRUE';
      INPUT_LOAD='(-0.01,0.01)';
      OUTPUT_LOAD='(1.0,-1.0)';
      PINUSE='BI';
    'VCLK':
      PIN_NUMBER='(15)';
      INPUT_LOAD='(-0.01,0.01)';
      PINUSE='IN';
    'VDIO':
      PIN_NUMBER='(16)';
      BIDIRECTIONAL='TRUE';
      INPUT_LOAD='(-0.01,0.01)';
      OUTPUT_LOAD='(1.0,-1.0)';
      PINUSE='BI';
    'VALRT_N':
      PIN_NUMBER='(17)';
      OUTPUT_LOAD='(1.0,-1.0)';
      PINUSE='OUT';
    'MP2':
      PIN_NUMBER='(18)';
      OUTPUT_LOAD='(1.0,-1.0)';
      PINUSE='OUT';
    'AVSEN':
      PIN_NUMBER='(19)';
      INPUT_LOAD='(-0.01,0.01)';
      PINUSE='IN';
    'AVREF':
      PIN_NUMBER='(20)';
      INPUT_LOAD='(-0.01,0.01)';
      PINUSE='IN';
    'AIREF1':
      PIN_NUMBER='(21)';
      INPUT_LOAD='(-0.01,0.01)';
      PINUSE='IN';
    'AISEN1':
      PIN_NUMBER='(22)';
      INPUT_LOAD='(-0.01,0.01)';
      PINUSE='IN';
    'GND'<1>:
      PIN_NUMBER='(23)';
      PINUSE='GROUND';
      NO_LOAD_CHECK='Both';
      NO_IO_CHECK='Both';
      NO_ASSERT_CHECK='TRUE';
      NO_DIR_CHECK='TRUE';
      ALLOW_CONNECT='TRUE';
    'DNC'<3>:
      PIN_NUMBER='(24)';
      PINUSE='NC';
      NO_LOAD_CHECK='Both';
      NO_IO_CHECK='Both';
      NO_ASSERT_CHECK='TRUE';
      NO_DIR_CHECK='TRUE';
      ALLOW_CONNECT='TRUE';
    'BIREF1':
      PIN_NUMBER='(25)';
      INPUT_LOAD='(-0.01,0.01)';
      PINUSE='IN';
    'BISEN1':
      PIN_NUMBER='(26)';
      INPUT_LOAD='(-0.01,0.01)';
      PINUSE='IN';
    'GND'<0>:
      PIN_NUMBER='(27)';
      PINUSE='GROUND';
      NO_LOAD_CHECK='Both';
      NO_IO_CHECK='Both';
      NO_ASSERT_CHECK='TRUE';
      NO_DIR_CHECK='TRUE';
      ALLOW_CONNECT='TRUE';
    'DNC'<4>:
      PIN_NUMBER='(28)';
      PINUSE='NC';
      NO_LOAD_CHECK='Both';
      NO_IO_CHECK='Both';
      NO_ASSERT_CHECK='TRUE';
      NO_DIR_CHECK='TRUE';
      ALLOW_CONNECT='TRUE';
    'BVSEN':
      PIN_NUMBER='(29)';
      INPUT_LOAD='(-0.01,0.01)';
      PINUSE='IN';
    'BVREF':
      PIN_NUMBER='(30)';
      INPUT_LOAD='(-0.01,0.01)';
      PINUSE='IN';
    'MP3':
      PIN_NUMBER='(31)';
      BIDIRECTIONAL='TRUE';
      INPUT_LOAD='(-0.01,0.01)';
      OUTPUT_LOAD='(1.0,-1.0)';
      PINUSE='BI';
    'MP4':
      PIN_NUMBER='(32)';
      BIDIRECTIONAL='TRUE';
      INPUT_LOAD='(-0.01,0.01)';
      OUTPUT_LOAD='(1.0,-1.0)';
      PINUSE='BI';
    'XADDR2':
      PIN_NUMBER='(33)';
      INPUT_LOAD='(-0.01,0.01)';
      PINUSE='IN';
    'BTSEN':
      PIN_NUMBER='(34)';
      INPUT_LOAD='(-0.01,0.01)';
      PINUSE='IN';
    'ATSEN':
      PIN_NUMBER='(35)';
      INPUT_LOAD='(-0.01,0.01)';
      PINUSE='IN';
    'XADDR1':
      PIN_NUMBER='(36)';
      INPUT_LOAD='(-0.01,0.01)';
      PINUSE='IN';
    'VINSEN':
      PIN_NUMBER='(37)';
      INPUT_LOAD='(-0.01,0.01)';
      PINUSE='IN';
    'IINSEN':
      PIN_NUMBER='(38)';
      INPUT_LOAD='(-0.01,0.01)';
      PINUSE='IN';
    'VDD':
      PIN_NUMBER='(39)';
      PINUSE='POWER';
      NO_LOAD_CHECK='Both';
      NO_IO_CHECK='Both';
      NO_ASSERT_CHECK='TRUE';
      NO_DIR_CHECK='TRUE';
      ALLOW_CONNECT='TRUE';
    'VD12':
      PIN_NUMBER='(40)';
      PINUSE='POWER';
      NO_LOAD_CHECK='Both';
      NO_IO_CHECK='Both';
      NO_ASSERT_CHECK='TRUE';
      NO_DIR_CHECK='TRUE';
      ALLOW_CONNECT='TRUE';
    'THPAD':
      PIN_NUMBER='(41)';
      PINUSE='GROUND';
      NO_LOAD_CHECK='Both';
      NO_IO_CHECK='Both';
      NO_ASSERT_CHECK='TRUE';
      NO_DIR_CHECK='TRUE';
      ALLOW_CONNECT='TRUE';
  end_pin;
  body
      PART_NAME='PXE1110B';
      PHYS_DES_PREFIX='EU';
      ENVCOMP='';
      PART_NUMBER='H89187-001';
      JEDEC_TYPE='QFN40_20_4MB';
      DESCRIPTION='IC,LIN,QFN,PXE1110B,CONTROLR';
      CLASS='IC';
      COMPONENT_TYPE='LCC';
      HEIGHT='0.035 IN';
      LPID='3556';
      SPEED_URL='http://speed.intel.com:8081/speed/module/pdm/item/pdm_item_deta~
il_direct.asp?item_cde=H89187-001&item_rev=01&url_param=unused';
      STATUS='';
      RPL='';
      AML='';
      BUS_UNIT='';
      DAYS='';
      PARENT_PART_TYPE='PXE1110B_QFN';
      PARENT_PPT='PXE1110B';
      PARENT_PPT_PART='PXE1110B_QFN-IC,H89187-001';
  end_body;
end_primitive;
primitive 'PXE1610B_QFN-IC,H79206-001';
  pin
    'BPWM1':
      PIN_NUMBER='(1)';
      OUTPUT_LOAD='(1.0,-1.0)';
      PINUSE='OUT';
    'APWM6':
      PIN_NUMBER='(2)';
      OUTPUT_LOAD='(1.0,-1.0)';
      PINUSE='OUT';
    'APWM5':
      PIN_NUMBER='(3)';
      OUTPUT_LOAD='(1.0,-1.0)';
      PINUSE='OUT';
    'APWM4':
      PIN_NUMBER='(4)';
      OUTPUT_LOAD='(1.0,-1.0)';
      PINUSE='OUT';
    'APWM3':
      PIN_NUMBER='(5)';
      OUTPUT_LOAD='(1.0,-1.0)';
      PINUSE='OUT';
    'APWM2':
      PIN_NUMBER='(6)';
      OUTPUT_LOAD='(1.0,-1.0)';
      PINUSE='OUT';
    'APWM1':
      PIN_NUMBER='(7)';
      OUTPUT_LOAD='(1.0,-1.0)';
      PINUSE='OUT';
    'SDA':
      PIN_NUMBER='(8)';
      BIDIRECTIONAL='TRUE';
      INPUT_LOAD='(-0.01,0.01)';
      OUTPUT_LOAD='(1.0,-1.0)';
      PINUSE='BI';
    'SCL':
      PIN_NUMBER='(9)';
      BIDIRECTIONAL='TRUE';
      INPUT_LOAD='(-0.01,0.01)';
      OUTPUT_LOAD='(1.0,-1.0)';
      PINUSE='BI';
    'RESET_N':
      PIN_NUMBER='(10)';
      INPUT_LOAD='(-0.01,0.01)';
      PINUSE='IN';
    'AVRRDY':
      PIN_NUMBER='(11)';
      OUTPUT_LOAD='(1.0,-1.0)';
      PINUSE='OUT';
    'AVREN':
      PIN_NUMBER='(12)';
      INPUT_LOAD='(-0.01,0.01)';
      PINUSE='IN';
    'VRHOT_N':
      PIN_NUMBER='(13)';
      OUTPUT_LOAD='(1.0,-1.0)';
      PINUSE='OUT';
    'PINALRT_N':
      PIN_NUMBER='(14)';
      OUTPUT_LOAD='(1.0,-1.0)';
      PINUSE='OUT';
    'MP0':
      PIN_NUMBER='(15)';
      BIDIRECTIONAL='TRUE';
      INPUT_LOAD='(-0.01,0.01)';
      OUTPUT_LOAD='(1.0,-1.0)';
      PINUSE='BI';
    'MP1':
      PIN_NUMBER='(16)';
      BIDIRECTIONAL='TRUE';
      INPUT_LOAD='(-0.01,0.01)';
      OUTPUT_LOAD='(1.0,-1.0)';
      PINUSE='BI';
    'VCLK':
      PIN_NUMBER='(17)';
      INPUT_LOAD='(-0.01,0.01)';
      PINUSE='IN';
    'VDIO':
      PIN_NUMBER='(18)';
      BIDIRECTIONAL='TRUE';
      INPUT_LOAD='(-0.01,0.01)';
      OUTPUT_LOAD='(1.0,-1.0)';
      PINUSE='BI';
    'VALRT_N':
      PIN_NUMBER='(19)';
      OUTPUT_LOAD='(1.0,-1.0)';
      PINUSE='OUT';
    'MP2':
      PIN_NUMBER='(20)';
      OUTPUT_LOAD='(1.0,-1.0)';
      PINUSE='OUT';
    'AVSEN':
      PIN_NUMBER='(21)';
      INPUT_LOAD='(-0.01,0.01)';
      PINUSE='IN';
    'AVREF':
      PIN_NUMBER='(22)';
      INPUT_LOAD='(-0.01,0.01)';
      PINUSE='IN';
    'AIREF1':
      PIN_NUMBER='(23)';
      INPUT_LOAD='(-0.01,0.01)';
      PINUSE='IN';
    'AISEN1':
      PIN_NUMBER='(24)';
      INPUT_LOAD='(-0.01,0.01)';
      PINUSE='IN';
    'AIREF2':
      PIN_NUMBER='(25)';
      INPUT_LOAD='(-0.01,0.01)';
      PINUSE='IN';
    'AISEN2':
      PIN_NUMBER='(26)';
      INPUT_LOAD='(-0.01,0.01)';
      PINUSE='IN';
    'AIREF3':
      PIN_NUMBER='(27)';
      INPUT_LOAD='(-0.01,0.01)';
      PINUSE='IN';
    'AISEN3':
      PIN_NUMBER='(28)';
      INPUT_LOAD='(-0.01,0.01)';
      PINUSE='IN';
    'AIREF4':
      PIN_NUMBER='(29)';
      INPUT_LOAD='(-0.01,0.01)';
      PINUSE='IN';
    'AISEN4':
      PIN_NUMBER='(30)';
      INPUT_LOAD='(-0.01,0.01)';
      PINUSE='IN';
    'AIREF5':
      PIN_NUMBER='(31)';
      INPUT_LOAD='(-0.01,0.01)';
      PINUSE='IN';
    'AISEN5':
      PIN_NUMBER='(32)';
      INPUT_LOAD='(-0.01,0.01)';
      PINUSE='IN';
    'AIREF6':
      PIN_NUMBER='(33)';
      INPUT_LOAD='(-0.01,0.01)';
      PINUSE='IN';
    'AISEN6':
      PIN_NUMBER='(34)';
      INPUT_LOAD='(-0.01,0.01)';
      PINUSE='IN';
    'BVSEN':
      PIN_NUMBER='(35)';
      INPUT_LOAD='(-0.01,0.01)';
      PINUSE='IN';
    'BVREF':
      PIN_NUMBER='(36)';
      INPUT_LOAD='(-0.01,0.01)';
      PINUSE='IN';
    'BIREF1':
      PIN_NUMBER='(37)';
      INPUT_LOAD='(-0.01,0.01)';
      PINUSE='IN';
    'BISEN1':
      PIN_NUMBER='(38)';
      INPUT_LOAD='(-0.01,0.01)';
      PINUSE='IN';
    'MP3':
      PIN_NUMBER='(39)';
      OUTPUT_LOAD='(1.0,-1.0)';
      PINUSE='OUT';
    'MP4':
      PIN_NUMBER='(40)';
      OUTPUT_LOAD='(1.0,-1.0)';
      PINUSE='OUT';
    'XADDR2':
      PIN_NUMBER='(41)';
      INPUT_LOAD='(-0.01,0.01)';
      PINUSE='IN';
    'BTSEN':
      PIN_NUMBER='(42)';
      INPUT_LOAD='(-0.01,0.01)';
      PINUSE='IN';
    'ATSEN':
      PIN_NUMBER='(43)';
      INPUT_LOAD='(-0.01,0.01)';
      PINUSE='IN';
    'XADDR1':
      PIN_NUMBER='(44)';
      INPUT_LOAD='(-0.01,0.01)';
      PINUSE='IN';
    'VINSEN':
      PIN_NUMBER='(45)';
      INPUT_LOAD='(-0.01,0.01)';
      PINUSE='IN';
    'IINSEN':
      PIN_NUMBER='(46)';
      INPUT_LOAD='(-0.01,0.01)';
      PINUSE='IN';
    'VDD':
      PIN_NUMBER='(47)';
      PINUSE='POWER';
      NO_LOAD_CHECK='Both';
      NO_IO_CHECK='Both';
      NO_ASSERT_CHECK='TRUE';
      NO_DIR_CHECK='TRUE';
      ALLOW_CONNECT='TRUE';
    'VD12':
      PIN_NUMBER='(48)';
      PINUSE='POWER';
      NO_LOAD_CHECK='Both';
      NO_IO_CHECK='Both';
      NO_ASSERT_CHECK='TRUE';
      NO_DIR_CHECK='TRUE';
      ALLOW_CONNECT='TRUE';
    'THPAD':
      PIN_NUMBER='(49)';
      PINUSE='GROUND';
      NO_LOAD_CHECK='Both';
      NO_IO_CHECK='Both';
      NO_ASSERT_CHECK='TRUE';
      NO_DIR_CHECK='TRUE';
      ALLOW_CONNECT='TRUE';
  end_pin;
  body
      PART_NAME='PXE1610B';
      PHYS_DES_PREFIX='EU';
      ENVCOMP='';
      PART_NUMBER='H79206-001';
      JEDEC_TYPE='QFN48_24_4MH';
      DESCRIPTION='IC,LIN,QFN,PXE1610B,CONTROLR';
      CLASS='IC';
      COMPONENT_TYPE='LCC';
      HEIGHT='0.035 IN';
      LPID='3252';
      SPEED_URL='http://speed.intel.com:8081/speed/module/pdm/item/pdm_item_deta~
il_direct.asp?item_cde=H79206-001&item_rev=01&url_param=unused';
      STATUS='';
      RPL='';
      AML='';
      BUS_UNIT='';
      DAYS='';
      PARENT_PART_TYPE='PXE1610B_QFN';
      PARENT_PPT='PXE1610B';
      PARENT_PPT_PART='PXE1610B_QFN-IC,H79206-001';
  end_body;
end_primitive;
primitive 'PXM1310B_QFN-IC,H89186-001';
  pin
    'BPWM1':
      PIN_NUMBER='(1)';
      OUTPUT_LOAD='(1.0,-1.0)';
      PINUSE='OUT';
    'DNC'<0>:
      PIN_NUMBER='(2)';
      PINUSE='NC';
      NO_LOAD_CHECK='Both';
      NO_IO_CHECK='Both';
      NO_ASSERT_CHECK='TRUE';
      NO_DIR_CHECK='TRUE';
      ALLOW_CONNECT='TRUE';
    'APWM3':
      PIN_NUMBER='(3)';
      OUTPUT_LOAD='(1.0,-1.0)';
      PINUSE='OUT';
    'APWM2':
      PIN_NUMBER='(4)';
      OUTPUT_LOAD='(1.0,-1.0)';
      PINUSE='OUT';
    'APWM1':
      PIN_NUMBER='(5)';
      OUTPUT_LOAD='(1.0,-1.0)';
      PINUSE='OUT';
    'SDA':
      PIN_NUMBER='(6)';
      BIDIRECTIONAL='TRUE';
      INPUT_LOAD='(-0.01,0.01)';
      OUTPUT_LOAD='(1.0,-1.0)';
      PINUSE='BI';
    'SCL':
      PIN_NUMBER='(7)';
      BIDIRECTIONAL='TRUE';
      INPUT_LOAD='(-0.01,0.01)';
      OUTPUT_LOAD='(1.0,-1.0)';
      PINUSE='BI';
    'RESET_N':
      PIN_NUMBER='(8)';
      INPUT_LOAD='(-0.01,0.01)';
      PINUSE='IN';
    'AVRRDY':
      PIN_NUMBER='(9)';
      OUTPUT_LOAD='(1.0,-1.0)';
      PINUSE='OUT';
    'AVREN':
      PIN_NUMBER='(10)';
      INPUT_LOAD='(-0.01,0.01)';
      PINUSE='IN';
    'VRHOT_N':
      PIN_NUMBER='(11)';
      OUTPUT_LOAD='(1.0,-1.0)';
      PINUSE='OUT';
    'PINALRT_N':
      PIN_NUMBER='(12)';
      OUTPUT_LOAD='(1.0,-1.0)';
      PINUSE='OUT';
    'MP0':
      PIN_NUMBER='(13)';
      BIDIRECTIONAL='TRUE';
      INPUT_LOAD='(-0.01,0.01)';
      OUTPUT_LOAD='(1.0,-1.0)';
      PINUSE='BI';
    'MP1':
      PIN_NUMBER='(14)';
      BIDIRECTIONAL='TRUE';
      INPUT_LOAD='(-0.01,0.01)';
      OUTPUT_LOAD='(1.0,-1.0)';
      PINUSE='BI';
    'VCLK':
      PIN_NUMBER='(15)';
      INPUT_LOAD='(-0.01,0.01)';
      PINUSE='IN';
    'VDIO':
      PIN_NUMBER='(16)';
      BIDIRECTIONAL='TRUE';
      INPUT_LOAD='(-0.01,0.01)';
      OUTPUT_LOAD='(1.0,-1.0)';
      PINUSE='BI';
    'VALRT_N':
      PIN_NUMBER='(17)';
      OUTPUT_LOAD='(1.0,-1.0)';
      PINUSE='OUT';
    'MP2':
      PIN_NUMBER='(18)';
      BIDIRECTIONAL='TRUE';
      INPUT_LOAD='(-0.01,0.01)';
      OUTPUT_LOAD='(1.0,-1.0)';
      PINUSE='BI';
    'AVSEN':
      PIN_NUMBER='(19)';
      INPUT_LOAD='(-0.01,0.01)';
      PINUSE='IN';
    'AVREF':
      PIN_NUMBER='(20)';
      INPUT_LOAD='(-0.01,0.01)';
      PINUSE='IN';
    'AIREF1':
      PIN_NUMBER='(21)';
      INPUT_LOAD='(-0.01,0.01)';
      PINUSE='IN';
    'AISEN1':
      PIN_NUMBER='(22)';
      INPUT_LOAD='(-0.01,0.01)';
      PINUSE='IN';
    'AIREF2':
      PIN_NUMBER='(23)';
      INPUT_LOAD='(-0.01,0.01)';
      PINUSE='IN';
    'AISEN2':
      PIN_NUMBER='(24)';
      INPUT_LOAD='(-0.01,0.01)';
      PINUSE='IN';
    'AIREF3':
      PIN_NUMBER='(25)';
      INPUT_LOAD='(-0.01,0.01)';
      PINUSE='IN';
    'AISEN3':
      PIN_NUMBER='(26)';
      INPUT_LOAD='(-0.01,0.01)';
      PINUSE='IN';
    'GND':
      PIN_NUMBER='(27)';
      PINUSE='GROUND';
      NO_LOAD_CHECK='Both';
      NO_IO_CHECK='Both';
      NO_ASSERT_CHECK='TRUE';
      NO_DIR_CHECK='TRUE';
      ALLOW_CONNECT='TRUE';
    'DNC'<1>:
      PIN_NUMBER='(28)';
      PINUSE='NC';
      NO_LOAD_CHECK='Both';
      NO_IO_CHECK='Both';
      NO_ASSERT_CHECK='TRUE';
      NO_DIR_CHECK='TRUE';
      ALLOW_CONNECT='TRUE';
    'BVSEN':
      PIN_NUMBER='(29)';
      INPUT_LOAD='(-0.01,0.01)';
      PINUSE='IN';
    'BVREF':
      PIN_NUMBER='(30)';
      INPUT_LOAD='(-0.01,0.01)';
      PINUSE='IN';
    'BIREF1':
      PIN_NUMBER='(31)';
      INPUT_LOAD='(-0.01,0.01)';
      PINUSE='IN';
    'BISEN1':
      PIN_NUMBER='(32)';
      INPUT_LOAD='(-0.01,0.01)';
      PINUSE='IN';
    'XADDR2':
      PIN_NUMBER='(33)';
      INPUT_LOAD='(-0.01,0.01)';
      PINUSE='IN';
    'BTSEN':
      PIN_NUMBER='(34)';
      INPUT_LOAD='(-0.01,0.01)';
      PINUSE='IN';
    'ATSEN':
      PIN_NUMBER='(35)';
      INPUT_LOAD='(-0.01,0.01)';
      PINUSE='IN';
    'XADDR1':
      PIN_NUMBER='(36)';
      INPUT_LOAD='(-0.01,0.01)';
      PINUSE='IN';
    'VINSEN':
      PIN_NUMBER='(37)';
      INPUT_LOAD='(-0.01,0.01)';
      PINUSE='IN';
    'IINSEN':
      PIN_NUMBER='(38)';
      INPUT_LOAD='(-0.01,0.01)';
      PINUSE='IN';
    'VDD':
      PIN_NUMBER='(39)';
      PINUSE='POWER';
      NO_LOAD_CHECK='Both';
      NO_IO_CHECK='Both';
      NO_ASSERT_CHECK='TRUE';
      NO_DIR_CHECK='TRUE';
      ALLOW_CONNECT='TRUE';
    'VD12':
      PIN_NUMBER='(40)';
      BIDIRECTIONAL='TRUE';
      INPUT_LOAD='(-0.01,0.01)';
      OUTPUT_LOAD='(1.0,-1.0)';
      PINUSE='BI';
    'THPAD':
      PIN_NUMBER='(41)';
      PINUSE='GROUND';
      NO_LOAD_CHECK='Both';
      NO_IO_CHECK='Both';
      NO_ASSERT_CHECK='TRUE';
      NO_DIR_CHECK='TRUE';
      ALLOW_CONNECT='TRUE';
  end_pin;
  body
      PART_NAME='PXM1310B';
      PHYS_DES_PREFIX='EU';
      ENVCOMP='';
      PART_NUMBER='H89186-001';
      JEDEC_TYPE='QFN40_20_4MB';
      DESCRIPTION='IC,LIN,QFN,PXM1310B,CONTROLR';
      CLASS='IC';
      COMPONENT_TYPE='LCC';
      HEIGHT='0.035 IN';
      LPID='3556';
      SPEED_URL='http://speed.intel.com:8081/speed/module/pdm/item/pdm_item_deta~
il_direct.asp?item_cde=H89186-001&item_rev=01&url_param=unused';
      STATUS='';
      RPL='';
      AML='';
      BUS_UNIT='';
      DAYS='';
      PARENT_PART_TYPE='PXM1310B_QFN';
      PARENT_PPT='PXM1310B';
      PARENT_PPT_PART='PXM1310B_QFN-IC,H89186-001';
  end_body;
end_primitive;
primitive 'RB551V30-GP_DISCRET-G-RB551V30A';
  pin
    'CATHODE':
      PIN_NUMBER='(K)';
      PIN_TYPE='ANALOG';
      NO_LOAD_CHECK='Both';
      NO_IO_CHECK='Both';
      NO_ASSERT_CHECK='TRUE';
      NO_DIR_CHECK='TRUE';
      ALLOW_CONNECT='TRUE';
      PINUSE='UNSPEC';
    'ANODE':
      PIN_NUMBER='(A)';
      PIN_TYPE='ANALOG';
      NO_LOAD_CHECK='Both';
      NO_IO_CHECK='Both';
      NO_ASSERT_CHECK='TRUE';
      NO_DIR_CHECK='TRUE';
      ALLOW_CONNECT='TRUE';
      PINUSE='UNSPEC';
  end_pin;
  body
      PART_NAME='RB551V30-GP';
      BODY_NAME='RB551V30-GP';
      PHYS_DES_PREFIX='D';
      CLASS='DISCRETE';
      DESCRIPTION='DIODE S.B RB551V30 0.5A 30V SOD-323';
      JEDEC_TYPE='SOD323AKH38';
      PARENT_PART_TYPE='RB551V30-GP';
      PARENT_PPT='RB551V30-GP';
      PARENT_PPT_PART='RB551V30-GP_DISCRET-G-RB551V30-GP,83.R5003.H8H';
  end_body;
end_primitive;
primitive 'RES_0402-0.0,5%,1/16W,CHIP,G21A';
  pin
    'A':
      PIN_GROUP='1';
      PIN_NUMBER='(1)';
      PIN_TYPE='UNSPEC';
      PINUSE='UNSPEC';
    'B':
      PIN_GROUP='1';
      PIN_NUMBER='(2)';
      PIN_TYPE='UNSPEC';
      PINUSE='UNSPEC';
  end_pin;
  body
      PART_NAME='RES';
      PHYS_DES_PREFIX='R';
      ENVCOMP='YES;YES;YES;UNK;OK;VLD';
      PART_NUMBER='G21497-005';
      JEDEC_TYPE='SMR0402A';
      ALT_SYMBOLS='(SMX0402,SMX0402A,SMX0402B)';
      VALUE='0.0';
      TOL='5%';
      WATTAGE='1/16W';
      CLASS='DISCRETE';
      DESCRIPTION='RES_D,0402,0.0OHM,5.00%,1/16W';
      HEIGHT='0.017 IN';
      COMPONENT_TYPE='CHIP0402';
      LEAD_LENGTH='';
      LPID='1141';
      SPEED_URL='http://speed.intel.com:8081/speed/module/pdm/item/pdm_item_deta~
il_direct.asp?item_cde=G21497-005&item_rev=01&url_param=unused';
      STATUS='UNQUAL';
      RPL='NO';
      AML='3';
      BUS_UNIT='GMPO_BD_EXMPFREE';
      DAYS='???';
      PARENT_PART_TYPE='RES';
      PARENT_PPT='RES';
      PARENT_PPT_PART='RES_0402-0.0,5%,1/16W,CHIP,G21497-005';
  end_body;
end_primitive;
primitive 'RES_0402-0.0,5%,1/16W,EMPTY,G2A';
  pin
    'A':
      PIN_GROUP='1';
      PIN_NUMBER='(1)';
      PIN_TYPE='UNSPEC';
      PINUSE='UNSPEC';
    'B':
      PIN_GROUP='1';
      PIN_NUMBER='(2)';
      PIN_TYPE='UNSPEC';
      PINUSE='UNSPEC';
  end_pin;
  body
      PART_NAME='RES';
      PHYS_DES_PREFIX='R';
      ENVCOMP='YES;YES;YES;UNK;OK;VLD';
      PART_NUMBER='G21497-005';
      JEDEC_TYPE='SMR0402A';
      ALT_SYMBOLS='(SMX0402,SMX0402A,SMX0402B)';
      VALUE='NA';
      TOL='5%';
      WATTAGE='1/16W';
      CLASS='DISCRETE';
      DESCRIPTION='RES_D,0402,0.0OHM,5.00%,1/16W';
      HEIGHT='0.017 IN';
      COMPONENT_TYPE='CHIP0402';
      LEAD_LENGTH='';
      LPID='1141';
      SPEED_URL='http://speed.intel.com:8081/speed/module/pdm/item/pdm_item_deta~
il_direct.asp?item_cde=G21497-005&item_rev=01&url_param=unused';
      STATUS='UNQUAL';
      RPL='NO';
      AML='3';
      BUS_UNIT='GMPO_BD_EXMPFREE';
      DAYS='???';
      PARENT_PART_TYPE='RES';
      PARENT_PPT='RES';
      PARENT_PPT_PART='RES_0402-0.0,5%,1/16W,EMPTY,G21497-005';
  end_body;
end_primitive;
primitive 'RES_0402-1.00K,1%,1/16W,CHIP,GA';
  pin
    'A':
      PIN_GROUP='1';
      PIN_NUMBER='(1)';
      PIN_TYPE='UNSPEC';
      PINUSE='UNSPEC';
    'B':
      PIN_GROUP='1';
      PIN_NUMBER='(2)';
      PIN_TYPE='UNSPEC';
      PINUSE='UNSPEC';
  end_pin;
  body
      PART_NAME='RES';
      PHYS_DES_PREFIX='R';
      ENVCOMP='YES;YES;YES;UNK;OK;VLD';
      PART_NUMBER='G21796-026';
      JEDEC_TYPE='SMR0402A';
      ALT_SYMBOLS='(SMX0402,SMX0402A,SMX0402B)';
      VALUE='1.00K';
      TOL='1%';
      WATTAGE='1/16W';
      CLASS='DISCRETE';
      DESCRIPTION='RES_D,0402,1.00KOHM,1.00%,1/16W';
      HEIGHT='0.017 IN';
      COMPONENT_TYPE='CHIP0402';
      LEAD_LENGTH='';
      LPID='1141';
      SPEED_URL='http://speed.intel.com:8081/speed/module/pdm/item/pdm_item_deta~
il_direct.asp?item_cde=G21796-026&item_rev=01&url_param=unused';
      STATUS='UNQUAL';
      RPL='NO';
      AML='4';
      BUS_UNIT='GMPO_BD_EXMPFREE';
      DAYS='???';
      PARENT_PART_TYPE='RES';
      PARENT_PPT='RES';
      PARENT_PPT_PART='RES_0402-1.00K,1%,1/16W,CHIP,G21796-026';
  end_body;
end_primitive;
primitive 'RES_0402-1.00K,1%,1/16W,EMPTY,A';
  pin
    'A':
      PIN_GROUP='1';
      PIN_NUMBER='(1)';
      PIN_TYPE='UNSPEC';
      PINUSE='UNSPEC';
    'B':
      PIN_GROUP='1';
      PIN_NUMBER='(2)';
      PIN_TYPE='UNSPEC';
      PINUSE='UNSPEC';
  end_pin;
  body
      PART_NAME='RES';
      PHYS_DES_PREFIX='R';
      ENVCOMP='YES;YES;YES;UNK;OK;VLD';
      PART_NUMBER='G21796-026';
      JEDEC_TYPE='SMR0402A';
      ALT_SYMBOLS='(SMX0402,SMX0402A,SMX0402B)';
      VALUE='NA';
      TOL='1%';
      WATTAGE='1/16W';
      CLASS='DISCRETE';
      DESCRIPTION='RES_D,0402,1.00KOHM,1.00%,1/16W';
      HEIGHT='0.017 IN';
      COMPONENT_TYPE='CHIP0402';
      LEAD_LENGTH='';
      LPID='1141';
      SPEED_URL='http://speed.intel.com:8081/speed/module/pdm/item/pdm_item_deta~
il_direct.asp?item_cde=G21796-026&item_rev=01&url_param=unused';
      STATUS='UNQUAL';
      RPL='NO';
      AML='4';
      BUS_UNIT='GMPO_BD_EXMPFREE';
      DAYS='???';
      PARENT_PART_TYPE='RES';
      PARENT_PPT='RES';
      PARENT_PPT_PART='RES_0402-1.00K,1%,1/16W,EMPTY,G21796-026';
  end_body;
end_primitive;
primitive 'RES_0402-1.0K,0.1%,1/16W,CHIP,A';
  pin
    'A':
      PIN_GROUP='1';
      PIN_NUMBER='(1)';
      PIN_TYPE='UNSPEC';
      PINUSE='UNSPEC';
    'B':
      PIN_GROUP='1';
      PIN_NUMBER='(2)';
      PIN_TYPE='UNSPEC';
      PINUSE='UNSPEC';
  end_pin;
  body
      PART_NAME='RES';
      PHYS_DES_PREFIX='R';
      ENVCOMP='YES;YES;YES;UNK;OK;VLD';
      PART_NUMBER='G85996-004';
      JEDEC_TYPE='SMR0402A';
      ALT_SYMBOLS='(SMX0402,SMX0402A,SMX0402B)';
      VALUE='1.0K';
      TOL='0.1%';
      WATTAGE='1/16W';
      CLASS='DISCRETE';
      DESCRIPTION='RES_D,0402,1.00KOHM,0.1%,1/16W';
      HEIGHT='0.017 IN';
      COMPONENT_TYPE='CHIP0402';
      LEAD_LENGTH='';
      LPID='1141';
      SPEED_URL='http://speed.intel.com:8081/speed/module/pdm/item/pdm_item_deta~
il_direct.asp?item_cde=G85996-004&item_rev=01&url_param=unused';
      STATUS='DESIGN';
      RPL='NO';
      AML='3';
      BUS_UNIT='GMPO_BD_EXMPFREE';
      DAYS='???';
      PARENT_PART_TYPE='RES';
      PARENT_PPT='RES';
      PARENT_PPT_PART='RES_0402-1.0K,0.1%,1/16W,CHIP,G85996-004';
  end_body;
end_primitive;
primitive 'RES_0402-1.0M,1%,1/16W,EMPTY,GA';
  pin
    'A':
      PIN_GROUP='1';
      PIN_NUMBER='(1)';
      PIN_TYPE='UNSPEC';
      PINUSE='UNSPEC';
    'B':
      PIN_GROUP='1';
      PIN_NUMBER='(2)';
      PIN_TYPE='UNSPEC';
      PINUSE='UNSPEC';
  end_pin;
  body
      PART_NAME='RES';
      PHYS_DES_PREFIX='R';
      ENVCOMP='YES;YES;YES;UNK;OK;VLD';
      PART_NUMBER='G21796-021';
      JEDEC_TYPE='SMR0402A';
      ALT_SYMBOLS='(SMX0402,SMX0402A,SMX0402B)';
      VALUE='NA';
      TOL='1%';
      WATTAGE='1/16W';
      CLASS='DISCRETE';
      DESCRIPTION='RES_D,0402,1.0MOHM,1.00%,1/16W';
      HEIGHT='0.017 IN';
      COMPONENT_TYPE='CHIP0402';
      LEAD_LENGTH='';
      LPID='1141';
      SPEED_URL='http://speed.intel.com:8081/speed/module/pdm/item/pdm_item_deta~
il_direct.asp?item_cde=G21796-021&item_rev=01&url_param=unused';
      STATUS='DESIGN';
      RPL='NO';
      AML='3';
      BUS_UNIT='GMPO_BD_EXMPFREE';
      DAYS='???';
      PARENT_PART_TYPE='RES';
      PARENT_PPT='RES';
      PARENT_PPT_PART='RES_0402-1.0M,1%,1/16W,EMPTY,G21796-021';
  end_body;
end_primitive;
primitive 'RES_0402-1.37K,1%,1/16W,CHIP,GA';
  pin
    'A':
      PIN_GROUP='1';
      PIN_NUMBER='(1)';
      PIN_TYPE='UNSPEC';
      PINUSE='UNSPEC';
    'B':
      PIN_GROUP='1';
      PIN_NUMBER='(2)';
      PIN_TYPE='UNSPEC';
      PINUSE='UNSPEC';
  end_pin;
  body
      PART_NAME='RES';
      PHYS_DES_PREFIX='R';
      ENVCOMP='YES;YES;YES;UNK;OK;VLD';
      PART_NUMBER='G21796-095';
      JEDEC_TYPE='SMR0402A';
      ALT_SYMBOLS='(SMX0402,SMX0402A,SMX0402B)';
      VALUE='1.37K';
      TOL='1%';
      WATTAGE='1/16W';
      CLASS='DISCRETE';
      DESCRIPTION='RES_D,0402,1.37KOHM,1.00%,1/16W';
      HEIGHT='0.017 IN';
      COMPONENT_TYPE='CHIP0402';
      LEAD_LENGTH='';
      LPID='1141';
      SPEED_URL='http://speed.intel.com:8081/speed/module/pdm/item/pdm_item_deta~
il_direct.asp?item_cde=G21796-095&item_rev=01&url_param=unused';
      STATUS='DESIGN';
      RPL='NO';
      AML='3';
      BUS_UNIT='GMPO_BD_EXMPFREE';
      DAYS='???';
      PARENT_PART_TYPE='RES';
      PARENT_PPT='RES';
      PARENT_PPT_PART='RES_0402-1.37K,1%,1/16W,CHIP,G21796-095';
  end_body;
end_primitive;
primitive 'RES_0402-1.5K,1%,1/16W,CHIP,G2A';
  pin
    'A':
      PIN_GROUP='1';
      PIN_NUMBER='(1)';
      PIN_TYPE='UNSPEC';
      PINUSE='UNSPEC';
    'B':
      PIN_GROUP='1';
      PIN_NUMBER='(2)';
      PIN_TYPE='UNSPEC';
      PINUSE='UNSPEC';
  end_pin;
  body
      PART_NAME='RES';
      PHYS_DES_PREFIX='R';
      ENVCOMP='YES;YES;YES;UNK;OK;VLD';
      PART_NUMBER='G21796-003';
      JEDEC_TYPE='SMR0402A';
      ALT_SYMBOLS='(SMX0402,SMX0402A,SMX0402B)';
      VALUE='1.5K';
      TOL='1%';
      WATTAGE='1/16W';
      CLASS='DISCRETE';
      DESCRIPTION='RES_D,0402,1.5KOHM,1.00%,1/16W';
      HEIGHT='0.017 IN';
      COMPONENT_TYPE='CHIP0402';
      LEAD_LENGTH='';
      LPID='1141';
      SPEED_URL='http://speed.intel.com:8081/speed/module/pdm/item/pdm_item_deta~
il_direct.asp?item_cde=G21796-003&item_rev=01&url_param=unused';
      STATUS='DESIGN';
      RPL='NO';
      AML='3';
      BUS_UNIT='GMPO_BD_EXMPFREE';
      DAYS='???';
      PARENT_PART_TYPE='RES';
      PARENT_PPT='RES';
      PARENT_PPT_PART='RES_0402-1.5K,1%,1/16W,CHIP,G21796-003';
  end_body;
end_primitive;
primitive 'RES_0402-1.8K,1%,1/16W,CHIP,G2A';
  pin
    'A':
      PIN_GROUP='1';
      PIN_NUMBER='(1)';
      PIN_TYPE='UNSPEC';
      PINUSE='UNSPEC';
    'B':
      PIN_GROUP='1';
      PIN_NUMBER='(2)';
      PIN_TYPE='UNSPEC';
      PINUSE='UNSPEC';
  end_pin;
  body
      PART_NAME='RES';
      PHYS_DES_PREFIX='R';
      ENVCOMP='';
      PART_NUMBER='G21796-336';
      JEDEC_TYPE='SMR0402A';
      ALT_SYMBOLS='(SMX0402,SMX0402A,SMX0402B)';
      VALUE='1.8K';
      TOL='1%';
      WATTAGE='1/16W';
      CLASS='DISCRETE';
      DESCRIPTION='RES_D,0402,1.80kOHM,1.00%,1/16W,';
      HEIGHT='0.016 IN';
      COMPONENT_TYPE='CHIP0402';
      LEAD_LENGTH='';
      LPID='1141';
      SPEED_URL='http://speed.intel.com:8081/speed/module/pdm/item/pdm_item_deta~
il_direct.asp?item_cde=G21796-336&item_rev=01&url_param=unused';
      STATUS='';
      RPL='';
      AML='';
      BUS_UNIT='';
      DAYS='';
      PARENT_PART_TYPE='RES';
      PARENT_PPT='RES';
      PARENT_PPT_PART='RES_0402-1.8K,1%,1/16W,CHIP,G21796-336';
  end_body;
end_primitive;
primitive 'RES_0402-10.0,1%,1/16W,CHIP,G2A';
  pin
    'A':
      PIN_GROUP='1';
      PIN_NUMBER='(1)';
      PIN_TYPE='UNSPEC';
      PINUSE='UNSPEC';
    'B':
      PIN_GROUP='1';
      PIN_NUMBER='(2)';
      PIN_TYPE='UNSPEC';
      PINUSE='UNSPEC';
  end_pin;
  body
      PART_NAME='RES';
      PHYS_DES_PREFIX='R';
      ENVCOMP='YES;YES;YES;UNK;OK;VLD';
      PART_NUMBER='G21796-066';
      JEDEC_TYPE='SMR0402A';
      ALT_SYMBOLS='(SMX0402,SMX0402A,SMX0402B)';
      VALUE='10.0';
      TOL='1%';
      WATTAGE='1/16W';
      CLASS='DISCRETE';
      DESCRIPTION='RES_D,0402,10.0OHM,1.00%,1/16W';
      HEIGHT='0.017 IN';
      COMPONENT_TYPE='CHIP0402';
      LEAD_LENGTH='';
      LPID='1141';
      SPEED_URL='http://speed.intel.com:8081/speed/module/pdm/item/pdm_item_deta~
il_direct.asp?item_cde=G21796-066&item_rev=01&url_param=unused';
      STATUS='UNQUAL';
      RPL='NO';
      AML='3';
      BUS_UNIT='GMPO_BD_EXMPFREE';
      DAYS='???';
      PARENT_PART_TYPE='RES';
      PARENT_PPT='RES';
      PARENT_PPT_PART='RES_0402-10.0,1%,1/16W,CHIP,G21796-066';
  end_body;
end_primitive;
primitive 'RES_0402-10.0,1%,1/16W,EMPTY,GA';
  pin
    'A':
      PIN_GROUP='1';
      PIN_NUMBER='(1)';
      PIN_TYPE='UNSPEC';
      PINUSE='UNSPEC';
    'B':
      PIN_GROUP='1';
      PIN_NUMBER='(2)';
      PIN_TYPE='UNSPEC';
      PINUSE='UNSPEC';
  end_pin;
  body
      PART_NAME='RES';
      PHYS_DES_PREFIX='R';
      ENVCOMP='YES;YES;YES;UNK;OK;VLD';
      PART_NUMBER='G21796-066';
      JEDEC_TYPE='SMR0402A';
      ALT_SYMBOLS='(SMX0402,SMX0402A,SMX0402B)';
      VALUE='NA';
      TOL='1%';
      WATTAGE='1/16W';
      CLASS='DISCRETE';
      DESCRIPTION='RES_D,0402,10.0OHM,1.00%,1/16W';
      HEIGHT='0.017 IN';
      COMPONENT_TYPE='CHIP0402';
      LEAD_LENGTH='';
      LPID='1141';
      SPEED_URL='http://speed.intel.com:8081/speed/module/pdm/item/pdm_item_deta~
il_direct.asp?item_cde=G21796-066&item_rev=01&url_param=unused';
      STATUS='UNQUAL';
      RPL='NO';
      AML='3';
      BUS_UNIT='GMPO_BD_EXMPFREE';
      DAYS='???';
      PARENT_PART_TYPE='RES';
      PARENT_PPT='RES';
      PARENT_PPT_PART='RES_0402-10.0,1%,1/16W,EMPTY,G21796-066';
  end_body;
end_primitive;
primitive 'RES_0402-10.0K,1%,1/16W,CHIP,GA';
  pin
    'A':
      PIN_GROUP='1';
      PIN_NUMBER='(1)';
      PIN_TYPE='UNSPEC';
      PINUSE='UNSPEC';
    'B':
      PIN_GROUP='1';
      PIN_NUMBER='(2)';
      PIN_TYPE='UNSPEC';
      PINUSE='UNSPEC';
  end_pin;
  body
      PART_NAME='RES';
      PHYS_DES_PREFIX='R';
      ENVCOMP='YES;YES;YES;UNK;OK;VLD';
      PART_NUMBER='G21796-016';
      JEDEC_TYPE='SMR0402A';
      ALT_SYMBOLS='(SMX0402,SMX0402A,SMX0402B)';
      VALUE='10.0K';
      TOL='1%';
      WATTAGE='1/16W';
      CLASS='DISCRETE';
      DESCRIPTION='RES_D,0402,10.0KOHM,1.00%,1/16W';
      HEIGHT='0.017 IN';
      COMPONENT_TYPE='CHIP0402';
      LEAD_LENGTH='';
      LPID='1141';
      SPEED_URL='http://speed.intel.com:8081/speed/module/pdm/item/pdm_item_deta~
il_direct.asp?item_cde=G21796-016&item_rev=01&url_param=unused';
      STATUS='UNQUAL';
      RPL='NO';
      AML='3';
      BUS_UNIT='GMPO_BD_EXMPFREE';
      DAYS='???';
      PARENT_PART_TYPE='RES';
      PARENT_PPT='RES';
      PARENT_PPT_PART='RES_0402-10.0K,1%,1/16W,CHIP,G21796-016';
  end_body;
end_primitive;
primitive 'RES_0402-10.0K,1%,1/16W,EMPTY,A';
  pin
    'A':
      PIN_GROUP='1';
      PIN_NUMBER='(1)';
      PIN_TYPE='UNSPEC';
      PINUSE='UNSPEC';
    'B':
      PIN_GROUP='1';
      PIN_NUMBER='(2)';
      PIN_TYPE='UNSPEC';
      PINUSE='UNSPEC';
  end_pin;
  body
      PART_NAME='RES';
      PHYS_DES_PREFIX='R';
      ENVCOMP='YES;YES;YES;UNK;OK;VLD';
      PART_NUMBER='G21796-016';
      JEDEC_TYPE='SMR0402A';
      ALT_SYMBOLS='(SMX0402,SMX0402A,SMX0402B)';
      VALUE='NA';
      TOL='1%';
      WATTAGE='1/16W';
      CLASS='DISCRETE';
      DESCRIPTION='RES_D,0402,10.0KOHM,1.00%,1/16W';
      HEIGHT='0.017 IN';
      COMPONENT_TYPE='CHIP0402';
      LEAD_LENGTH='';
      LPID='1141';
      SPEED_URL='http://speed.intel.com:8081/speed/module/pdm/item/pdm_item_deta~
il_direct.asp?item_cde=G21796-016&item_rev=01&url_param=unused';
      STATUS='UNQUAL';
      RPL='NO';
      AML='3';
      BUS_UNIT='GMPO_BD_EXMPFREE';
      DAYS='???';
      PARENT_PART_TYPE='RES';
      PARENT_PPT='RES';
      PARENT_PPT_PART='RES_0402-10.0K,1%,1/16W,EMPTY,G21796-016';
  end_body;
end_primitive;
primitive 'RES_0402-100.0,1%,1/16W,CHIP,GA';
  pin
    'A':
      PIN_GROUP='1';
      PIN_NUMBER='(1)';
      PIN_TYPE='UNSPEC';
      PINUSE='UNSPEC';
    'B':
      PIN_GROUP='1';
      PIN_NUMBER='(2)';
      PIN_TYPE='UNSPEC';
      PINUSE='UNSPEC';
  end_pin;
  body
      PART_NAME='RES';
      PHYS_DES_PREFIX='R';
      ENVCOMP='YES;YES;YES;UNK;OK;VLD';
      PART_NUMBER='G21796-017';
      JEDEC_TYPE='SMR0402A';
      ALT_SYMBOLS='(SMX0402,SMX0402A,SMX0402B)';
      VALUE='100.0';
      TOL='1%';
      WATTAGE='1/16W';
      CLASS='DISCRETE';
      DESCRIPTION='RES_D,0402,100.0OHM,1.00%,1/16W';
      HEIGHT='0.017 IN';
      COMPONENT_TYPE='CHIP0402';
      LEAD_LENGTH='';
      LPID='1141';
      SPEED_URL='http://speed.intel.com:8081/speed/module/pdm/item/pdm_item_deta~
il_direct.asp?item_cde=G21796-017&item_rev=01&url_param=unused';
      STATUS='UNQUAL';
      RPL='NO';
      AML='4';
      BUS_UNIT='GMPO_BD_EXMPFREE';
      DAYS='???';
      PARENT_PART_TYPE='RES';
      PARENT_PPT='RES';
      PARENT_PPT_PART='RES_0402-100.0,1%,1/16W,CHIP,G21796-017';
  end_body;
end_primitive;
primitive 'RES_0402-100.0,1%,1/16W,EMPTY,A';
  pin
    'A':
      PIN_GROUP='1';
      PIN_NUMBER='(1)';
      PIN_TYPE='UNSPEC';
      PINUSE='UNSPEC';
    'B':
      PIN_GROUP='1';
      PIN_NUMBER='(2)';
      PIN_TYPE='UNSPEC';
      PINUSE='UNSPEC';
  end_pin;
  body
      PART_NAME='RES';
      PHYS_DES_PREFIX='R';
      ENVCOMP='YES;YES;YES;UNK;OK;VLD';
      PART_NUMBER='G21796-017';
      JEDEC_TYPE='SMR0402A';
      ALT_SYMBOLS='(SMX0402,SMX0402A,SMX0402B)';
      VALUE='NA';
      TOL='1%';
      WATTAGE='1/16W';
      CLASS='DISCRETE';
      DESCRIPTION='RES_D,0402,100.0OHM,1.00%,1/16W';
      HEIGHT='0.017 IN';
      COMPONENT_TYPE='CHIP0402';
      LEAD_LENGTH='';
      LPID='1141';
      SPEED_URL='http://speed.intel.com:8081/speed/module/pdm/item/pdm_item_deta~
il_direct.asp?item_cde=G21796-017&item_rev=01&url_param=unused';
      STATUS='UNQUAL';
      RPL='NO';
      AML='4';
      BUS_UNIT='GMPO_BD_EXMPFREE';
      DAYS='???';
      PARENT_PART_TYPE='RES';
      PARENT_PPT='RES';
      PARENT_PPT_PART='RES_0402-100.0,1%,1/16W,EMPTY,G21796-017';
  end_body;
end_primitive;
primitive 'RES_0402-100.0K,1%,1/16W,CHIP,A';
  pin
    'A':
      PIN_GROUP='1';
      PIN_NUMBER='(1)';
      PIN_TYPE='UNSPEC';
      PINUSE='UNSPEC';
    'B':
      PIN_GROUP='1';
      PIN_NUMBER='(2)';
      PIN_TYPE='UNSPEC';
      PINUSE='UNSPEC';
  end_pin;
  body
      PART_NAME='RES';
      PHYS_DES_PREFIX='R';
      ENVCOMP='YES;YES;YES;UNK;OK;VLD';
      PART_NUMBER='G21796-010';
      JEDEC_TYPE='SMR0402A';
      ALT_SYMBOLS='(SMX0402,SMX0402A,SMX0402B)';
      VALUE='100.0K';
      TOL='1%';
      WATTAGE='1/16W';
      CLASS='DISCRETE';
      DESCRIPTION='RES_D,0402,100.0KOHM,1.00%,1/16W';
      HEIGHT='0.017 IN';
      COMPONENT_TYPE='CHIP0402';
      LEAD_LENGTH='';
      LPID='1141';
      SPEED_URL='http://speed.intel.com:8081/speed/module/pdm/item/pdm_item_deta~
il_direct.asp?item_cde=G21796-010&item_rev=01&url_param=unused';
      STATUS='UNQUAL';
      RPL='NO';
      AML='3';
      BUS_UNIT='GMPO_BD_EXMPFREE';
      DAYS='???';
      PARENT_PART_TYPE='RES';
      PARENT_PPT='RES';
      PARENT_PPT_PART='RES_0402-100.0K,1%,1/16W,CHIP,G21796-010';
  end_body;
end_primitive;
primitive 'RES_0402-100.0K,1%,1/16W,CHIP,B';
  pin
    'A':
      PIN_GROUP='1';
      PIN_NUMBER='(1)';
      PIN_TYPE='UNSPEC';
      PINUSE='UNSPEC';
    'B':
      PIN_GROUP='1';
      PIN_NUMBER='(2)';
      PIN_TYPE='UNSPEC';
      PINUSE='UNSPEC';
  end_pin;
  body
      PART_NAME='RES';
      PHYS_DES_PREFIX='R';
      ENVCOMP='YES;YES;YES;UNK;OK;VLD';
      PART_NUMBER='G21796-160';
      JEDEC_TYPE='SMR0402A';
      ALT_SYMBOLS='(SMX0402,SMX0402A,SMX0402B)';
      VALUE='100.0K';
      TOL='1%';
      WATTAGE='1/16W';
      CLASS='DISCRETE';
      DESCRIPTION='RES_D,0402,100.0KOHM,1.00%,1/16W';
      HEIGHT='0.017 IN';
      COMPONENT_TYPE='CHIP0402';
      LEAD_LENGTH='';
      LPID='1141';
      SPEED_URL='http://speed.intel.com:8081/speed/module/pdm/item/pdm_item_deta~
il_direct.asp?item_cde=G21796-160&item_rev=01&url_param=unused';
      STATUS='DESIGN';
      RPL='NO';
      AML='1';
      BUS_UNIT='GMPO_BD_EXMPFREE';
      DAYS='???';
      PARENT_PART_TYPE='RES';
      PARENT_PPT='RES';
      PARENT_PPT_PART='RES_0402-100.0K,1%,1/16W,CHIP,G21796-160';
  end_body;
end_primitive;
primitive 'RES_0402-100.0K,1%,1/16W,EMPTYA';
  pin
    'A':
      PIN_GROUP='1';
      PIN_NUMBER='(1)';
      PIN_TYPE='UNSPEC';
      PINUSE='UNSPEC';
    'B':
      PIN_GROUP='1';
      PIN_NUMBER='(2)';
      PIN_TYPE='UNSPEC';
      PINUSE='UNSPEC';
  end_pin;
  body
      PART_NAME='RES';
      PHYS_DES_PREFIX='R';
      ENVCOMP='YES;YES;YES;UNK;OK;VLD';
      PART_NUMBER='G21796-010';
      JEDEC_TYPE='SMR0402A';
      ALT_SYMBOLS='(SMX0402,SMX0402A,SMX0402B)';
      VALUE='NA';
      TOL='1%';
      WATTAGE='1/16W';
      CLASS='DISCRETE';
      DESCRIPTION='RES_D,0402,100.0KOHM,1.00%,1/16W';
      HEIGHT='0.017 IN';
      COMPONENT_TYPE='CHIP0402';
      LEAD_LENGTH='';
      LPID='1141';
      SPEED_URL='http://speed.intel.com:8081/speed/module/pdm/item/pdm_item_deta~
il_direct.asp?item_cde=G21796-010&item_rev=01&url_param=unused';
      STATUS='UNQUAL';
      RPL='NO';
      AML='3';
      BUS_UNIT='GMPO_BD_EXMPFREE';
      DAYS='???';
      PARENT_PART_TYPE='RES';
      PARENT_PPT='RES';
      PARENT_PPT_PART='RES_0402-100.0K,1%,1/16W,EMPTY,G21796-010';
  end_body;
end_primitive;
primitive 'RES_0402-105.0K,1%,1/16W,CHIP,A';
  pin
    'A':
      PIN_GROUP='1';
      PIN_NUMBER='(1)';
      PIN_TYPE='UNSPEC';
      PINUSE='UNSPEC';
    'B':
      PIN_GROUP='1';
      PIN_NUMBER='(2)';
      PIN_TYPE='UNSPEC';
      PINUSE='UNSPEC';
  end_pin;
  body
      PART_NAME='RES';
      PHYS_DES_PREFIX='R';
      ENVCOMP='YES;YES;YES;UNK;OK;VLD';
      PART_NUMBER='G21796-099';
      JEDEC_TYPE='SMR0402A';
      ALT_SYMBOLS='(SMX0402,SMX0402A,SMX0402B)';
      VALUE='105.0K';
      TOL='1%';
      WATTAGE='1/16W';
      CLASS='DISCRETE';
      DESCRIPTION='RES_D,0402,105.0KOHM,1.00%,1/16W';
      HEIGHT='0.017 IN';
      COMPONENT_TYPE='CHIP0402';
      LEAD_LENGTH='';
      LPID='1141';
      SPEED_URL='http://speed.intel.com:8081/speed/module/pdm/item/pdm_item_deta~
il_direct.asp?item_cde=G21796-099&item_rev=01&url_param=unused';
      STATUS='DESIGN';
      RPL='NO';
      AML='3';
      BUS_UNIT='GMPO_BD_EXMPFREE';
      DAYS='???';
      PARENT_PART_TYPE='RES';
      PARENT_PPT='RES';
      PARENT_PPT_PART='RES_0402-105.0K,1%,1/16W,CHIP,G21796-099';
  end_body;
end_primitive;
primitive 'RES_0402-110,1%,1/16W,EMPTY,G2A';
  pin
    'A':
      PIN_GROUP='1';
      PIN_NUMBER='(1)';
      PIN_TYPE='UNSPEC';
      PINUSE='UNSPEC';
    'B':
      PIN_GROUP='1';
      PIN_NUMBER='(2)';
      PIN_TYPE='UNSPEC';
      PINUSE='UNSPEC';
  end_pin;
  body
      PART_NAME='RES';
      PHYS_DES_PREFIX='R';
      ENVCOMP='';
      PART_NUMBER='G21796-203';
      JEDEC_TYPE='SMR0402A';
      ALT_SYMBOLS='(SMX0402,SMX0402A,SMX0402B)';
      VALUE='NA';
      TOL='1%';
      WATTAGE='1/16W';
      CLASS='DISCRETE';
      DESCRIPTION='RES_D,0402,110.00OHM,1.00%,1/16W,';
      HEIGHT='0.016 IN';
      COMPONENT_TYPE='CHIP0402';
      LEAD_LENGTH='';
      LPID='1141';
      SPEED_URL='http://speed.intel.com:8081/speed/module/pdm/item/pdm_item_deta~
il_direct.asp?item_cde=G21796-203&item_rev=01&url_param=unused';
      STATUS='';
      RPL='';
      AML='';
      BUS_UNIT='';
      DAYS='';
      PARENT_PART_TYPE='RES';
      PARENT_PPT='RES';
      PARENT_PPT_PART='RES_0402-110,1%,1/16W,EMPTY,G21796-203';
  end_body;
end_primitive;
primitive 'RES_0402-113,1%,1/16W,CHIP,G21A';
  pin
    'A':
      PIN_GROUP='1';
      PIN_NUMBER='(1)';
      PIN_TYPE='UNSPEC';
      PINUSE='UNSPEC';
    'B':
      PIN_GROUP='1';
      PIN_NUMBER='(2)';
      PIN_TYPE='UNSPEC';
      PINUSE='UNSPEC';
  end_pin;
  body
      PART_NAME='RES';
      PHYS_DES_PREFIX='R';
      ENVCOMP='';
      PART_NUMBER='G21796-341';
      JEDEC_TYPE='SMR0402A';
      ALT_SYMBOLS='(SMX0402,SMX0402A,SMX0402B)';
      VALUE='113';
      TOL='1%';
      WATTAGE='1/16W';
      CLASS='DISCRETE';
      DESCRIPTION='RES_D,0402,113.00OHM,1.00%,1/16W,';
      HEIGHT='0.016 IN';
      COMPONENT_TYPE='CHIP0402';
      LEAD_LENGTH='';
      LPID='1141';
      SPEED_URL='http://speed.intel.com:8081/speed/module/pdm/item/pdm_item_deta~
il_direct.asp?item_cde=G21796-341&item_rev=01&url_param=unused';
      STATUS='';
      RPL='';
      AML='';
      BUS_UNIT='';
      DAYS='';
      PARENT_PART_TYPE='RES';
      PARENT_PPT='RES';
      PARENT_PPT_PART='RES_0402-113,1%,1/16W,CHIP,G21796-341';
  end_body;
end_primitive;
primitive 'RES_0402-11K,1%,1/16W,CHIP,G21A';
  pin
    'A':
      PIN_GROUP='1';
      PIN_NUMBER='(1)';
      PIN_TYPE='UNSPEC';
      PINUSE='UNSPEC';
    'B':
      PIN_GROUP='1';
      PIN_NUMBER='(2)';
      PIN_TYPE='UNSPEC';
      PINUSE='UNSPEC';
  end_pin;
  body
      PART_NAME='RES';
      PHYS_DES_PREFIX='R';
      ENVCOMP='';
      PART_NUMBER='G21796-220';
      JEDEC_TYPE='SMR0402A';
      ALT_SYMBOLS='(SMX0402,SMX0402A,SMX0402B)';
      VALUE='11K';
      TOL='1%';
      WATTAGE='1/16W';
      CLASS='DISCRETE';
      DESCRIPTION='RES_D,0402,11.00kOHM,1.00%,1/16W,';
      HEIGHT='0.016 IN';
      COMPONENT_TYPE='CHIP0402';
      LEAD_LENGTH='';
      LPID='1141';
      SPEED_URL='http://speed.intel.com:8081/speed/module/pdm/item/pdm_item_deta~
il_direct.asp?item_cde=G21796-220&item_rev=01&url_param=unused';
      STATUS='';
      RPL='';
      AML='';
      BUS_UNIT='';
      DAYS='';
      PARENT_PART_TYPE='RES';
      PARENT_PPT='RES';
      PARENT_PPT_PART='RES_0402-11K,1%,1/16W,CHIP,G21796-220';
  end_body;
end_primitive;
primitive 'RES_0402-12.1K,1%,1/16W,CHIP,GA';
  pin
    'A':
      PIN_GROUP='1';
      PIN_NUMBER='(1)';
      PIN_TYPE='UNSPEC';
      PINUSE='UNSPEC';
    'B':
      PIN_GROUP='1';
      PIN_NUMBER='(2)';
      PIN_TYPE='UNSPEC';
      PINUSE='UNSPEC';
  end_pin;
  body
      PART_NAME='RES';
      PHYS_DES_PREFIX='R';
      ENVCOMP='YES;YES;YES;UNK;OK;VLD';
      PART_NUMBER='G21796-089';
      JEDEC_TYPE='SMR0402A';
      ALT_SYMBOLS='(SMX0402,SMX0402A,SMX0402B)';
      VALUE='12.1K';
      TOL='1%';
      WATTAGE='1/16W';
      CLASS='DISCRETE';
      DESCRIPTION='RES_D,0402,12.1KOHM,1.00%,1/16W';
      HEIGHT='0.017 IN';
      COMPONENT_TYPE='CHIP0402';
      LEAD_LENGTH='';
      LPID='1141';
      SPEED_URL='http://speed.intel.com:8081/speed/module/pdm/item/pdm_item_deta~
il_direct.asp?item_cde=G21796-089&item_rev=01&url_param=unused';
      STATUS='UNQUAL';
      RPL='NO';
      AML='3';
      BUS_UNIT='GMPO_BD_EXMPFREE';
      DAYS='???';
      PARENT_PART_TYPE='RES';
      PARENT_PPT='RES';
      PARENT_PPT_PART='RES_0402-12.1K,1%,1/16W,CHIP,G21796-089';
  end_body;
end_primitive;
primitive 'RES_0402-15.0K,1%,1/16W,CHIP,GA';
  pin
    'A':
      PIN_GROUP='1';
      PIN_NUMBER='(1)';
      PIN_TYPE='UNSPEC';
      PINUSE='UNSPEC';
    'B':
      PIN_GROUP='1';
      PIN_NUMBER='(2)';
      PIN_TYPE='UNSPEC';
      PINUSE='UNSPEC';
  end_pin;
  body
      PART_NAME='RES';
      PHYS_DES_PREFIX='R';
      ENVCOMP='YES;YES;YES;UNK;OK;VLD';
      PART_NUMBER='G21796-107';
      JEDEC_TYPE='SMR0402A';
      ALT_SYMBOLS='(SMX0402,SMX0402A,SMX0402B)';
      VALUE='15.0K';
      TOL='1%';
      WATTAGE='1/16W';
      CLASS='DISCRETE';
      DESCRIPTION='RES_D,0402,15.0KOHM,1.00%,1/16W';
      HEIGHT='0.017 IN';
      COMPONENT_TYPE='CHIP0402';
      LEAD_LENGTH='';
      LPID='1141';
      SPEED_URL='http://speed.intel.com:8081/speed/module/pdm/item/pdm_item_deta~
il_direct.asp?item_cde=G21796-107&item_rev=01&url_param=unused';
      STATUS='UNQUAL';
      RPL='NO';
      AML='3';
      BUS_UNIT='GMPO_BD_EXMPFREE';
      DAYS='???';
      PARENT_PART_TYPE='RES';
      PARENT_PPT='RES';
      PARENT_PPT_PART='RES_0402-15.0K,1%,1/16W,CHIP,G21796-107';
  end_body;
end_primitive;
primitive 'RES_0402-150.0,1%,1/16W,CHIP,GA';
  pin
    'A':
      PIN_GROUP='1';
      PIN_NUMBER='(1)';
      PIN_TYPE='UNSPEC';
      PINUSE='UNSPEC';
    'B':
      PIN_GROUP='1';
      PIN_NUMBER='(2)';
      PIN_TYPE='UNSPEC';
      PINUSE='UNSPEC';
  end_pin;
  body
      PART_NAME='RES';
      PHYS_DES_PREFIX='R';
      ENVCOMP='YES;YES;YES;UNK;OK;VLD';
      PART_NUMBER='G21796-009';
      JEDEC_TYPE='SMR0402A';
      ALT_SYMBOLS='(SMX0402,SMX0402A,SMX0402B)';
      VALUE='150.0';
      TOL='1%';
      WATTAGE='1/16W';
      CLASS='DISCRETE';
      DESCRIPTION='RES_D,0402,150.0OHM,1.00%,1/16W';
      HEIGHT='0.017 IN';
      COMPONENT_TYPE='CHIP0402';
      LEAD_LENGTH='';
      LPID='1141';
      SPEED_URL='http://speed.intel.com:8081/speed/module/pdm/item/pdm_item_deta~
il_direct.asp?item_cde=G21796-009&item_rev=01&url_param=unused';
      STATUS='DESIGN';
      RPL='NO';
      AML='3';
      BUS_UNIT='GMPO_BD_EXMPFREE';
      DAYS='???';
      PARENT_PART_TYPE='RES';
      PARENT_PPT='RES';
      PARENT_PPT_PART='RES_0402-150.0,1%,1/16W,CHIP,G21796-009';
  end_body;
end_primitive;
primitive 'RES_0402-150.0K,1%,1/16W,CHIP,A';
  pin
    'A':
      PIN_GROUP='1';
      PIN_NUMBER='(1)';
      PIN_TYPE='UNSPEC';
      PINUSE='UNSPEC';
    'B':
      PIN_GROUP='1';
      PIN_NUMBER='(2)';
      PIN_TYPE='UNSPEC';
      PINUSE='UNSPEC';
  end_pin;
  body
      PART_NAME='RES';
      PHYS_DES_PREFIX='R';
      ENVCOMP='YES;YES;YES;UNK;OK;VLD';
      PART_NUMBER='G21796-109';
      JEDEC_TYPE='SMR0402A';
      ALT_SYMBOLS='(SMX0402,SMX0402A,SMX0402B)';
      VALUE='150.0K';
      TOL='1%';
      WATTAGE='1/16W';
      CLASS='DISCRETE';
      DESCRIPTION='RES_D,0402,150.0KOHM,1.00%,1/16W';
      HEIGHT='0.017 IN';
      COMPONENT_TYPE='CHIP0402';
      LEAD_LENGTH='';
      LPID='1141';
      SPEED_URL='http://speed.intel.com:8081/speed/module/pdm/item/pdm_item_deta~
il_direct.asp?item_cde=G21796-109&item_rev=01&url_param=unused';
      STATUS='UNQUAL';
      RPL='NO';
      AML='3';
      BUS_UNIT='GMPO_BD_EXMPFREE';
      DAYS='???';
      PARENT_PART_TYPE='RES';
      PARENT_PPT='RES';
      PARENT_PPT_PART='RES_0402-150.0K,1%,1/16W,CHIP,G21796-109';
  end_body;
end_primitive;
primitive 'RES_0402-169,1.0%,1/16W,CHIP,GA';
  pin
    'A':
      PIN_GROUP='1';
      PIN_NUMBER='(1)';
      PIN_TYPE='UNSPEC';
      PINUSE='UNSPEC';
    'B':
      PIN_GROUP='1';
      PIN_NUMBER='(2)';
      PIN_TYPE='UNSPEC';
      PINUSE='UNSPEC';
  end_pin;
  body
      PART_NAME='RES';
      PHYS_DES_PREFIX='R';
      ENVCOMP='YES;YES;YES;UNK;OK;VLD';
      PART_NUMBER='G21796-276';
      JEDEC_TYPE='SMR0402A';
      ALT_SYMBOLS='(SMX0402,SMX0402A,SMX0402B)';
      VALUE='169';
      TOL='1.0%';
      WATTAGE='1/16W';
      CLASS='DISCRETE';
      DESCRIPTION='RES_D,0402,169.00OHM,1.00%,1/16W,';
      HEIGHT='0.016 IN';
      COMPONENT_TYPE='CHIP0402';
      LEAD_LENGTH='';
      LPID='1141';
      SPEED_URL='http://speed.intel.com:8081/speed/module/pdm/item/pdm_item_deta~
il_direct.asp?item_cde=G21796-276&item_rev=01&url_param=unused';
      STATUS='DESIGN';
      RPL='NO';
      AML='3';
      BUS_UNIT='GMPO_BD_EXMPFREE';
      DAYS='???';
      PARENT_PART_TYPE='RES';
      PARENT_PPT='RES';
      PARENT_PPT_PART='RES_0402-169,1.0%,1/16W,CHIP,G21796-276';
  end_body;
end_primitive;
primitive 'RES_0402-16K,1.0%,1/16W,CHIP,GA';
  pin
    'A':
      PIN_GROUP='1';
      PIN_NUMBER='(1)';
      PIN_TYPE='UNSPEC';
      PINUSE='UNSPEC';
    'B':
      PIN_GROUP='1';
      PIN_NUMBER='(2)';
      PIN_TYPE='UNSPEC';
      PINUSE='UNSPEC';
  end_pin;
  body
      PART_NAME='RES';
      PHYS_DES_PREFIX='R';
      ENVCOMP='YES;YES;YES;UNK;OK;VLD';
      PART_NUMBER='G21796-317';
      JEDEC_TYPE='SMR0402A';
      ALT_SYMBOLS='(SMX0402,SMX0402A,SMX0402B)';
      VALUE='16K';
      TOL='1.0%';
      WATTAGE='1/16W';
      CLASS='DISCRETE';
      DESCRIPTION='RES_D,0402,16.00KOHM,1.00%,1/16W,';
      HEIGHT='0.016 IN';
      COMPONENT_TYPE='CHIP0402';
      LEAD_LENGTH='';
      LPID='1141';
      SPEED_URL='http://speed.intel.com:8081/speed/module/pdm/item/pdm_item_deta~
il_direct.asp?item_cde=G21796-317&item_rev=01&url_param=unused';
      STATUS='DESIGN';
      RPL='NO';
      AML='3';
      BUS_UNIT='GMPO_BD_EXMPFREE';
      DAYS='???';
      PARENT_PART_TYPE='RES';
      PARENT_PPT='RES';
      PARENT_PPT_PART='RES_0402-16K,1.0%,1/16W,CHIP,G21796-317';
  end_body;
end_primitive;
primitive 'RES_0402-2,1.0%,1/16W,CHIP,G21A';
  pin
    'A':
      PIN_GROUP='1';
      PIN_NUMBER='(1)';
      PIN_TYPE='UNSPEC';
      PINUSE='UNSPEC';
    'B':
      PIN_GROUP='1';
      PIN_NUMBER='(2)';
      PIN_TYPE='UNSPEC';
      PINUSE='UNSPEC';
  end_pin;
  body
      PART_NAME='RES';
      PHYS_DES_PREFIX='R';
      ENVCOMP='YES;YES;YES;UNK;OK;VLD';
      PART_NUMBER='G21796-274';
      JEDEC_TYPE='SMR0402A';
      ALT_SYMBOLS='(SMX0402,SMX0402A,SMX0402B)';
      VALUE='2';
      TOL='1.0%';
      WATTAGE='1/16W';
      CLASS='DISCRETE';
      DESCRIPTION='RES_D,0402,2.00OHM,1.00%,1/16W,';
      HEIGHT='0.016 IN';
      COMPONENT_TYPE='CHIP0402';
      LEAD_LENGTH='';
      LPID='1141';
      SPEED_URL='http://speed.intel.com:8081/speed/module/pdm/item/pdm_item_deta~
il_direct.asp?item_cde=G21796-274&item_rev=01&url_param=unused';
      STATUS='DESIGN';
      RPL='NO';
      AML='2';
      BUS_UNIT='GMPO_BD_EXMPFREE';
      DAYS='???';
      PARENT_PART_TYPE='RES';
      PARENT_PPT='RES';
      PARENT_PPT_PART='RES_0402-2,1.0%,1/16W,CHIP,G21796-274';
  end_body;
end_primitive;
primitive 'RES_0402-2.0K,1%,1/16W,CHIP,G2A';
  pin
    'A':
      PIN_GROUP='1';
      PIN_NUMBER='(1)';
      PIN_TYPE='UNSPEC';
      PINUSE='UNSPEC';
    'B':
      PIN_GROUP='1';
      PIN_NUMBER='(2)';
      PIN_TYPE='UNSPEC';
      PINUSE='UNSPEC';
  end_pin;
  body
      PART_NAME='RES';
      PHYS_DES_PREFIX='R';
      ENVCOMP='YES;YES;YES;UNK;OK;VLD';
      PART_NUMBER='G21796-001';
      JEDEC_TYPE='SMR0402A';
      ALT_SYMBOLS='(SMX0402,SMX0402A,SMX0402B)';
      VALUE='2.0K';
      TOL='1%';
      WATTAGE='1/16W';
      CLASS='DISCRETE';
      DESCRIPTION='RES_D,0402,2.0KOHM,1.00%,1/16W';
      HEIGHT='0.017 IN';
      COMPONENT_TYPE='CHIP0402';
      LEAD_LENGTH='';
      LPID='1141';
      SPEED_URL='http://speed.intel.com:8081/speed/module/pdm/item/pdm_item_deta~
il_direct.asp?item_cde=G21796-001&item_rev=01&url_param=unused';
      STATUS='CONDITIONAL';
      RPL='NO';
      AML='3';
      BUS_UNIT='GMPO_BD_EXMPFREE';
      DAYS='???';
      PARENT_PART_TYPE='RES';
      PARENT_PPT='RES';
      PARENT_PPT_PART='RES_0402-2.0K,1%,1/16W,CHIP,G21796-001';
  end_body;
end_primitive;
primitive 'RES_0402-2.0K,1%,1/16W,EMPTY,GA';
  pin
    'A':
      PIN_GROUP='1';
      PIN_NUMBER='(1)';
      PIN_TYPE='UNSPEC';
      PINUSE='UNSPEC';
    'B':
      PIN_GROUP='1';
      PIN_NUMBER='(2)';
      PIN_TYPE='UNSPEC';
      PINUSE='UNSPEC';
  end_pin;
  body
      PART_NAME='RES';
      PHYS_DES_PREFIX='R';
      ENVCOMP='YES;YES;YES;UNK;OK;VLD';
      PART_NUMBER='G21796-001';
      JEDEC_TYPE='SMR0402A';
      ALT_SYMBOLS='(SMX0402,SMX0402A,SMX0402B)';
      VALUE='NA';
      TOL='1%';
      WATTAGE='1/16W';
      CLASS='DISCRETE';
      DESCRIPTION='RES_D,0402,2.0KOHM,1.00%,1/16W';
      HEIGHT='0.017 IN';
      COMPONENT_TYPE='CHIP0402';
      LEAD_LENGTH='';
      LPID='1141';
      SPEED_URL='http://speed.intel.com:8081/speed/module/pdm/item/pdm_item_deta~
il_direct.asp?item_cde=G21796-001&item_rev=01&url_param=unused';
      STATUS='CONDITIONAL';
      RPL='NO';
      AML='3';
      BUS_UNIT='GMPO_BD_EXMPFREE';
      DAYS='???';
      PARENT_PART_TYPE='RES';
      PARENT_PPT='RES';
      PARENT_PPT_PART='RES_0402-2.0K,1%,1/16W,EMPTY,G21796-001';
  end_body;
end_primitive;
primitive 'RES_0402-2.2,5%,1/16W,EMPTY,G2A';
  pin
    'A':
      PIN_GROUP='1';
      PIN_NUMBER='(1)';
      PIN_TYPE='UNSPEC';
      PINUSE='UNSPEC';
    'B':
      PIN_GROUP='1';
      PIN_NUMBER='(2)';
      PIN_TYPE='UNSPEC';
      PINUSE='UNSPEC';
  end_pin;
  body
      PART_NAME='RES';
      PHYS_DES_PREFIX='R';
      ENVCOMP='YES;YES;YES;UNK;OK;VLD';
      PART_NUMBER='G21497-016';
      JEDEC_TYPE='SMR0402A';
      ALT_SYMBOLS='(SMX0402,SMX0402A,SMX0402B)';
      VALUE='NA';
      TOL='5%';
      WATTAGE='1/16W';
      CLASS='DISCRETE';
      DESCRIPTION='RES_D,0402,2.2OHM,5.00%,1/16W';
      HEIGHT='0.017 IN';
      COMPONENT_TYPE='CHIP0402';
      LEAD_LENGTH='';
      LPID='1141';
      SPEED_URL='http://speed.intel.com:8081/speed/module/pdm/item/pdm_item_deta~
il_direct.asp?item_cde=G21497-016&item_rev=01&url_param=unused';
      STATUS='DESIGN';
      RPL='NO';
      AML='3';
      BUS_UNIT='GMPO_BD_EXMPFREE';
      DAYS='???';
      PARENT_PART_TYPE='RES';
      PARENT_PPT='RES';
      PARENT_PPT_PART='RES_0402-2.2,5%,1/16W,EMPTY,G21497-016';
  end_body;
end_primitive;
primitive 'RES_0402-2.21K,1%,1/16W,CHIP,GA';
  pin
    'A':
      PIN_GROUP='1';
      PIN_NUMBER='(1)';
      PIN_TYPE='UNSPEC';
      PINUSE='UNSPEC';
    'B':
      PIN_GROUP='1';
      PIN_NUMBER='(2)';
      PIN_TYPE='UNSPEC';
      PINUSE='UNSPEC';
  end_pin;
  body
      PART_NAME='RES';
      PHYS_DES_PREFIX='R';
      ENVCOMP='YES;YES;YES;UNK;OK;VLD';
      PART_NUMBER='G21796-112';
      JEDEC_TYPE='SMR0402A';
      ALT_SYMBOLS='(SMX0402,SMX0402A,SMX0402B)';
      VALUE='2.21K';
      TOL='1%';
      WATTAGE='1/16W';
      CLASS='DISCRETE';
      DESCRIPTION='RES_D,0402,2.21KOHM,1.00%,1/16W';
      HEIGHT='0.017 IN';
      COMPONENT_TYPE='CHIP0402';
      LEAD_LENGTH='';
      LPID='1141';
      SPEED_URL='http://speed.intel.com:8081/speed/module/pdm/item/pdm_item_deta~
il_direct.asp?item_cde=G21796-112&item_rev=01&url_param=unused';
      STATUS='DESIGN';
      RPL='NO';
      AML='3';
      BUS_UNIT='GMPO_BD_EXMPFREE';
      DAYS='???';
      PARENT_PART_TYPE='RES';
      PARENT_PPT='RES';
      PARENT_PPT_PART='RES_0402-2.21K,1%,1/16W,CHIP,G21796-112';
  end_body;
end_primitive;
primitive 'RES_0402-2.26K,1.0%,1/16W,CHIPA';
  pin
    'A':
      PIN_GROUP='1';
      PIN_NUMBER='(1)';
      PIN_TYPE='UNSPEC';
      PINUSE='UNSPEC';
    'B':
      PIN_GROUP='1';
      PIN_NUMBER='(2)';
      PIN_TYPE='UNSPEC';
      PINUSE='UNSPEC';
  end_pin;
  body
      PART_NAME='RES';
      PHYS_DES_PREFIX='R';
      ENVCOMP='YES;YES;YES;UNK;OK;VLD';
      PART_NUMBER='G21796-311';
      JEDEC_TYPE='SMR0402A';
      ALT_SYMBOLS='(SMX0402,SMX0402A,SMX0402B)';
      VALUE='2.26K';
      TOL='1.0%';
      WATTAGE='1/16W';
      CLASS='DISCRETE';
      DESCRIPTION='RES_D,0402,2.26KOHM,1.00%,1/16W,';
      HEIGHT='0.016 IN';
      COMPONENT_TYPE='CHIP0402';
      LEAD_LENGTH='';
      LPID='1141';
      SPEED_URL='http://speed.intel.com:8081/speed/module/pdm/item/pdm_item_deta~
il_direct.asp?item_cde=G21796-311&item_rev=01&url_param=unused';
      STATUS='DESIGN';
      RPL='NO';
      AML='3';
      BUS_UNIT='GMPO_BD_EXMPFREE';
      DAYS='???';
      PARENT_PART_TYPE='RES';
      PARENT_PPT='RES';
      PARENT_PPT_PART='RES_0402-2.26K,1.0%,1/16W,CHIP,G21796-311';
  end_body;
end_primitive;
primitive 'RES_0402-2.26K,1.0%,1/16W,EMPTA';
  pin
    'A':
      PIN_GROUP='1';
      PIN_NUMBER='(1)';
      PIN_TYPE='UNSPEC';
      PINUSE='UNSPEC';
    'B':
      PIN_GROUP='1';
      PIN_NUMBER='(2)';
      PIN_TYPE='UNSPEC';
      PINUSE='UNSPEC';
  end_pin;
  body
      PART_NAME='RES';
      PHYS_DES_PREFIX='R';
      ENVCOMP='YES;YES;YES;UNK;OK;VLD';
      PART_NUMBER='G21796-311';
      JEDEC_TYPE='SMR0402A';
      ALT_SYMBOLS='(SMX0402,SMX0402A,SMX0402B)';
      VALUE='NA';
      TOL='1.0%';
      WATTAGE='1/16W';
      CLASS='DISCRETE';
      DESCRIPTION='RES_D,0402,2.26KOHM,1.00%,1/16W,';
      HEIGHT='0.016 IN';
      COMPONENT_TYPE='CHIP0402';
      LEAD_LENGTH='';
      LPID='1141';
      SPEED_URL='http://speed.intel.com:8081/speed/module/pdm/item/pdm_item_deta~
il_direct.asp?item_cde=G21796-311&item_rev=01&url_param=unused';
      STATUS='DESIGN';
      RPL='NO';
      AML='3';
      BUS_UNIT='GMPO_BD_EXMPFREE';
      DAYS='???';
      PARENT_PART_TYPE='RES';
      PARENT_PPT='RES';
      PARENT_PPT_PART='RES_0402-2.26K,1.0%,1/16W,EMPTY,G21796-311';
  end_body;
end_primitive;
primitive 'RES_0402-2.67K,1%,1/16W,CHIP,GA';
  pin
    'A':
      PIN_GROUP='1';
      PIN_NUMBER='(1)';
      PIN_TYPE='UNSPEC';
      PINUSE='UNSPEC';
    'B':
      PIN_GROUP='1';
      PIN_NUMBER='(2)';
      PIN_TYPE='UNSPEC';
      PINUSE='UNSPEC';
  end_pin;
  body
      PART_NAME='RES';
      PHYS_DES_PREFIX='R';
      ENVCOMP='YES;YES;YES;UNK;OK;VLD';
      PART_NUMBER='G21796-180';
      JEDEC_TYPE='SMR0402A';
      ALT_SYMBOLS='(SMX0402,SMX0402A,SMX0402B)';
      VALUE='2.67K';
      TOL='1%';
      WATTAGE='1/16W';
      CLASS='DISCRETE';
      DESCRIPTION='RES_D,0402,2.67KOHM,1.00%,1/16W';
      HEIGHT='0.017 IN';
      COMPONENT_TYPE='CHIP0402';
      LEAD_LENGTH='';
      LPID='1141';
      SPEED_URL='http://speed.intel.com:8081/speed/module/pdm/item/pdm_item_deta~
il_direct.asp?item_cde=G21796-180&item_rev=01&url_param=unused';
      STATUS='DESIGN';
      RPL='NO';
      AML='3';
      BUS_UNIT='GMPO_BD_EXMPFREE';
      DAYS='???';
      PARENT_PART_TYPE='RES';
      PARENT_PPT='RES';
      PARENT_PPT_PART='RES_0402-2.67K,1%,1/16W,CHIP,G21796-180';
  end_body;
end_primitive;
primitive 'RES_0402-2.7K,1%,1/16W,CHIP,G2A';
  pin
    'A':
      PIN_GROUP='1';
      PIN_NUMBER='(1)';
      PIN_TYPE='UNSPEC';
      PINUSE='UNSPEC';
    'B':
      PIN_GROUP='1';
      PIN_NUMBER='(2)';
      PIN_TYPE='UNSPEC';
      PINUSE='UNSPEC';
  end_pin;
  body
      PART_NAME='RES';
      PHYS_DES_PREFIX='R';
      ENVCOMP='';
      PART_NUMBER='G21796-344';
      JEDEC_TYPE='SMR0402A';
      ALT_SYMBOLS='(SMX0402,SMX0402A,SMX0402B)';
      VALUE='2.7K';
      TOL='1%';
      WATTAGE='1/16W';
      CLASS='DISCRETE';
      DESCRIPTION='RES_D,0402,2.70kOHM,1.00%,1/16W,';
      HEIGHT='0.016 IN';
      COMPONENT_TYPE='CHIP0402';
      LEAD_LENGTH='';
      LPID='1141';
      SPEED_URL='http://speed.intel.com:8081/speed/module/pdm/item/pdm_item_deta~
il_direct.asp?item_cde=G21796-344&item_rev=01&url_param=unused';
      STATUS='';
      RPL='';
      AML='';
      BUS_UNIT='';
      DAYS='';
      PARENT_PART_TYPE='RES';
      PARENT_PPT='RES';
      PARENT_PPT_PART='RES_0402-2.7K,1%,1/16W,CHIP,G21796-344';
  end_body;
end_primitive;
primitive 'RES_0402-2.7K,1%,1/16W,EMPTY,GA';
  pin
    'A':
      PIN_GROUP='1';
      PIN_NUMBER='(1)';
      PIN_TYPE='UNSPEC';
      PINUSE='UNSPEC';
    'B':
      PIN_GROUP='1';
      PIN_NUMBER='(2)';
      PIN_TYPE='UNSPEC';
      PINUSE='UNSPEC';
  end_pin;
  body
      PART_NAME='RES';
      PHYS_DES_PREFIX='R';
      ENVCOMP='';
      PART_NUMBER='G21796-344';
      JEDEC_TYPE='SMR0402A';
      ALT_SYMBOLS='(SMX0402,SMX0402A,SMX0402B)';
      VALUE='NA';
      TOL='1%';
      WATTAGE='1/16W';
      CLASS='DISCRETE';
      DESCRIPTION='RES_D,0402,2.70kOHM,1.00%,1/16W,';
      HEIGHT='0.016 IN';
      COMPONENT_TYPE='CHIP0402';
      LEAD_LENGTH='';
      LPID='1141';
      SPEED_URL='http://speed.intel.com:8081/speed/module/pdm/item/pdm_item_deta~
il_direct.asp?item_cde=G21796-344&item_rev=01&url_param=unused';
      STATUS='';
      RPL='';
      AML='';
      BUS_UNIT='';
      DAYS='';
      PARENT_PART_TYPE='RES';
      PARENT_PPT='RES';
      PARENT_PPT_PART='RES_0402-2.7K,1%,1/16W,EMPTY,G21796-344';
  end_body;
end_primitive;
primitive 'RES_0402-20.0,1%,1/16W,CHIP,G2A';
  pin
    'A':
      PIN_GROUP='1';
      PIN_NUMBER='(1)';
      PIN_TYPE='UNSPEC';
      PINUSE='UNSPEC';
    'B':
      PIN_GROUP='1';
      PIN_NUMBER='(2)';
      PIN_TYPE='UNSPEC';
      PINUSE='UNSPEC';
  end_pin;
  body
      PART_NAME='RES';
      PHYS_DES_PREFIX='R';
      ENVCOMP='YES;YES;YES;UNK;OK;VLD';
      PART_NUMBER='G21796-173';
      JEDEC_TYPE='SMR0402A';
      ALT_SYMBOLS='(SMX0402,SMX0402A,SMX0402B)';
      VALUE='20.0';
      TOL='1%';
      WATTAGE='1/16W';
      CLASS='DISCRETE';
      DESCRIPTION='RES_D,0402,20.0OHM,1.00%,1/16W';
      HEIGHT='0.017 IN';
      COMPONENT_TYPE='CHIP0402';
      LEAD_LENGTH='';
      LPID='1141';
      SPEED_URL='http://speed.intel.com:8081/speed/module/pdm/item/pdm_item_deta~
il_direct.asp?item_cde=G21796-173&item_rev=01&url_param=unused';
      STATUS='DESIGN';
      RPL='NO';
      AML='3';
      BUS_UNIT='GMPO_BD_EXMPFREE';
      DAYS='???';
      PARENT_PART_TYPE='RES';
      PARENT_PPT='RES';
      PARENT_PPT_PART='RES_0402-20.0,1%,1/16W,CHIP,G21796-173';
  end_body;
end_primitive;
primitive 'RES_0402-20.0,1%,1/16W,EMPTY,GA';
  pin
    'A':
      PIN_GROUP='1';
      PIN_NUMBER='(1)';
      PIN_TYPE='UNSPEC';
      PINUSE='UNSPEC';
    'B':
      PIN_GROUP='1';
      PIN_NUMBER='(2)';
      PIN_TYPE='UNSPEC';
      PINUSE='UNSPEC';
  end_pin;
  body
      PART_NAME='RES';
      PHYS_DES_PREFIX='R';
      ENVCOMP='YES;YES;YES;UNK;OK;VLD';
      PART_NUMBER='G21796-173';
      JEDEC_TYPE='SMR0402A';
      ALT_SYMBOLS='(SMX0402,SMX0402A,SMX0402B)';
      VALUE='NA';
      TOL='1%';
      WATTAGE='1/16W';
      CLASS='DISCRETE';
      DESCRIPTION='RES_D,0402,20.0OHM,1.00%,1/16W';
      HEIGHT='0.017 IN';
      COMPONENT_TYPE='CHIP0402';
      LEAD_LENGTH='';
      LPID='1141';
      SPEED_URL='http://speed.intel.com:8081/speed/module/pdm/item/pdm_item_deta~
il_direct.asp?item_cde=G21796-173&item_rev=01&url_param=unused';
      STATUS='DESIGN';
      RPL='NO';
      AML='3';
      BUS_UNIT='GMPO_BD_EXMPFREE';
      DAYS='???';
      PARENT_PART_TYPE='RES';
      PARENT_PPT='RES';
      PARENT_PPT_PART='RES_0402-20.0,1%,1/16W,EMPTY,G21796-173';
  end_body;
end_primitive;
primitive 'RES_0402-20.0K,1%,1/16W,CHIP,GA';
  pin
    'A':
      PIN_GROUP='1';
      PIN_NUMBER='(1)';
      PIN_TYPE='UNSPEC';
      PINUSE='UNSPEC';
    'B':
      PIN_GROUP='1';
      PIN_NUMBER='(2)';
      PIN_TYPE='UNSPEC';
      PINUSE='UNSPEC';
  end_pin;
  body
      PART_NAME='RES';
      PHYS_DES_PREFIX='R';
      ENVCOMP='YES;YES;YES;UNK;OK;VLD';
      PART_NUMBER='G21796-040';
      JEDEC_TYPE='SMR0402A';
      ALT_SYMBOLS='(SMX0402,SMX0402A,SMX0402B)';
      VALUE='20.0K';
      TOL='1%';
      WATTAGE='1/16W';
      CLASS='DISCRETE';
      DESCRIPTION='RES_D,0402,20.0KOHM,1.00%,1/16W';
      HEIGHT='0.017 IN';
      COMPONENT_TYPE='CHIP0402';
      LEAD_LENGTH='';
      LPID='1141';
      SPEED_URL='http://speed.intel.com:8081/speed/module/pdm/item/pdm_item_deta~
il_direct.asp?item_cde=G21796-040&item_rev=01&url_param=unused';
      STATUS='UNQUAL';
      RPL='NO';
      AML='4';
      BUS_UNIT='GMPO_BD_EXMPFREE';
      DAYS='???';
      PARENT_PART_TYPE='RES';
      PARENT_PPT='RES';
      PARENT_PPT_PART='RES_0402-20.0K,1%,1/16W,CHIP,G21796-040';
  end_body;
end_primitive;
primitive 'RES_0402-200.0,1%,1/16W,CHIP,GA';
  pin
    'A':
      PIN_GROUP='1';
      PIN_NUMBER='(1)';
      PIN_TYPE='UNSPEC';
      PINUSE='UNSPEC';
    'B':
      PIN_GROUP='1';
      PIN_NUMBER='(2)';
      PIN_TYPE='UNSPEC';
      PINUSE='UNSPEC';
  end_pin;
  body
      PART_NAME='RES';
      PHYS_DES_PREFIX='R';
      ENVCOMP='YES;YES;YES;UNK;OK;VLD';
      PART_NUMBER='G21796-004';
      JEDEC_TYPE='SMR0402A';
      ALT_SYMBOLS='(SMX0402,SMX0402A,SMX0402B)';
      VALUE='200.0';
      TOL='1%';
      WATTAGE='1/16W';
      CLASS='DISCRETE';
      DESCRIPTION='RES_D,0402,200.0OHM,1.00%,1/16W';
      HEIGHT='0.017 IN';
      COMPONENT_TYPE='CHIP0402';
      LEAD_LENGTH='';
      LPID='1141';
      SPEED_URL='http://speed.intel.com:8081/speed/module/pdm/item/pdm_item_deta~
il_direct.asp?item_cde=G21796-004&item_rev=01&url_param=unused';
      STATUS='UNQUAL';
      RPL='NO';
      AML='3';
      BUS_UNIT='GMPO_BD_EXMPFREE';
      DAYS='???';
      PARENT_PART_TYPE='RES';
      PARENT_PPT='RES';
      PARENT_PPT_PART='RES_0402-200.0,1%,1/16W,CHIP,G21796-004';
  end_body;
end_primitive;
primitive 'RES_0402-200.0K,1%,1/16W,CHIP,A';
  pin
    'A':
      PIN_GROUP='1';
      PIN_NUMBER='(1)';
      PIN_TYPE='UNSPEC';
      PINUSE='UNSPEC';
    'B':
      PIN_GROUP='1';
      PIN_NUMBER='(2)';
      PIN_TYPE='UNSPEC';
      PINUSE='UNSPEC';
  end_pin;
  body
      PART_NAME='RES';
      PHYS_DES_PREFIX='R';
      ENVCOMP='YES;YES;YES;UNK;OK;VLD';
      PART_NUMBER='G21796-080';
      JEDEC_TYPE='SMR0402A';
      ALT_SYMBOLS='(SMX0402,SMX0402A,SMX0402B)';
      VALUE='200.0K';
      TOL='1%';
      WATTAGE='1/16W';
      CLASS='DISCRETE';
      DESCRIPTION='RES_D,0402,200.0KOHM,1.00%,1/16W';
      HEIGHT='0.017 IN';
      COMPONENT_TYPE='CHIP0402';
      LEAD_LENGTH='';
      LPID='1141';
      SPEED_URL='http://speed.intel.com:8081/speed/module/pdm/item/pdm_item_deta~
il_direct.asp?item_cde=G21796-080&item_rev=01&url_param=unused';
      STATUS='UNQUAL';
      RPL='NO';
      AML='3';
      BUS_UNIT='GMPO_BD_EXMPFREE';
      DAYS='???';
      PARENT_PART_TYPE='RES';
      PARENT_PPT='RES';
      PARENT_PPT_PART='RES_0402-200.0K,1%,1/16W,CHIP,G21796-080';
  end_body;
end_primitive;
primitive 'RES_0402-22.1,1.0%,1/16W,CHIP,A';
  pin
    'A':
      PIN_GROUP='1';
      PIN_NUMBER='(1)';
      PIN_TYPE='UNSPEC';
      PINUSE='UNSPEC';
    'B':
      PIN_GROUP='1';
      PIN_NUMBER='(2)';
      PIN_TYPE='UNSPEC';
      PINUSE='UNSPEC';
  end_pin;
  body
      PART_NAME='RES';
      PHYS_DES_PREFIX='R';
      ENVCOMP='YES;YES;YES;UNK;OK;VLD';
      PART_NUMBER='G21796-250';
      JEDEC_TYPE='SMR0402A';
      ALT_SYMBOLS='(SMX0402,SMX0402A,SMX0402B)';
      VALUE='22.1';
      TOL='1.0%';
      WATTAGE='1/16W';
      CLASS='DISCRETE';
      DESCRIPTION='RES_D,0402,22.10OHM,1.00%,1/16W,';
      HEIGHT='0.016 IN';
      COMPONENT_TYPE='CHIP0402';
      LEAD_LENGTH='';
      LPID='1141';
      SPEED_URL='http://speed.intel.com:8081/speed/module/pdm/item/pdm_item_deta~
il_direct.asp?item_cde=G21796-250&item_rev=01&url_param=unused';
      STATUS='DESIGN';
      RPL='NO';
      AML='3';
      BUS_UNIT='GMPO_BD_EXMPFREE';
      DAYS='???';
      PARENT_PART_TYPE='RES';
      PARENT_PPT='RES';
      PARENT_PPT_PART='RES_0402-22.1,1.0%,1/16W,CHIP,G21796-250';
  end_body;
end_primitive;
primitive 'RES_0402-221,1.0%,1/16W,CHIP,GA';
  pin
    'A':
      PIN_GROUP='1';
      PIN_NUMBER='(1)';
      PIN_TYPE='UNSPEC';
      PINUSE='UNSPEC';
    'B':
      PIN_GROUP='1';
      PIN_NUMBER='(2)';
      PIN_TYPE='UNSPEC';
      PINUSE='UNSPEC';
  end_pin;
  body
      PART_NAME='RES';
      PHYS_DES_PREFIX='R';
      ENVCOMP='YES;YES;YES;UNK;OK;VLD';
      PART_NUMBER='G21796-271';
      JEDEC_TYPE='SMR0402A';
      ALT_SYMBOLS='(SMX0402,SMX0402A,SMX0402B)';
      VALUE='221';
      TOL='1.0%';
      WATTAGE='1/16W';
      CLASS='DISCRETE';
      DESCRIPTION='RES_D,0402,221.00OHM,1.00%,1/16W,';
      HEIGHT='0.016 IN';
      COMPONENT_TYPE='CHIP0402';
      LEAD_LENGTH='';
      LPID='1141';
      SPEED_URL='http://speed.intel.com:8081/speed/module/pdm/item/pdm_item_deta~
il_direct.asp?item_cde=G21796-271&item_rev=01&url_param=unused';
      STATUS='DESIGN';
      RPL='NO';
      AML='3';
      BUS_UNIT='GMPO_BD_EXMPFREE';
      DAYS='???';
      PARENT_PART_TYPE='RES';
      PARENT_PPT='RES';
      PARENT_PPT_PART='RES_0402-221,1.0%,1/16W,CHIP,G21796-271';
  end_body;
end_primitive;
primitive 'RES_0402-23.2K,1%,1/16W,CHIP,GA';
  pin
    'A':
      PIN_GROUP='1';
      PIN_NUMBER='(1)';
      PIN_TYPE='UNSPEC';
      PINUSE='UNSPEC';
    'B':
      PIN_GROUP='1';
      PIN_NUMBER='(2)';
      PIN_TYPE='UNSPEC';
      PINUSE='UNSPEC';
  end_pin;
  body
      PART_NAME='RES';
      PHYS_DES_PREFIX='R';
      ENVCOMP='YES;YES;YES;UNK;OK;VLD';
      PART_NUMBER='G21796-114';
      JEDEC_TYPE='SMR0402A';
      ALT_SYMBOLS='(SMX0402,SMX0402A,SMX0402B)';
      VALUE='23.2K';
      TOL='1%';
      WATTAGE='1/16W';
      CLASS='DISCRETE';
      DESCRIPTION='RES_D,0402,23.2KOHM,1.00%,1/16W';
      HEIGHT='0.017 IN';
      COMPONENT_TYPE='CHIP0402';
      LEAD_LENGTH='';
      LPID='1141';
      SPEED_URL='http://speed.intel.com:8081/speed/module/pdm/item/pdm_item_deta~
il_direct.asp?item_cde=G21796-114&item_rev=01&url_param=unused';
      STATUS='DESIGN';
      RPL='NO';
      AML='3';
      BUS_UNIT='GMPO_BD_EXMPFREE';
      DAYS='???';
      PARENT_PART_TYPE='RES';
      PARENT_PPT='RES';
      PARENT_PPT_PART='RES_0402-23.2K,1%,1/16W,CHIP,G21796-114';
  end_body;
end_primitive;
primitive 'RES_0402-24.9K,1%,1/16W,CHIP,GA';
  pin
    'A':
      PIN_GROUP='1';
      PIN_NUMBER='(1)';
      PIN_TYPE='UNSPEC';
      PINUSE='UNSPEC';
    'B':
      PIN_GROUP='1';
      PIN_NUMBER='(2)';
      PIN_TYPE='UNSPEC';
      PINUSE='UNSPEC';
  end_pin;
  body
      PART_NAME='RES';
      PHYS_DES_PREFIX='R';
      ENVCOMP='';
      PART_NUMBER='G21796-254';
      JEDEC_TYPE='SMR0402A';
      ALT_SYMBOLS='(SMX0402,SMX0402A,SMX0402B)';
      VALUE='24.9K';
      TOL='1%';
      WATTAGE='1/16W';
      CLASS='DISCRETE';
      DESCRIPTION='RES_D,0402,24.90kOHM,1.00%,1/16W,';
      HEIGHT='0.016 IN';
      COMPONENT_TYPE='CHIP0402';
      LEAD_LENGTH='';
      LPID='1141';
      SPEED_URL='http://speed.intel.com:8081/speed/module/pdm/item/pdm_item_deta~
il_direct.asp?item_cde=G21796-254&item_rev=01&url_param=unused';
      STATUS='';
      RPL='';
      AML='';
      BUS_UNIT='';
      DAYS='';
      PARENT_PART_TYPE='RES';
      PARENT_PPT='RES';
      PARENT_PPT_PART='RES_0402-24.9K,1%,1/16W,CHIP,G21796-254';
  end_body;
end_primitive;
primitive 'RES_0402-240,1.0%,1/16W,CHIP,GA';
  pin
    'A':
      PIN_GROUP='1';
      PIN_NUMBER='(1)';
      PIN_TYPE='UNSPEC';
      PINUSE='UNSPEC';
    'B':
      PIN_GROUP='1';
      PIN_NUMBER='(2)';
      PIN_TYPE='UNSPEC';
      PINUSE='UNSPEC';
  end_pin;
  body
      PART_NAME='RES';
      PHYS_DES_PREFIX='R';
      ENVCOMP='YES;YES;YES;UNK;OK;VLD';
      PART_NUMBER='G21796-294';
      JEDEC_TYPE='SMR0402A';
      ALT_SYMBOLS='(SMX0402,SMX0402A,SMX0402B)';
      VALUE='240';
      TOL='1.0%';
      WATTAGE='1/16W';
      CLASS='DISCRETE';
      DESCRIPTION='RES_D,0402,240.00OHM,1.00%,1/16W,';
      HEIGHT='0.016 IN';
      COMPONENT_TYPE='CHIP0402';
      LEAD_LENGTH='';
      LPID='1141';
      SPEED_URL='http://speed.intel.com:8081/speed/module/pdm/item/pdm_item_deta~
il_direct.asp?item_cde=G21796-294&item_rev=01&url_param=unused';
      STATUS='DESIGN';
      RPL='NO';
      AML='3';
      BUS_UNIT='GMPO_BD_EXMPFREE';
      DAYS='???';
      PARENT_PART_TYPE='RES';
      PARENT_PPT='RES';
      PARENT_PPT_PART='RES_0402-240,1.0%,1/16W,CHIP,G21796-294';
  end_body;
end_primitive;
primitive 'RES_0402-240,1.0%,1/16W,EMPTY,A';
  pin
    'A':
      PIN_GROUP='1';
      PIN_NUMBER='(1)';
      PIN_TYPE='UNSPEC';
      PINUSE='UNSPEC';
    'B':
      PIN_GROUP='1';
      PIN_NUMBER='(2)';
      PIN_TYPE='UNSPEC';
      PINUSE='UNSPEC';
  end_pin;
  body
      PART_NAME='RES';
      PHYS_DES_PREFIX='R';
      ENVCOMP='YES;YES;YES;UNK;OK;VLD';
      PART_NUMBER='G21796-294';
      JEDEC_TYPE='SMR0402A';
      ALT_SYMBOLS='(SMX0402,SMX0402A,SMX0402B)';
      VALUE='NA';
      TOL='1.0%';
      WATTAGE='1/16W';
      CLASS='DISCRETE';
      DESCRIPTION='RES_D,0402,240.00OHM,1.00%,1/16W,';
      HEIGHT='0.016 IN';
      COMPONENT_TYPE='CHIP0402';
      LEAD_LENGTH='';
      LPID='1141';
      SPEED_URL='http://speed.intel.com:8081/speed/module/pdm/item/pdm_item_deta~
il_direct.asp?item_cde=G21796-294&item_rev=01&url_param=unused';
      STATUS='DESIGN';
      RPL='NO';
      AML='3';
      BUS_UNIT='GMPO_BD_EXMPFREE';
      DAYS='???';
      PARENT_PART_TYPE='RES';
      PARENT_PPT='RES';
      PARENT_PPT_PART='RES_0402-240,1.0%,1/16W,EMPTY,G21796-294';
  end_body;
end_primitive;
primitive 'RES_0402-249,0.1%,1/16W,CHIP,GA';
  pin
    'A':
      PIN_GROUP='1';
      PIN_NUMBER='(1)';
      PIN_TYPE='UNSPEC';
      PINUSE='UNSPEC';
    'B':
      PIN_GROUP='1';
      PIN_NUMBER='(2)';
      PIN_TYPE='UNSPEC';
      PINUSE='UNSPEC';
  end_pin;
  body
      PART_NAME='RES';
      PHYS_DES_PREFIX='R';
      ENVCOMP='';
      PART_NUMBER='G85996-031';
      JEDEC_TYPE='SMR0402A';
      ALT_SYMBOLS='(SMX0402,SMX0402A)';
      VALUE='249';
      TOL='0.1%';
      WATTAGE='1/16W';
      CLASS='DISCRETE';
      DESCRIPTION='RES_D,0402,249.00OHM,0.1%,1/16W,';
      HEIGHT='0.016 IN';
      COMPONENT_TYPE='CHIP0402';
      LEAD_LENGTH='';
      LPID='1141';
      SPEED_URL='http://speed.intel.com:8081/speed/module/pdm/item/pdm_item_deta~
il_direct.asp?item_cde=G85996-031&item_rev=01&url_param=unused';
      STATUS='';
      RPL='';
      AML='';
      BUS_UNIT='';
      DAYS='';
      PARENT_PART_TYPE='RES';
      PARENT_PPT='RES';
      PARENT_PPT_PART='RES_0402-249,0.1%,1/16W,CHIP,G85996-031';
  end_body;
end_primitive;
primitive 'RES_0402-27.4,1%,1/16W,CHIP,G2A';
  pin
    'A':
      PIN_GROUP='1';
      PIN_NUMBER='(1)';
      PIN_TYPE='UNSPEC';
      PINUSE='UNSPEC';
    'B':
      PIN_GROUP='1';
      PIN_NUMBER='(2)';
      PIN_TYPE='UNSPEC';
      PINUSE='UNSPEC';
  end_pin;
  body
      PART_NAME='RES';
      PHYS_DES_PREFIX='R';
      ENVCOMP='YES;YES;YES;UNK;OK;VLD';
      PART_NUMBER='G21796-182';
      JEDEC_TYPE='SMR0402A';
      ALT_SYMBOLS='(SMX0402,SMX0402A,SMX0402B)';
      VALUE='27.4';
      TOL='1%';
      WATTAGE='1/16W';
      CLASS='DISCRETE';
      DESCRIPTION='RES_D,0402,27.4OHM,1.00%,1/16W';
      HEIGHT='0.017 IN';
      COMPONENT_TYPE='CHIP0402';
      LEAD_LENGTH='';
      LPID='1141';
      SPEED_URL='http://speed.intel.com:8081/speed/module/pdm/item/pdm_item_deta~
il_direct.asp?item_cde=G21796-182&item_rev=01&url_param=unused';
      STATUS='DESIGN';
      RPL='NO';
      AML='3';
      BUS_UNIT='GMPO_BD_EXMPFREE';
      DAYS='???';
      PARENT_PART_TYPE='RES';
      PARENT_PPT='RES';
      PARENT_PPT_PART='RES_0402-27.4,1%,1/16W,CHIP,G21796-182';
  end_body;
end_primitive;
primitive 'RES_0402-3.16K,1%,1/16W,CHIP,GA';
  pin
    'A':
      PIN_GROUP='1';
      PIN_NUMBER='(1)';
      PIN_TYPE='UNSPEC';
      PINUSE='UNSPEC';
    'B':
      PIN_GROUP='1';
      PIN_NUMBER='(2)';
      PIN_TYPE='UNSPEC';
      PINUSE='UNSPEC';
  end_pin;
  body
      PART_NAME='RES';
      PHYS_DES_PREFIX='R';
      ENVCOMP='YES;YES;YES;UNK;OK;VLD';
      PART_NUMBER='G21796-043';
      JEDEC_TYPE='SMR0402A';
      ALT_SYMBOLS='(SMX0402,SMX0402A,SMX0402B)';
      VALUE='3.16K';
      TOL='1%';
      WATTAGE='1/16W';
      CLASS='DISCRETE';
      DESCRIPTION='RES_D,0402,3.16KOHM,1.00%,1/16W';
      HEIGHT='0.017 IN';
      COMPONENT_TYPE='CHIP0402';
      LEAD_LENGTH='';
      LPID='1141';
      SPEED_URL='http://speed.intel.com:8081/speed/module/pdm/item/pdm_item_deta~
il_direct.asp?item_cde=G21796-043&item_rev=01&url_param=unused';
      STATUS='DESIGN';
      RPL='NO';
      AML='4';
      BUS_UNIT='GMPO_BD_EXMPFREE';
      DAYS='???';
      PARENT_PART_TYPE='RES';
      PARENT_PPT='RES';
      PARENT_PPT_PART='RES_0402-3.16K,1%,1/16W,CHIP,G21796-043';
  end_body;
end_primitive;
primitive 'RES_0402-3.32K,1%,1/16W,CHIP,GA';
  pin
    'A':
      PIN_GROUP='1';
      PIN_NUMBER='(1)';
      PIN_TYPE='UNSPEC';
      PINUSE='UNSPEC';
    'B':
      PIN_GROUP='1';
      PIN_NUMBER='(2)';
      PIN_TYPE='UNSPEC';
      PINUSE='UNSPEC';
  end_pin;
  body
      PART_NAME='RES';
      PHYS_DES_PREFIX='R';
      ENVCOMP='YES;YES;YES;UNK;OK;VLD';
      PART_NUMBER='G21796-027';
      JEDEC_TYPE='SMR0402A';
      ALT_SYMBOLS='(SMX0402,SMX0402A,SMX0402B)';
      VALUE='3.32K';
      TOL='1%';
      WATTAGE='1/16W';
      CLASS='DISCRETE';
      DESCRIPTION='RES_D,0402,3.32KOHM,1.00%,1/16W';
      HEIGHT='0.017 IN';
      COMPONENT_TYPE='CHIP0402';
      LEAD_LENGTH='';
      LPID='1141';
      SPEED_URL='http://speed.intel.com:8081/speed/module/pdm/item/pdm_item_deta~
il_direct.asp?item_cde=G21796-027&item_rev=01&url_param=unused';
      STATUS='UNQUAL';
      RPL='NO';
      AML='5';
      BUS_UNIT='GMPO_BD_EXMPFREE';
      DAYS='???';
      PARENT_PART_TYPE='RES';
      PARENT_PPT='RES';
      PARENT_PPT_PART='RES_0402-3.32K,1%,1/16W,CHIP,G21796-027';
  end_body;
end_primitive;
primitive 'RES_0402-3.32K,1%,1/16W,EMPTY,A';
  pin
    'A':
      PIN_GROUP='1';
      PIN_NUMBER='(1)';
      PIN_TYPE='UNSPEC';
      PINUSE='UNSPEC';
    'B':
      PIN_GROUP='1';
      PIN_NUMBER='(2)';
      PIN_TYPE='UNSPEC';
      PINUSE='UNSPEC';
  end_pin;
  body
      PART_NAME='RES';
      PHYS_DES_PREFIX='R';
      ENVCOMP='YES;YES;YES;UNK;OK;VLD';
      PART_NUMBER='G21796-027';
      JEDEC_TYPE='SMR0402A';
      ALT_SYMBOLS='(SMX0402,SMX0402A,SMX0402B)';
      VALUE='NA';
      TOL='1%';
      WATTAGE='1/16W';
      CLASS='DISCRETE';
      DESCRIPTION='RES_D,0402,3.32KOHM,1.00%,1/16W';
      HEIGHT='0.017 IN';
      COMPONENT_TYPE='CHIP0402';
      LEAD_LENGTH='';
      LPID='1141';
      SPEED_URL='http://speed.intel.com:8081/speed/module/pdm/item/pdm_item_deta~
il_direct.asp?item_cde=G21796-027&item_rev=01&url_param=unused';
      STATUS='UNQUAL';
      RPL='NO';
      AML='5';
      BUS_UNIT='GMPO_BD_EXMPFREE';
      DAYS='???';
      PARENT_PART_TYPE='RES';
      PARENT_PPT='RES';
      PARENT_PPT_PART='RES_0402-3.32K,1%,1/16W,EMPTY,G21796-027';
  end_body;
end_primitive;
primitive 'RES_0402-3.3K,5%,1/16W,CHIP,G2A';
  pin
    'A':
      PIN_GROUP='1';
      PIN_NUMBER='(1)';
      PIN_TYPE='UNSPEC';
      PINUSE='UNSPEC';
    'B':
      PIN_GROUP='1';
      PIN_NUMBER='(2)';
      PIN_TYPE='UNSPEC';
      PINUSE='UNSPEC';
  end_pin;
  body
      PART_NAME='RES';
      PHYS_DES_PREFIX='R';
      ENVCOMP='YES;YES;YES;UNK;OK;VLD';
      PART_NUMBER='G21497-013';
      JEDEC_TYPE='SMR0402A';
      ALT_SYMBOLS='(SMX0402,SMX0402A,SMX0402B)';
      VALUE='3.3K';
      TOL='5%';
      WATTAGE='1/16W';
      CLASS='DISCRETE';
      DESCRIPTION='RES_D,0402,3.3KOHM,5.00%,1/16W';
      HEIGHT='0.017 IN';
      COMPONENT_TYPE='CHIP0402';
      LEAD_LENGTH='';
      LPID='1141';
      SPEED_URL='http://speed.intel.com:8081/speed/module/pdm/item/pdm_item_deta~
il_direct.asp?item_cde=G21497-013&item_rev=01&url_param=unused';
      STATUS='UNQUAL';
      RPL='NO';
      AML='3';
      BUS_UNIT='GMPO_BD_EXMPFREE';
      DAYS='???';
      PARENT_PART_TYPE='RES';
      PARENT_PPT='RES';
      PARENT_PPT_PART='RES_0402-3.3K,5%,1/16W,CHIP,G21497-013';
  end_body;
end_primitive;
primitive 'RES_0402-3.48K,1.0%,1/16W,CHIPA';
  pin
    'A':
      PIN_GROUP='1';
      PIN_NUMBER='(1)';
      PIN_TYPE='UNSPEC';
      PINUSE='UNSPEC';
    'B':
      PIN_GROUP='1';
      PIN_NUMBER='(2)';
      PIN_TYPE='UNSPEC';
      PINUSE='UNSPEC';
  end_pin;
  body
      PART_NAME='RES';
      PHYS_DES_PREFIX='R';
      ENVCOMP='YES;YES;YES;UNK;OK;VLD';
      PART_NUMBER='G21796-279';
      JEDEC_TYPE='SMR0402A';
      ALT_SYMBOLS='(SMX0402,SMX0402A,SMX0402B)';
      VALUE='3.48K';
      TOL='1.0%';
      WATTAGE='1/16W';
      CLASS='DISCRETE';
      DESCRIPTION='RES_D,0402,3.48KOHM,1.00%,1/16W,';
      HEIGHT='0.016 IN';
      COMPONENT_TYPE='CHIP0402';
      LEAD_LENGTH='';
      LPID='1141';
      SPEED_URL='http://speed.intel.com:8081/speed/module/pdm/item/pdm_item_deta~
il_direct.asp?item_cde=G21796-279&item_rev=01&url_param=unused';
      STATUS='DESIGN';
      RPL='NO';
      AML='3';
      BUS_UNIT='GMPO_BD_EXMPFREE';
      DAYS='???';
      PARENT_PART_TYPE='RES';
      PARENT_PPT='RES';
      PARENT_PPT_PART='RES_0402-3.48K,1.0%,1/16W,CHIP,G21796-279';
  end_body;
end_primitive;
primitive 'RES_0402-3.74K,1%,1/16W,CHIP,GA';
  pin
    'A':
      PIN_GROUP='1';
      PIN_NUMBER='(1)';
      PIN_TYPE='UNSPEC';
      PINUSE='UNSPEC';
    'B':
      PIN_GROUP='1';
      PIN_NUMBER='(2)';
      PIN_TYPE='UNSPEC';
      PINUSE='UNSPEC';
  end_pin;
  body
      PART_NAME='RES';
      PHYS_DES_PREFIX='R';
      ENVCOMP='YES;YES;YES;UNK;OK;VLD';
      PART_NUMBER='G21796-059';
      JEDEC_TYPE='SMR0402A';
      ALT_SYMBOLS='(SMX0402,SMX0402A,SMX0402B)';
      VALUE='3.74K';
      TOL='1%';
      WATTAGE='1/16W';
      CLASS='DISCRETE';
      DESCRIPTION='RES_D,0402,3.74KOHM,1.00%,1/16W';
      HEIGHT='0.017 IN';
      COMPONENT_TYPE='CHIP0402';
      LEAD_LENGTH='';
      LPID='1141';
      SPEED_URL='http://speed.intel.com:8081/speed/module/pdm/item/pdm_item_deta~
il_direct.asp?item_cde=G21796-059&item_rev=01&url_param=unused';
      STATUS='DESIGN';
      RPL='NO';
      AML='4';
      BUS_UNIT='GMPO_BD_EXMPFREE';
      DAYS='???';
      PARENT_PART_TYPE='RES';
      PARENT_PPT='RES';
      PARENT_PPT_PART='RES_0402-3.74K,1%,1/16W,CHIP,G21796-059';
  end_body;
end_primitive;
primitive 'RES_0402-301.0,1%,1/16W,CHIP,GA';
  pin
    'A':
      PIN_GROUP='1';
      PIN_NUMBER='(1)';
      PIN_TYPE='UNSPEC';
      PINUSE='UNSPEC';
    'B':
      PIN_GROUP='1';
      PIN_NUMBER='(2)';
      PIN_TYPE='UNSPEC';
      PINUSE='UNSPEC';
  end_pin;
  body
      PART_NAME='RES';
      PHYS_DES_PREFIX='R';
      ENVCOMP='YES;YES;YES;UNK;OK;VLD';
      PART_NUMBER='G21796-076';
      JEDEC_TYPE='SMR0402A';
      ALT_SYMBOLS='(SMX0402,SMX0402A,SMX0402B)';
      VALUE='301.0';
      TOL='1%';
      WATTAGE='1/16W';
      CLASS='DISCRETE';
      DESCRIPTION='RES_D,0402,301.0OHM,1.00%,1/16W';
      HEIGHT='0.017 IN';
      COMPONENT_TYPE='CHIP0402';
      LEAD_LENGTH='';
      LPID='1141';
      SPEED_URL='http://speed.intel.com:8081/speed/module/pdm/item/pdm_item_deta~
il_direct.asp?item_cde=G21796-076&item_rev=01&url_param=unused';
      STATUS='UNQUAL';
      RPL='NO';
      AML='3';
      BUS_UNIT='GMPO_BD_EXMPFREE';
      DAYS='???';
      PARENT_PART_TYPE='RES';
      PARENT_PPT='RES';
      PARENT_PPT_PART='RES_0402-301.0,1%,1/16W,CHIP,G21796-076';
  end_body;
end_primitive;
primitive 'RES_0402-33.0K,5%,1/16W,CHIP,GA';
  pin
    'A':
      PIN_GROUP='1';
      PIN_NUMBER='(1)';
      PIN_TYPE='UNSPEC';
      PINUSE='UNSPEC';
    'B':
      PIN_GROUP='1';
      PIN_NUMBER='(2)';
      PIN_TYPE='UNSPEC';
      PINUSE='UNSPEC';
  end_pin;
  body
      PART_NAME='RES';
      PHYS_DES_PREFIX='R';
      ENVCOMP='YES;YES;YES;UNK;OK;VLD';
      PART_NUMBER='G21497-023';
      JEDEC_TYPE='SMR0402A';
      ALT_SYMBOLS='(SMX0402,SMX0402A,SMX0402B)';
      VALUE='33.0K';
      TOL='5%';
      WATTAGE='1/16W';
      CLASS='DISCRETE';
      DESCRIPTION='RES_D,0402,33.0KOHM,5.00%,1/16W';
      HEIGHT='0.017 IN';
      COMPONENT_TYPE='CHIP0402';
      LEAD_LENGTH='';
      LPID='1141';
      SPEED_URL='http://speed.intel.com:8081/speed/module/pdm/item/pdm_item_deta~
il_direct.asp?item_cde=G21497-023&item_rev=01&url_param=unused';
      STATUS='DESIGN';
      RPL='NO';
      AML='3';
      BUS_UNIT='GMPO_BD_EXMPFREE';
      DAYS='???';
      PARENT_PART_TYPE='RES';
      PARENT_PPT='RES';
      PARENT_PPT_PART='RES_0402-33.0K,5%,1/16W,CHIP,G21497-023';
  end_body;
end_primitive;
primitive 'RES_0402-33.2,1%,1/16W,CHIP,G2A';
  pin
    'A':
      PIN_GROUP='1';
      PIN_NUMBER='(1)';
      PIN_TYPE='UNSPEC';
      PINUSE='UNSPEC';
    'B':
      PIN_GROUP='1';
      PIN_NUMBER='(2)';
      PIN_TYPE='UNSPEC';
      PINUSE='UNSPEC';
  end_pin;
  body
      PART_NAME='RES';
      PHYS_DES_PREFIX='R';
      ENVCOMP='YES;YES;YES;UNK;OK;VLD';
      PART_NUMBER='G21796-074';
      JEDEC_TYPE='SMR0402A';
      ALT_SYMBOLS='(SMX0402,SMX0402A,SMX0402B)';
      VALUE='33.2';
      TOL='1%';
      WATTAGE='1/16W';
      CLASS='DISCRETE';
      DESCRIPTION='RES_D,0402,33.2OHM,1.00%,1/16W';
      HEIGHT='0.017 IN';
      COMPONENT_TYPE='CHIP0402';
      LEAD_LENGTH='';
      LPID='1141';
      SPEED_URL='http://speed.intel.com:8081/speed/module/pdm/item/pdm_item_deta~
il_direct.asp?item_cde=G21796-074&item_rev=01&url_param=unused';
      STATUS='UNQUAL';
      RPL='NO';
      AML='3';
      BUS_UNIT='GMPO_BD_EXMPFREE';
      DAYS='???';
      PARENT_PART_TYPE='RES';
      PARENT_PPT='RES';
      PARENT_PPT_PART='RES_0402-33.2,1%,1/16W,CHIP,G21796-074';
  end_body;
end_primitive;
primitive 'RES_0402-33.2,1%,1/16W,EMPTY,GA';
  pin
    'A':
      PIN_GROUP='1';
      PIN_NUMBER='(1)';
      PIN_TYPE='UNSPEC';
      PINUSE='UNSPEC';
    'B':
      PIN_GROUP='1';
      PIN_NUMBER='(2)';
      PIN_TYPE='UNSPEC';
      PINUSE='UNSPEC';
  end_pin;
  body
      PART_NAME='RES';
      PHYS_DES_PREFIX='R';
      ENVCOMP='YES;YES;YES;UNK;OK;VLD';
      PART_NUMBER='G21796-074';
      JEDEC_TYPE='SMR0402A';
      ALT_SYMBOLS='(SMX0402,SMX0402A,SMX0402B)';
      VALUE='NA';
      TOL='1%';
      WATTAGE='1/16W';
      CLASS='DISCRETE';
      DESCRIPTION='RES_D,0402,33.2OHM,1.00%,1/16W';
      HEIGHT='0.017 IN';
      COMPONENT_TYPE='CHIP0402';
      LEAD_LENGTH='';
      LPID='1141';
      SPEED_URL='http://speed.intel.com:8081/speed/module/pdm/item/pdm_item_deta~
il_direct.asp?item_cde=G21796-074&item_rev=01&url_param=unused';
      STATUS='UNQUAL';
      RPL='NO';
      AML='3';
      BUS_UNIT='GMPO_BD_EXMPFREE';
      DAYS='???';
      PARENT_PART_TYPE='RES';
      PARENT_PPT='RES';
      PARENT_PPT_PART='RES_0402-33.2,1%,1/16W,EMPTY,G21796-074';
  end_body;
end_primitive;
primitive 'RES_0402-330,5%,1/16W,CHIP,G21A';
  pin
    'A':
      PIN_GROUP='1';
      PIN_NUMBER='(1)';
      PIN_TYPE='UNSPEC';
      PINUSE='UNSPEC';
    'B':
      PIN_GROUP='1';
      PIN_NUMBER='(2)';
      PIN_TYPE='UNSPEC';
      PINUSE='UNSPEC';
  end_pin;
  body
      PART_NAME='RES';
      PHYS_DES_PREFIX='R';
      ENVCOMP='YES;YES;YES;UNK;OK;VLD';
      PART_NUMBER='G21497-028';
      JEDEC_TYPE='SMR0402A';
      ALT_SYMBOLS='(SMX0402,SMX0402A,SMX0402B)';
      VALUE='300';
      TOL='5%';
      WATTAGE='1/16W';
      CLASS='DISCRETE';
      DESCRIPTION='RES_D,0402,330.00OHM,5.00%,1/16W';
      HEIGHT='0.016 IN';
      COMPONENT_TYPE='CHIP0402';
      LEAD_LENGTH='';
      LPID='1141';
      SPEED_URL='http://speed.intel.com:8081/speed/module/pdm/item/pdm_item_deta~
il_direct.asp?item_cde=G21497-028&item_rev=01&url_param=unused';
      STATUS='UNQUAL';
      RPL='NO';
      AML='2';
      BUS_UNIT='GMPO_BD_EXMPFREE';
      DAYS='???';
      PARENT_PART_TYPE='RES';
      PARENT_PPT='RES';
      PARENT_PPT_PART='RES_0402-330,5%,1/16W,CHIP,G21497-028';
  end_body;
end_primitive;
primitive 'RES_0402-348,1%,1/16W,CHIP,G21A';
  pin
    'A':
      PIN_GROUP='1';
      PIN_NUMBER='(1)';
      PIN_TYPE='UNSPEC';
      PINUSE='UNSPEC';
    'B':
      PIN_GROUP='1';
      PIN_NUMBER='(2)';
      PIN_TYPE='UNSPEC';
      PINUSE='UNSPEC';
  end_pin;
  body
      PART_NAME='RES';
      PHYS_DES_PREFIX='R';
      ENVCOMP='';
      PART_NUMBER='G21796-340';
      JEDEC_TYPE='SMR0402A';
      ALT_SYMBOLS='(SMX0402,SMX0402A,SMX0402B)';
      VALUE='348';
      TOL='1%';
      WATTAGE='1/16W';
      CLASS='DISCRETE';
      DESCRIPTION='RES_D,0402,348.00OHM,1.00%,1/16W,';
      HEIGHT='0.016 IN';
      COMPONENT_TYPE='CHIP0402';
      LEAD_LENGTH='';
      LPID='1141';
      SPEED_URL='http://speed.intel.com:8081/speed/module/pdm/item/pdm_item_deta~
il_direct.asp?item_cde=G21796-340&item_rev=01&url_param=unused';
      STATUS='';
      RPL='';
      AML='';
      BUS_UNIT='';
      DAYS='';
      PARENT_PART_TYPE='RES';
      PARENT_PPT='RES';
      PARENT_PPT_PART='RES_0402-348,1%,1/16W,CHIP,G21796-340';
  end_body;
end_primitive;
primitive 'RES_0402-348,1%,1/16W,EMPTY,G2A';
  pin
    'A':
      PIN_GROUP='1';
      PIN_NUMBER='(1)';
      PIN_TYPE='UNSPEC';
      PINUSE='UNSPEC';
    'B':
      PIN_GROUP='1';
      PIN_NUMBER='(2)';
      PIN_TYPE='UNSPEC';
      PINUSE='UNSPEC';
  end_pin;
  body
      PART_NAME='RES';
      PHYS_DES_PREFIX='R';
      ENVCOMP='';
      PART_NUMBER='G21796-340';
      JEDEC_TYPE='SMR0402A';
      ALT_SYMBOLS='(SMX0402,SMX0402A,SMX0402B)';
      VALUE='NA';
      TOL='1%';
      WATTAGE='1/16W';
      CLASS='DISCRETE';
      DESCRIPTION='RES_D,0402,348.00OHM,1.00%,1/16W,';
      HEIGHT='0.016 IN';
      COMPONENT_TYPE='CHIP0402';
      LEAD_LENGTH='';
      LPID='1141';
      SPEED_URL='http://speed.intel.com:8081/speed/module/pdm/item/pdm_item_deta~
il_direct.asp?item_cde=G21796-340&item_rev=01&url_param=unused';
      STATUS='';
      RPL='';
      AML='';
      BUS_UNIT='';
      DAYS='';
      PARENT_PART_TYPE='RES';
      PARENT_PPT='RES';
      PARENT_PPT_PART='RES_0402-348,1%,1/16W,EMPTY,G21796-340';
  end_body;
end_primitive;
primitive 'RES_0402-4.02K,1%,1/16W,CHIP,GA';
  pin
    'A':
      PIN_GROUP='1';
      PIN_NUMBER='(1)';
      PIN_TYPE='UNSPEC';
      PINUSE='UNSPEC';
    'B':
      PIN_GROUP='1';
      PIN_NUMBER='(2)';
      PIN_TYPE='UNSPEC';
      PINUSE='UNSPEC';
  end_pin;
  body
      PART_NAME='RES';
      PHYS_DES_PREFIX='R';
      ENVCOMP='YES;YES;YES;UNK;OK;VLD';
      PART_NUMBER='G21796-082';
      JEDEC_TYPE='SMR0402A';
      ALT_SYMBOLS='(SMX0402,SMX0402A,SMX0402B)';
      VALUE='4.02K';
      TOL='1%';
      WATTAGE='1/16W';
      CLASS='DISCRETE';
      DESCRIPTION='RES_D,0402,4.02KOHM,1.00%,1/16W';
      HEIGHT='0.017 IN';
      COMPONENT_TYPE='CHIP0402';
      LEAD_LENGTH='';
      LPID='1141';
      SPEED_URL='http://speed.intel.com:8081/speed/module/pdm/item/pdm_item_deta~
il_direct.asp?item_cde=G21796-082&item_rev=01&url_param=unused';
      STATUS='UNQUAL';
      RPL='NO';
      AML='3';
      BUS_UNIT='GMPO_BD_EXMPFREE';
      DAYS='???';
      PARENT_PART_TYPE='RES';
      PARENT_PPT='RES';
      PARENT_PPT_PART='RES_0402-4.02K,1%,1/16W,CHIP,G21796-082';
  end_body;
end_primitive;
primitive 'RES_0402-4.75K,1%,1/16W,CHIP,GA';
  pin
    'A':
      PIN_GROUP='1';
      PIN_NUMBER='(1)';
      PIN_TYPE='UNSPEC';
      PINUSE='UNSPEC';
    'B':
      PIN_GROUP='1';
      PIN_NUMBER='(2)';
      PIN_TYPE='UNSPEC';
      PINUSE='UNSPEC';
  end_pin;
  body
      PART_NAME='RES';
      PHYS_DES_PREFIX='R';
      ENVCOMP='YES;YES;YES;UNK;OK;VLD';
      PART_NUMBER='G21796-072';
      JEDEC_TYPE='SMR0402A';
      ALT_SYMBOLS='(SMX0402,SMX0402A,SMX0402B)';
      VALUE='4.75K';
      TOL='1%';
      WATTAGE='1/16W';
      CLASS='DISCRETE';
      DESCRIPTION='RES_D,0402,4.75KOHM,1.00%,1/16W';
      HEIGHT='0.017 IN';
      COMPONENT_TYPE='CHIP0402';
      LEAD_LENGTH='';
      LPID='1141';
      SPEED_URL='http://speed.intel.com:8081/speed/module/pdm/item/pdm_item_deta~
il_direct.asp?item_cde=G21796-072&item_rev=01&url_param=unused';
      STATUS='UNQUAL';
      RPL='NO';
      AML='3';
      BUS_UNIT='GMPO_BD_EXMPFREE';
      DAYS='???';
      PARENT_PART_TYPE='RES';
      PARENT_PPT='RES';
      PARENT_PPT_PART='RES_0402-4.75K,1%,1/16W,CHIP,G21796-072';
  end_body;
end_primitive;
primitive 'RES_0402-4.75K,1%,1/16W,EMPTY,A';
  pin
    'A':
      PIN_GROUP='1';
      PIN_NUMBER='(1)';
      PIN_TYPE='UNSPEC';
      PINUSE='UNSPEC';
    'B':
      PIN_GROUP='1';
      PIN_NUMBER='(2)';
      PIN_TYPE='UNSPEC';
      PINUSE='UNSPEC';
  end_pin;
  body
      PART_NAME='RES';
      PHYS_DES_PREFIX='R';
      ENVCOMP='YES;YES;YES;UNK;OK;VLD';
      PART_NUMBER='G21796-072';
      JEDEC_TYPE='SMR0402A';
      ALT_SYMBOLS='(SMX0402,SMX0402A,SMX0402B)';
      VALUE='NA';
      TOL='1%';
      WATTAGE='1/16W';
      CLASS='DISCRETE';
      DESCRIPTION='RES_D,0402,4.75KOHM,1.00%,1/16W';
      HEIGHT='0.017 IN';
      COMPONENT_TYPE='CHIP0402';
      LEAD_LENGTH='';
      LPID='1141';
      SPEED_URL='http://speed.intel.com:8081/speed/module/pdm/item/pdm_item_deta~
il_direct.asp?item_cde=G21796-072&item_rev=01&url_param=unused';
      STATUS='UNQUAL';
      RPL='NO';
      AML='3';
      BUS_UNIT='GMPO_BD_EXMPFREE';
      DAYS='???';
      PARENT_PART_TYPE='RES';
      PARENT_PPT='RES';
      PARENT_PPT_PART='RES_0402-4.75K,1%,1/16W,EMPTY,G21796-072';
  end_body;
end_primitive;
primitive 'RES_0402-4.99K,1%,1/16W,CHIP,GA';
  pin
    'A':
      PIN_GROUP='1';
      PIN_NUMBER='(1)';
      PIN_TYPE='UNSPEC';
      PINUSE='UNSPEC';
    'B':
      PIN_GROUP='1';
      PIN_NUMBER='(2)';
      PIN_TYPE='UNSPEC';
      PINUSE='UNSPEC';
  end_pin;
  body
      PART_NAME='RES';
      PHYS_DES_PREFIX='R';
      ENVCOMP='YES;YES;YES;UNK;OK;VLD';
      PART_NUMBER='G21796-013';
      JEDEC_TYPE='SMR0402A';
      ALT_SYMBOLS='(SMX0402,SMX0402A,SMX0402B)';
      VALUE='4.99K';
      TOL='1%';
      WATTAGE='1/16W';
      CLASS='DISCRETE';
      DESCRIPTION='RES_D,0402,4.99KOHM,1.00%,1/16W';
      HEIGHT='0.017 IN';
      COMPONENT_TYPE='CHIP0402';
      LEAD_LENGTH='';
      LPID='1141';
      SPEED_URL='http://speed.intel.com:8081/speed/module/pdm/item/pdm_item_deta~
il_direct.asp?item_cde=G21796-013&item_rev=01&url_param=unused';
      STATUS='UNQUAL';
      RPL='NO';
      AML='4';
      BUS_UNIT='GMPO_BD_EXMPFREE';
      DAYS='???';
      PARENT_PART_TYPE='RES';
      PARENT_PPT='RES';
      PARENT_PPT_PART='RES_0402-4.99K,1%,1/16W,CHIP,G21796-013';
  end_body;
end_primitive;
primitive 'RES_0402-40.2K,1%,1/16W,CHIP,GA';
  pin
    'A':
      PIN_GROUP='1';
      PIN_NUMBER='(1)';
      PIN_TYPE='UNSPEC';
      PINUSE='UNSPEC';
    'B':
      PIN_GROUP='1';
      PIN_NUMBER='(2)';
      PIN_TYPE='UNSPEC';
      PINUSE='UNSPEC';
  end_pin;
  body
      PART_NAME='RES';
      PHYS_DES_PREFIX='R';
      ENVCOMP='YES;YES;YES;UNK;OK;VLD';
      PART_NUMBER='G21796-133';
      JEDEC_TYPE='SMR0402A';
      ALT_SYMBOLS='(SMX0402,SMX0402A,SMX0402B)';
      VALUE='40.2K';
      TOL='1%';
      WATTAGE='1/16W';
      CLASS='DISCRETE';
      DESCRIPTION='RES_D,0402,40.2KOHM,1.00%,1/16W';
      HEIGHT='0.017 IN';
      COMPONENT_TYPE='CHIP0402';
      LEAD_LENGTH='';
      LPID='1141';
      SPEED_URL='http://speed.intel.com:8081/speed/module/pdm/item/pdm_item_deta~
il_direct.asp?item_cde=G21796-133&item_rev=01&url_param=unused';
      STATUS='DESIGN';
      RPL='NO';
      AML='3';
      BUS_UNIT='GMPO_BD_EXMPFREE';
      DAYS='???';
      PARENT_PART_TYPE='RES';
      PARENT_PPT='RES';
      PARENT_PPT_PART='RES_0402-40.2K,1%,1/16W,CHIP,G21796-133';
  end_body;
end_primitive;
primitive 'RES_0402-42.2,1.0%,1/16W,EMPTYA';
  pin
    'A':
      PIN_GROUP='1';
      PIN_NUMBER='(1)';
      PIN_TYPE='UNSPEC';
      PINUSE='UNSPEC';
    'B':
      PIN_GROUP='1';
      PIN_NUMBER='(2)';
      PIN_TYPE='UNSPEC';
      PINUSE='UNSPEC';
  end_pin;
  body
      PART_NAME='RES';
      PHYS_DES_PREFIX='R';
      ENVCOMP='YES;YES;YES;UNK;OK;VLD';
      PART_NUMBER='G21796-259';
      JEDEC_TYPE='SMR0402A';
      ALT_SYMBOLS='(SMX0402,SMX0402A,SMX0402B)';
      VALUE='NA';
      TOL='1.0%';
      WATTAGE='1/16W';
      CLASS='DISCRETE';
      DESCRIPTION='RES_D,0402,42.20OHM,1.00%,1/16W,';
      HEIGHT='0.016 IN';
      COMPONENT_TYPE='CHIP0402';
      LEAD_LENGTH='';
      LPID='1141';
      SPEED_URL='http://speed.intel.com:8081/speed/module/pdm/item/pdm_item_deta~
il_direct.asp?item_cde=G21796-259&item_rev=01&url_param=unused';
      STATUS='DESIGN';
      RPL='NO';
      AML='3';
      BUS_UNIT='GMPO_BD_EXMPFREE';
      DAYS='???';
      PARENT_PART_TYPE='RES';
      PARENT_PPT='RES';
      PARENT_PPT_PART='RES_0402-42.2,1.0%,1/16W,EMPTY,G21796-259';
  end_body;
end_primitive;
primitive 'RES_0402-470.0,5%,1/16W,CHIP,GA';
  pin
    'A':
      PIN_GROUP='1';
      PIN_NUMBER='(1)';
      PIN_TYPE='UNSPEC';
      PINUSE='UNSPEC';
    'B':
      PIN_GROUP='1';
      PIN_NUMBER='(2)';
      PIN_TYPE='UNSPEC';
      PINUSE='UNSPEC';
  end_pin;
  body
      PART_NAME='RES';
      PHYS_DES_PREFIX='R';
      ENVCOMP='YES;YES;YES;UNK;OK;VLD';
      PART_NUMBER='G21497-024';
      JEDEC_TYPE='SMR0402A';
      ALT_SYMBOLS='(SMX0402,SMX0402A,SMX0402B)';
      VALUE='470.0';
      TOL='5%';
      WATTAGE='1/16W';
      CLASS='DISCRETE';
      DESCRIPTION='RES_D,0402,470.0OHM,5.00%,1/16W';
      HEIGHT='0.017 IN';
      COMPONENT_TYPE='CHIP0402';
      LEAD_LENGTH='';
      LPID='1141';
      SPEED_URL='http://speed.intel.com:8081/speed/module/pdm/item/pdm_item_deta~
il_direct.asp?item_cde=G21497-024&item_rev=01&url_param=unused';
      STATUS='UNQUAL';
      RPL='NO';
      AML='3';
      BUS_UNIT='GMPO_BD_EXMPFREE';
      DAYS='???';
      PARENT_PART_TYPE='RES';
      PARENT_PPT='RES';
      PARENT_PPT_PART='RES_0402-470.0,5%,1/16W,CHIP,G21497-024';
  end_body;
end_primitive;
primitive 'RES_0402-475.0,1%,1/16W,CHIP,GA';
  pin
    'A':
      PIN_GROUP='1';
      PIN_NUMBER='(1)';
      PIN_TYPE='UNSPEC';
      PINUSE='UNSPEC';
    'B':
      PIN_GROUP='1';
      PIN_NUMBER='(2)';
      PIN_TYPE='UNSPEC';
      PINUSE='UNSPEC';
  end_pin;
  body
      PART_NAME='RES';
      PHYS_DES_PREFIX='R';
      ENVCOMP='YES;YES;YES;UNK;OK;VLD';
      PART_NUMBER='G21796-077';
      JEDEC_TYPE='SMR0402A';
      ALT_SYMBOLS='(SMX0402,SMX0402A,SMX0402B)';
      VALUE='475.0';
      TOL='1%';
      WATTAGE='1/16W';
      CLASS='DISCRETE';
      DESCRIPTION='RES_D,0402,475.0OHM,1.00%,1/16W';
      HEIGHT='0.017 IN';
      COMPONENT_TYPE='CHIP0402';
      LEAD_LENGTH='';
      LPID='1141';
      SPEED_URL='http://speed.intel.com:8081/speed/module/pdm/item/pdm_item_deta~
il_direct.asp?item_cde=G21796-077&item_rev=01&url_param=unused';
      STATUS='UNQUAL';
      RPL='NO';
      AML='3';
      BUS_UNIT='GMPO_BD_EXMPFREE';
      DAYS='???';
      PARENT_PART_TYPE='RES';
      PARENT_PPT='RES';
      PARENT_PPT_PART='RES_0402-475.0,1%,1/16W,CHIP,G21796-077';
  end_body;
end_primitive;
primitive 'RES_0402-49.9,1%,1/16W,CHIP,G2A';
  pin
    'A':
      PIN_GROUP='1';
      PIN_NUMBER='(1)';
      PIN_TYPE='UNSPEC';
      PINUSE='UNSPEC';
    'B':
      PIN_GROUP='1';
      PIN_NUMBER='(2)';
      PIN_TYPE='UNSPEC';
      PINUSE='UNSPEC';
  end_pin;
  body
      PART_NAME='RES';
      PHYS_DES_PREFIX='R';
      ENVCOMP='YES;YES;YES;UNK;OK;VLD';
      PART_NUMBER='G21796-047';
      JEDEC_TYPE='SMR0402A';
      ALT_SYMBOLS='(SMX0402,SMX0402A,SMX0402B)';
      VALUE='49.9';
      TOL='1%';
      WATTAGE='1/16W';
      CLASS='DISCRETE';
      DESCRIPTION='RES_D,0402,49.9 OHM,1.00%,1/16W';
      HEIGHT='0.017 IN';
      COMPONENT_TYPE='CHIP0402';
      LEAD_LENGTH='';
      LPID='1141';
      SPEED_URL='http://speed.intel.com:8081/speed/module/pdm/item/pdm_item_deta~
il_direct.asp?item_cde=G21796-047&item_rev=01&url_param=unused';
      STATUS='UNQUAL';
      RPL='NO';
      AML='4';
      BUS_UNIT='GMPO_BD_EXMPFREE';
      DAYS='???';
      PARENT_PART_TYPE='RES';
      PARENT_PPT='RES';
      PARENT_PPT_PART='RES_0402-49.9,1%,1/16W,CHIP,G21796-047';
  end_body;
end_primitive;
primitive 'RES_0402-49.9,1%,1/16W,EMPTY,GA';
  pin
    'A':
      PIN_GROUP='1';
      PIN_NUMBER='(1)';
      PIN_TYPE='UNSPEC';
      PINUSE='UNSPEC';
    'B':
      PIN_GROUP='1';
      PIN_NUMBER='(2)';
      PIN_TYPE='UNSPEC';
      PINUSE='UNSPEC';
  end_pin;
  body
      PART_NAME='RES';
      PHYS_DES_PREFIX='R';
      ENVCOMP='YES;YES;YES;UNK;OK;VLD';
      PART_NUMBER='G21796-047';
      JEDEC_TYPE='SMR0402A';
      ALT_SYMBOLS='(SMX0402,SMX0402A,SMX0402B)';
      VALUE='NA';
      TOL='1%';
      WATTAGE='1/16W';
      CLASS='DISCRETE';
      DESCRIPTION='RES_D,0402,49.9 OHM,1.00%,1/16W';
      HEIGHT='0.017 IN';
      COMPONENT_TYPE='CHIP0402';
      LEAD_LENGTH='';
      LPID='1141';
      SPEED_URL='http://speed.intel.com:8081/speed/module/pdm/item/pdm_item_deta~
il_direct.asp?item_cde=G21796-047&item_rev=01&url_param=unused';
      STATUS='UNQUAL';
      RPL='NO';
      AML='4';
      BUS_UNIT='GMPO_BD_EXMPFREE';
      DAYS='???';
      PARENT_PART_TYPE='RES';
      PARENT_PPT='RES';
      PARENT_PPT_PART='RES_0402-49.9,1%,1/16W,EMPTY,G21796-047';
  end_body;
end_primitive;
primitive 'RES_0402-49.9K,1%,1/16W,CHIP,GA';
  pin
    'A':
      PIN_GROUP='1';
      PIN_NUMBER='(1)';
      PIN_TYPE='UNSPEC';
      PINUSE='UNSPEC';
    'B':
      PIN_GROUP='1';
      PIN_NUMBER='(2)';
      PIN_TYPE='UNSPEC';
      PINUSE='UNSPEC';
  end_pin;
  body
      PART_NAME='RES';
      PHYS_DES_PREFIX='R';
      ENVCOMP='YES;YES;YES;UNK;OK;VLD';
      PART_NUMBER='G21796-048';
      JEDEC_TYPE='SMR0402A';
      ALT_SYMBOLS='(SMX0402,SMX0402A,SMX0402B)';
      VALUE='49.9K';
      TOL='1%';
      WATTAGE='1/16W';
      CLASS='DISCRETE';
      DESCRIPTION='RES_D,0402,49.9KOHM,1.00%,1/16W';
      HEIGHT='0.017 IN';
      COMPONENT_TYPE='CHIP0402';
      LEAD_LENGTH='';
      LPID='1141';
      SPEED_URL='http://speed.intel.com:8081/speed/module/pdm/item/pdm_item_deta~
il_direct.asp?item_cde=G21796-048&item_rev=01&url_param=unused';
      STATUS='UNQUAL';
      RPL='NO';
      AML='4';
      BUS_UNIT='GMPO_BD_EXMPFREE';
      DAYS='???';
      PARENT_PART_TYPE='RES';
      PARENT_PPT='RES';
      PARENT_PPT_PART='RES_0402-49.9K,1%,1/16W,CHIP,G21796-048';
  end_body;
end_primitive;
primitive 'RES_0402-5.11K,1%,1/16W,CHIP,GA';
  pin
    'A':
      PIN_GROUP='1';
      PIN_NUMBER='(1)';
      PIN_TYPE='UNSPEC';
      PINUSE='UNSPEC';
    'B':
      PIN_GROUP='1';
      PIN_NUMBER='(2)';
      PIN_TYPE='UNSPEC';
      PINUSE='UNSPEC';
  end_pin;
  body
      PART_NAME='RES';
      PHYS_DES_PREFIX='R';
      ENVCOMP='YES;YES;YES;UNK;OK;VLD';
      PART_NUMBER='G21796-140';
      JEDEC_TYPE='SMR0402A';
      ALT_SYMBOLS='(SMX0402,SMX0402A,SMX0402B)';
      VALUE='5.11K';
      TOL='1%';
      WATTAGE='1/16W';
      CLASS='DISCRETE';
      DESCRIPTION='RES_D,0402,5.11KOHM,1.00%,1/16W';
      HEIGHT='0.017 IN';
      COMPONENT_TYPE='CHIP0402';
      LEAD_LENGTH='';
      LPID='1141';
      SPEED_URL='http://speed.intel.com:8081/speed/module/pdm/item/pdm_item_deta~
il_direct.asp?item_cde=G21796-140&item_rev=01&url_param=unused';
      STATUS='UNQUAL';
      RPL='NO';
      AML='3';
      BUS_UNIT='GMPO_BD_EXMPFREE';
      DAYS='???';
      PARENT_PART_TYPE='RES';
      PARENT_PPT='RES';
      PARENT_PPT_PART='RES_0402-5.11K,1%,1/16W,CHIP,G21796-140';
  end_body;
end_primitive;
primitive 'RES_0402-5.36K,1.0%,1/16W,CHIPA';
  pin
    'A':
      PIN_GROUP='1';
      PIN_NUMBER='(1)';
      PIN_TYPE='UNSPEC';
      PINUSE='UNSPEC';
    'B':
      PIN_GROUP='1';
      PIN_NUMBER='(2)';
      PIN_TYPE='UNSPEC';
      PINUSE='UNSPEC';
  end_pin;
  body
      PART_NAME='RES';
      PHYS_DES_PREFIX='R';
      ENVCOMP='YES;YES;YES;UNK;OK;VLD';
      PART_NUMBER='G21796-297';
      JEDEC_TYPE='SMR0402A';
      ALT_SYMBOLS='(SMX0402,SMX0402A,SMX0402B)';
      VALUE='5.36K';
      TOL='1.0%';
      WATTAGE='1/16W';
      CLASS='DISCRETE';
      DESCRIPTION='RES_D,0402,5.36KOHM,1.00%,1/16W,';
      HEIGHT='0.016 IN';
      COMPONENT_TYPE='CHIP0402';
      LEAD_LENGTH='';
      LPID='1141';
      SPEED_URL='http://speed.intel.com:8081/speed/module/pdm/item/pdm_item_deta~
il_direct.asp?item_cde=G21796-297&item_rev=01&url_param=unused';
      STATUS='DESIGN';
      RPL='NO';
      AML='3';
      BUS_UNIT='GMPO_BD_EXMPFREE';
      DAYS='???';
      PARENT_PART_TYPE='RES';
      PARENT_PPT='RES';
      PARENT_PPT_PART='RES_0402-5.36K,1.0%,1/16W,CHIP,G21796-297';
  end_body;
end_primitive;
primitive 'RES_0402-51,5.0%,1/16W,CHIP,G2A';
  pin
    'A':
      PIN_GROUP='1';
      PIN_NUMBER='(1)';
      PIN_TYPE='UNSPEC';
      PINUSE='UNSPEC';
    'B':
      PIN_GROUP='1';
      PIN_NUMBER='(2)';
      PIN_TYPE='UNSPEC';
      PINUSE='UNSPEC';
  end_pin;
  body
      PART_NAME='RES';
      PHYS_DES_PREFIX='R';
      ENVCOMP='YES;YES;YES;UNK;OK;VLD';
      PART_NUMBER='G21497-048';
      JEDEC_TYPE='SMR0402A';
      ALT_SYMBOLS='(SMX0402,SMX0402A,SMX0402B)';
      VALUE='51';
      TOL='5.0%';
      WATTAGE='1/16W';
      CLASS='DISCRETE';
      DESCRIPTION='RES_D,0402,51.00OHM,5.00%,1/16W,';
      HEIGHT='0.016 IN';
      COMPONENT_TYPE='CHIP0402';
      LEAD_LENGTH='';
      LPID='1141';
      SPEED_URL='http://speed.intel.com:8081/speed/module/pdm/item/pdm_item_deta~
il_direct.asp?item_cde=G21497-048&item_rev=01&url_param=unused';
      STATUS='DESIGN';
      RPL='NO';
      AML='2';
      BUS_UNIT='GMPO_BD_EXMPFREE';
      DAYS='???';
      PARENT_PART_TYPE='RES';
      PARENT_PPT='RES';
      PARENT_PPT_PART='RES_0402-51,5.0%,1/16W,CHIP,G21497-048';
  end_body;
end_primitive;
primitive 'RES_0402-51.1,1.0%,1/16W,CHIP,A';
  pin
    'A':
      PIN_GROUP='1';
      PIN_NUMBER='(1)';
      PIN_TYPE='UNSPEC';
      PINUSE='UNSPEC';
    'B':
      PIN_GROUP='1';
      PIN_NUMBER='(2)';
      PIN_TYPE='UNSPEC';
      PINUSE='UNSPEC';
  end_pin;
  body
      PART_NAME='RES';
      PHYS_DES_PREFIX='R';
      ENVCOMP='YES;YES;YES;UNK;OK;VLD';
      PART_NUMBER='G21796-208';
      JEDEC_TYPE='SMR0402A';
      ALT_SYMBOLS='(SMX0402,SMX0402A,SMX0402B)';
      VALUE='51.1';
      TOL='1.0%';
      WATTAGE='1/16W';
      CLASS='DISCRETE';
      DESCRIPTION='RES_D,0402,51.10OHM,1.00%,1/16W,';
      HEIGHT='0.016 IN';
      COMPONENT_TYPE='CHIP0402';
      LEAD_LENGTH='';
      LPID='1141';
      SPEED_URL='http://speed.intel.com:8081/speed/module/pdm/item/pdm_item_deta~
il_direct.asp?item_cde=G21796-208&item_rev=01&url_param=unused';
      STATUS='DESIGN';
      RPL='NO';
      AML='3';
      BUS_UNIT='GMPO_BD_EXMPFREE';
      DAYS='???';
      PARENT_PART_TYPE='RES';
      PARENT_PPT='RES';
      PARENT_PPT_PART='RES_0402-51.1,1.0%,1/16W,CHIP,G21796-208';
  end_body;
end_primitive;
primitive 'RES_0402-6.19K,1%,1/16W,CHIP,GA';
  pin
    'A':
      PIN_GROUP='1';
      PIN_NUMBER='(1)';
      PIN_TYPE='UNSPEC';
      PINUSE='UNSPEC';
    'B':
      PIN_GROUP='1';
      PIN_NUMBER='(2)';
      PIN_TYPE='UNSPEC';
      PINUSE='UNSPEC';
  end_pin;
  body
      PART_NAME='RES';
      PHYS_DES_PREFIX='R';
      ENVCOMP='YES;YES;YES;UNK;OK;VLD';
      PART_NUMBER='G21796-161';
      JEDEC_TYPE='SMR0402A';
      ALT_SYMBOLS='(SMX0402,SMX0402A,SMX0402B)';
      VALUE='6.19K';
      TOL='1%';
      WATTAGE='1/16W';
      CLASS='DISCRETE';
      DESCRIPTION='RES_D,0402,6.19KOHM,1.00%,1/16W';
      HEIGHT='0.017 IN';
      COMPONENT_TYPE='CHIP0402';
      LEAD_LENGTH='';
      LPID='1141';
      SPEED_URL='http://speed.intel.com:8081/speed/module/pdm/item/pdm_item_deta~
il_direct.asp?item_cde=G21796-161&item_rev=01&url_param=unused';
      STATUS='UNQUAL';
      RPL='NO';
      AML='3';
      BUS_UNIT='GMPO_BD_EXMPFREE';
      DAYS='???';
      PARENT_PART_TYPE='RES';
      PARENT_PPT='RES';
      PARENT_PPT_PART='RES_0402-6.19K,1%,1/16W,CHIP,G21796-161';
  end_body;
end_primitive;
primitive 'RES_0402-6.34K,1%,1/16W,CHIP,GA';
  pin
    'A':
      PIN_GROUP='1';
      PIN_NUMBER='(1)';
      PIN_TYPE='UNSPEC';
      PINUSE='UNSPEC';
    'B':
      PIN_GROUP='1';
      PIN_NUMBER='(2)';
      PIN_TYPE='UNSPEC';
      PINUSE='UNSPEC';
  end_pin;
  body
      PART_NAME='RES';
      PHYS_DES_PREFIX='R';
      ENVCOMP='YES;YES;YES;UNK;OK;VLD';
      PART_NUMBER='G21796-146';
      JEDEC_TYPE='SMR0402A';
      ALT_SYMBOLS='(SMX0402,SMX0402A,SMX0402B)';
      VALUE='6.34K';
      TOL='1%';
      WATTAGE='1/16W';
      CLASS='DISCRETE';
      DESCRIPTION='RES_D,0402,6.34KOHM,1.00%,1/16W';
      HEIGHT='0.017 IN';
      COMPONENT_TYPE='CHIP0402';
      LEAD_LENGTH='';
      LPID='1141';
      SPEED_URL='http://speed.intel.com:8081/speed/module/pdm/item/pdm_item_deta~
il_direct.asp?item_cde=G21796-146&item_rev=01&url_param=unused';
      STATUS='DESIGN';
      RPL='NO';
      AML='3';
      BUS_UNIT='GMPO_BD_EXMPFREE';
      DAYS='???';
      PARENT_PART_TYPE='RES';
      PARENT_PPT='RES';
      PARENT_PPT_PART='RES_0402-6.34K,1%,1/16W,CHIP,G21796-146';
  end_body;
end_primitive;
primitive 'RES_0402-63.4K,1.0%,1/16W,CHIPA';
  pin
    'A':
      PIN_GROUP='1';
      PIN_NUMBER='(1)';
      PIN_TYPE='UNSPEC';
      PINUSE='UNSPEC';
    'B':
      PIN_GROUP='1';
      PIN_NUMBER='(2)';
      PIN_TYPE='UNSPEC';
      PINUSE='UNSPEC';
  end_pin;
  body
      PART_NAME='RES';
      PHYS_DES_PREFIX='R';
      ENVCOMP='YES;YES;YES;UNK;OK;VLD';
      PART_NUMBER='G21796-327';
      JEDEC_TYPE='SMR0402A';
      ALT_SYMBOLS='(SMX0402,SMX0402A,SMX0402B)';
      VALUE='63.4K';
      TOL='1.0%';
      WATTAGE='1/16W';
      CLASS='DISCRETE';
      DESCRIPTION='RES_D,0402,63.40KOHM,1.00%,1/16W,';
      HEIGHT='0.016 IN';
      COMPONENT_TYPE='CHIP0402';
      LEAD_LENGTH='';
      LPID='1141';
      SPEED_URL='http://speed.intel.com:8081/speed/module/pdm/item/pdm_item_deta~
il_direct.asp?item_cde=G21796-327&item_rev=01&url_param=unused';
      STATUS='DESIGN';
      RPL='NO';
      AML='3';
      BUS_UNIT='GMPO_BD_EXMPFREE';
      DAYS='???';
      PARENT_PART_TYPE='RES';
      PARENT_PPT='RES';
      PARENT_PPT_PART='RES_0402-63.4K,1.0%,1/16W,CHIP,G21796-327';
  end_body;
end_primitive;
primitive 'RES_0402-64.9,1.0%,1/16W,CHIP,A';
  pin
    'A':
      PIN_GROUP='1';
      PIN_NUMBER='(1)';
      PIN_TYPE='UNSPEC';
      PINUSE='UNSPEC';
    'B':
      PIN_GROUP='1';
      PIN_NUMBER='(2)';
      PIN_TYPE='UNSPEC';
      PINUSE='UNSPEC';
  end_pin;
  body
      PART_NAME='RES';
      PHYS_DES_PREFIX='R';
      ENVCOMP='YES;YES;YES;UNK;OK;VLD';
      PART_NUMBER='G21796-298';
      JEDEC_TYPE='SMR0402A';
      ALT_SYMBOLS='(SMX0402,SMX0402A,SMX0402B)';
      VALUE='64.9';
      TOL='1.0%';
      WATTAGE='1/16W';
      CLASS='DISCRETE';
      DESCRIPTION='RES_D,0402,64.90OHM,1.00%,1/16W,';
      HEIGHT='0.016 IN';
      COMPONENT_TYPE='CHIP0402';
      LEAD_LENGTH='';
      LPID='1141';
      SPEED_URL='http://speed.intel.com:8081/speed/module/pdm/item/pdm_item_deta~
il_direct.asp?item_cde=G21796-298&item_rev=01&url_param=unused';
      STATUS='DESIGN';
      RPL='NO';
      AML='3';
      BUS_UNIT='GMPO_BD_EXMPFREE';
      DAYS='???';
      PARENT_PART_TYPE='RES';
      PARENT_PPT='RES';
      PARENT_PPT_PART='RES_0402-64.9,1.0%,1/16W,CHIP,G21796-298';
  end_body;
end_primitive;
primitive 'RES_0402-665,1.0%,1/16W,CHIP,GA';
  pin
    'A':
      PIN_GROUP='1';
      PIN_NUMBER='(1)';
      PIN_TYPE='UNSPEC';
      PINUSE='UNSPEC';
    'B':
      PIN_GROUP='1';
      PIN_NUMBER='(2)';
      PIN_TYPE='UNSPEC';
      PINUSE='UNSPEC';
  end_pin;
  body
      PART_NAME='RES';
      PHYS_DES_PREFIX='R';
      ENVCOMP='YES;YES;YES;UNK;OK;VLD';
      PART_NUMBER='G21796-235';
      JEDEC_TYPE='SMR0402A';
      ALT_SYMBOLS='(SMX0402,SMX0402A,SMX0402B)';
      VALUE='665';
      TOL='1.0%';
      WATTAGE='1/16W';
      CLASS='DISCRETE';
      DESCRIPTION='RES_D,0402,665.00OHM,1.00%,1/16W,';
      HEIGHT='0.016 IN';
      COMPONENT_TYPE='CHIP0402';
      LEAD_LENGTH='';
      LPID='1141';
      SPEED_URL='http://speed.intel.com:8081/speed/module/pdm/item/pdm_item_deta~
il_direct.asp?item_cde=G21796-235&item_rev=01&url_param=unused';
      STATUS='DESIGN';
      RPL='NO';
      AML='3';
      BUS_UNIT='GMPO_BD_EXMPFREE';
      DAYS='???';
      PARENT_PART_TYPE='RES';
      PARENT_PPT='RES';
      PARENT_PPT_PART='RES_0402-665,1.0%,1/16W,CHIP,G21796-235';
  end_body;
end_primitive;
primitive 'RES_0402-68.1K,1%,1/16W,EMPTY,A';
  pin
    'A':
      PIN_GROUP='1';
      PIN_NUMBER='(1)';
      PIN_TYPE='UNSPEC';
      PINUSE='UNSPEC';
    'B':
      PIN_GROUP='1';
      PIN_NUMBER='(2)';
      PIN_TYPE='UNSPEC';
      PINUSE='UNSPEC';
  end_pin;
  body
      PART_NAME='RES';
      PHYS_DES_PREFIX='R';
      ENVCOMP='YES;YES;YES;UNK;OK;VLD';
      PART_NUMBER='G21796-187';
      JEDEC_TYPE='SMR0402A';
      ALT_SYMBOLS='(SMX0402,SMX0402A,SMX0402B)';
      VALUE='NA';
      TOL='1%';
      WATTAGE='1/16W';
      CLASS='DISCRETE';
      DESCRIPTION='RES_D,0402,68.1KOHM,1.00%,1/16W';
      HEIGHT='0.017 IN';
      COMPONENT_TYPE='CHIP0402';
      LEAD_LENGTH='';
      LPID='1141';
      SPEED_URL='http://speed.intel.com:8081/speed/module/pdm/item/pdm_item_deta~
il_direct.asp?item_cde=G21796-187&item_rev=01&url_param=unused';
      STATUS='DESIGN';
      RPL='NO';
      AML='3';
      BUS_UNIT='GMPO_BD_EXMPFREE';
      DAYS='???';
      PARENT_PART_TYPE='RES';
      PARENT_PPT='RES';
      PARENT_PPT_PART='RES_0402-68.1K,1%,1/16W,EMPTY,G21796-187';
  end_body;
end_primitive;
primitive 'RES_0402-69.8K,1%,1/16W,CHIP,GA';
  pin
    'A':
      PIN_GROUP='1';
      PIN_NUMBER='(1)';
      PIN_TYPE='UNSPEC';
      PINUSE='UNSPEC';
    'B':
      PIN_GROUP='1';
      PIN_NUMBER='(2)';
      PIN_TYPE='UNSPEC';
      PINUSE='UNSPEC';
  end_pin;
  body
      PART_NAME='RES';
      PHYS_DES_PREFIX='R';
      ENVCOMP='YES;YES;YES;UNK;OK;VLD';
      PART_NUMBER='G21796-007';
      JEDEC_TYPE='SMR0402A';
      ALT_SYMBOLS='(SMX0402,SMX0402A,SMX0402B)';
      VALUE='69.8K';
      TOL='1%';
      WATTAGE='1/16W';
      CLASS='DISCRETE';
      DESCRIPTION='RES_D,0402,69.8KOHM,1.00%,1/16W';
      HEIGHT='0.017 IN';
      COMPONENT_TYPE='CHIP0402';
      LEAD_LENGTH='';
      LPID='1141';
      SPEED_URL='http://speed.intel.com:8081/speed/module/pdm/item/pdm_item_deta~
il_direct.asp?item_cde=G21796-007&item_rev=01&url_param=unused';
      STATUS='DESIGN';
      RPL='NO';
      AML='3';
      BUS_UNIT='GMPO_BD_EXMPFREE';
      DAYS='???';
      PARENT_PART_TYPE='RES';
      PARENT_PPT='RES';
      PARENT_PPT_PART='RES_0402-69.8K,1%,1/16W,CHIP,G21796-007';
  end_body;
end_primitive;
primitive 'RES_0402-7.5K,1%,1/16W,CHIP,G2A';
  pin
    'A':
      PIN_GROUP='1';
      PIN_NUMBER='(1)';
      PIN_TYPE='UNSPEC';
      PINUSE='UNSPEC';
    'B':
      PIN_GROUP='1';
      PIN_NUMBER='(2)';
      PIN_TYPE='UNSPEC';
      PINUSE='UNSPEC';
  end_pin;
  body
      PART_NAME='RES';
      PHYS_DES_PREFIX='R';
      ENVCOMP='YES;YES;YES;UNK;OK;VLD';
      PART_NUMBER='G21796-177';
      JEDEC_TYPE='SMR0402A';
      ALT_SYMBOLS='(SMX0402,SMX0402A,SMX0402B)';
      VALUE='7.5K';
      TOL='1%';
      WATTAGE='1/16W';
      CLASS='DISCRETE';
      DESCRIPTION='RES_D,0402,7.5KOHM,1.00%,1/16W';
      HEIGHT='0.017 IN';
      COMPONENT_TYPE='CHIP0402';
      LEAD_LENGTH='';
      LPID='1141';
      SPEED_URL='http://speed.intel.com:8081/speed/module/pdm/item/pdm_item_deta~
il_direct.asp?item_cde=G21796-177&item_rev=01&url_param=unused';
      STATUS='UNQUAL';
      RPL='NO';
      AML='3';
      BUS_UNIT='GMPO_BD_EXMPFREE';
      DAYS='???';
      PARENT_PART_TYPE='RES';
      PARENT_PPT='RES';
      PARENT_PPT_PART='RES_0402-7.5K,1%,1/16W,CHIP,G21796-177';
  end_body;
end_primitive;
primitive 'RES_0402-7.87K,1.0%,1/16W,CHIPA';
  pin
    'A':
      PIN_GROUP='1';
      PIN_NUMBER='(1)';
      PIN_TYPE='UNSPEC';
      PINUSE='UNSPEC';
    'B':
      PIN_GROUP='1';
      PIN_NUMBER='(2)';
      PIN_TYPE='UNSPEC';
      PINUSE='UNSPEC';
  end_pin;
  body
      PART_NAME='RES';
      PHYS_DES_PREFIX='R';
      ENVCOMP='YES;YES;YES;UNK;OK;VLD';
      PART_NUMBER='G21796-242';
      JEDEC_TYPE='SMR0402A';
      ALT_SYMBOLS='(SMX0402,SMX0402A,SMX0402B)';
      VALUE='7.87K';
      TOL='1.0%';
      WATTAGE='1/16W';
      CLASS='DISCRETE';
      DESCRIPTION='RES_D,0402,7.87KOHM,1.00%,1/16W,';
      HEIGHT='0.016 IN';
      COMPONENT_TYPE='CHIP0402';
      LEAD_LENGTH='';
      LPID='1141';
      SPEED_URL='http://speed.intel.com:8081/speed/module/pdm/item/pdm_item_deta~
il_direct.asp?item_cde=G21796-242&item_rev=01&url_param=unused';
      STATUS='DESIGN';
      RPL='NO';
      AML='3';
      BUS_UNIT='GMPO_BD_EXMPFREE';
      DAYS='???';
      PARENT_PART_TYPE='RES';
      PARENT_PPT='RES';
      PARENT_PPT_PART='RES_0402-7.87K,1.0%,1/16W,CHIP,G21796-242';
  end_body;
end_primitive;
primitive 'RES_0402-75,1.0%,1/16W,CHIP,G2A';
  pin
    'A':
      PIN_GROUP='1';
      PIN_NUMBER='(1)';
      PIN_TYPE='UNSPEC';
      PINUSE='UNSPEC';
    'B':
      PIN_GROUP='1';
      PIN_NUMBER='(2)';
      PIN_TYPE='UNSPEC';
      PINUSE='UNSPEC';
  end_pin;
  body
      PART_NAME='RES';
      PHYS_DES_PREFIX='R';
      ENVCOMP='YES;YES;YES;UNK;OK;VLD';
      PART_NUMBER='G21796-267';
      JEDEC_TYPE='SMR0402A';
      ALT_SYMBOLS='(SMX0402,SMX0402A,SMX0402B)';
      VALUE='75';
      TOL='1.0%';
      WATTAGE='1/16W';
      CLASS='DISCRETE';
      DESCRIPTION='RES_D,0402,75.00OHM,1.00%,1/16W,';
      HEIGHT='0.016 IN';
      COMPONENT_TYPE='CHIP0402';
      LEAD_LENGTH='';
      LPID='1141';
      SPEED_URL='http://speed.intel.com:8081/speed/module/pdm/item/pdm_item_deta~
il_direct.asp?item_cde=G21796-267&item_rev=01&url_param=unused';
      STATUS='DESIGN';
      RPL='NO';
      AML='3';
      BUS_UNIT='GMPO_BD_EXMPFREE';
      DAYS='???';
      PARENT_PART_TYPE='RES';
      PARENT_PPT='RES';
      PARENT_PPT_PART='RES_0402-75,1.0%,1/16W,CHIP,G21796-267';
  end_body;
end_primitive;
primitive 'RES_0402-75K,1%,1/16W,CHIP,G21A';
  pin
    'A':
      PIN_GROUP='1';
      PIN_NUMBER='(1)';
      PIN_TYPE='UNSPEC';
      PINUSE='UNSPEC';
    'B':
      PIN_GROUP='1';
      PIN_NUMBER='(2)';
      PIN_TYPE='UNSPEC';
      PINUSE='UNSPEC';
  end_pin;
  body
      PART_NAME='RES';
      PHYS_DES_PREFIX='R';
      ENVCOMP='';
      PART_NUMBER='G21796-224';
      JEDEC_TYPE='SMR0402A';
      ALT_SYMBOLS='(SMX0402,SMX0402A,SMX0402B)';
      VALUE='75K';
      TOL='1%';
      WATTAGE='1/16W';
      CLASS='DISCRETE';
      DESCRIPTION='RES_D,0402,75.00kOHM,1.00%,1/16W,';
      HEIGHT='0.016 IN';
      COMPONENT_TYPE='CHIP0402';
      LEAD_LENGTH='';
      LPID='1141';
      SPEED_URL='http://speed.intel.com:8081/speed/module/pdm/item/pdm_item_deta~
il_direct.asp?item_cde=G21796-224&item_rev=01&url_param=unused';
      STATUS='';
      RPL='';
      AML='';
      BUS_UNIT='';
      DAYS='';
      PARENT_PART_TYPE='RES';
      PARENT_PPT='RES';
      PARENT_PPT_PART='RES_0402-75K,1%,1/16W,CHIP,G21796-224';
  end_body;
end_primitive;
primitive 'RES_0402-8.06K,1%,1/16W,CHIP,GA';
  pin
    'A':
      PIN_GROUP='1';
      PIN_NUMBER='(1)';
      PIN_TYPE='UNSPEC';
      PINUSE='UNSPEC';
    'B':
      PIN_GROUP='1';
      PIN_NUMBER='(2)';
      PIN_TYPE='UNSPEC';
      PINUSE='UNSPEC';
  end_pin;
  body
      PART_NAME='RES';
      PHYS_DES_PREFIX='R';
      ENVCOMP='YES;YES;YES;UNK;OK;VLD';
      PART_NUMBER='G21796-078';
      JEDEC_TYPE='SMR0402A';
      ALT_SYMBOLS='(SMX0402,SMX0402A,SMX0402B)';
      VALUE='8.06K';
      TOL='1%';
      WATTAGE='1/16W';
      CLASS='DISCRETE';
      DESCRIPTION='RES_D,0402,8.06KOHM,1.00%,1/16W';
      HEIGHT='0.017 IN';
      COMPONENT_TYPE='CHIP0402';
      LEAD_LENGTH='';
      LPID='1141';
      SPEED_URL='http://speed.intel.com:8081/speed/module/pdm/item/pdm_item_deta~
il_direct.asp?item_cde=G21796-078&item_rev=01&url_param=unused';
      STATUS='UNQUAL';
      RPL='NO';
      AML='3';
      BUS_UNIT='GMPO_BD_EXMPFREE';
      DAYS='???';
      PARENT_PART_TYPE='RES';
      PARENT_PPT='RES';
      PARENT_PPT_PART='RES_0402-8.06K,1%,1/16W,CHIP,G21796-078';
  end_body;
end_primitive;
primitive 'RES_0402-8.2K,1%,1/16W,CHIP,G2A';
  pin
    'A':
      PIN_GROUP='1';
      PIN_NUMBER='(1)';
      PIN_TYPE='UNSPEC';
      PINUSE='UNSPEC';
    'B':
      PIN_GROUP='1';
      PIN_NUMBER='(2)';
      PIN_TYPE='UNSPEC';
      PINUSE='UNSPEC';
  end_pin;
  body
      PART_NAME='RES';
      PHYS_DES_PREFIX='R';
      ENVCOMP='';
      PART_NUMBER='G21796-345';
      JEDEC_TYPE='SMR0402A';
      ALT_SYMBOLS='(SMX0402,SMX0402A,SMX0402B)';
      VALUE='8.2K';
      TOL='1%';
      WATTAGE='1/16W';
      CLASS='DISCRETE';
      DESCRIPTION='RES_D,0402,8.20kOHM,1.00%,1/16W,';
      HEIGHT='0.016 IN';
      COMPONENT_TYPE='CHIP0402';
      LEAD_LENGTH='';
      LPID='1141';
      SPEED_URL='http://speed.intel.com:8081/speed/module/pdm/item/pdm_item_deta~
il_direct.asp?item_cde=G21796-345&item_rev=01&url_param=unused';
      STATUS='';
      RPL='';
      AML='';
      BUS_UNIT='';
      DAYS='';
      PARENT_PART_TYPE='RES';
      PARENT_PPT='RES';
      PARENT_PPT_PART='RES_0402-8.2K,1%,1/16W,CHIP,G21796-345';
  end_body;
end_primitive;
primitive 'RES_0402-8.2K,1%,1/16W,EMPTY,GA';
  pin
    'A':
      PIN_GROUP='1';
      PIN_NUMBER='(1)';
      PIN_TYPE='UNSPEC';
      PINUSE='UNSPEC';
    'B':
      PIN_GROUP='1';
      PIN_NUMBER='(2)';
      PIN_TYPE='UNSPEC';
      PINUSE='UNSPEC';
  end_pin;
  body
      PART_NAME='RES';
      PHYS_DES_PREFIX='R';
      ENVCOMP='';
      PART_NUMBER='G21796-345';
      JEDEC_TYPE='SMR0402A';
      ALT_SYMBOLS='(SMX0402,SMX0402A,SMX0402B)';
      VALUE='NA';
      TOL='1%';
      WATTAGE='1/16W';
      CLASS='DISCRETE';
      DESCRIPTION='RES_D,0402,8.20kOHM,1.00%,1/16W,';
      HEIGHT='0.016 IN';
      COMPONENT_TYPE='CHIP0402';
      LEAD_LENGTH='';
      LPID='1141';
      SPEED_URL='http://speed.intel.com:8081/speed/module/pdm/item/pdm_item_deta~
il_direct.asp?item_cde=G21796-345&item_rev=01&url_param=unused';
      STATUS='';
      RPL='';
      AML='';
      BUS_UNIT='';
      DAYS='';
      PARENT_PART_TYPE='RES';
      PARENT_PPT='RES';
      PARENT_PPT_PART='RES_0402-8.2K,1%,1/16W,EMPTY,G21796-345';
  end_body;
end_primitive;
primitive 'RES_0402-90.9,1%,1/16W,CHIP,G2A';
  pin
    'A':
      PIN_GROUP='1';
      PIN_NUMBER='(1)';
      PIN_TYPE='UNSPEC';
      PINUSE='UNSPEC';
    'B':
      PIN_GROUP='1';
      PIN_NUMBER='(2)';
      PIN_TYPE='UNSPEC';
      PINUSE='UNSPEC';
  end_pin;
  body
      PART_NAME='RES';
      PHYS_DES_PREFIX='R';
      ENVCOMP='';
      PART_NUMBER='G21796-365';
      JEDEC_TYPE='SMR0402A';
      ALT_SYMBOLS='(SMX0402,SMX0402A)';
      VALUE='90.9';
      TOL='1%';
      WATTAGE='1/16W';
      CLASS='DISCRETE';
      DESCRIPTION='RES_D,0402,90.90OHM,1.00%,1/16W,';
      HEIGHT='0.016 IN';
      COMPONENT_TYPE='CHIP0402';
      LEAD_LENGTH='';
      LPID='1141';
      SPEED_URL='http://speed.intel.com:8081/speed/module/pdm/item/pdm_item_deta~
il_direct.asp?item_cde=G21796-365&item_rev=01&url_param=unused';
      STATUS='';
      RPL='';
      AML='';
      BUS_UNIT='';
      DAYS='';
      PARENT_PART_TYPE='RES';
      PARENT_PPT='RES';
      PARENT_PPT_PART='RES_0402-90.9,1%,1/16W,CHIP,G21796-365';
  end_body;
end_primitive;
primitive 'RES_0402-90.9K,1%,1/16W,CHIP,GA';
  pin
    'A':
      PIN_GROUP='1';
      PIN_NUMBER='(1)';
      PIN_TYPE='UNSPEC';
      PINUSE='UNSPEC';
    'B':
      PIN_GROUP='1';
      PIN_NUMBER='(2)';
      PIN_TYPE='UNSPEC';
      PINUSE='UNSPEC';
  end_pin;
  body
      PART_NAME='RES';
      PHYS_DES_PREFIX='R';
      ENVCOMP='YES;YES;YES;UNK;OK;VLD';
      PART_NUMBER='G21796-058';
      JEDEC_TYPE='SMR0402A';
      ALT_SYMBOLS='(SMX0402,SMX0402A,SMX0402B)';
      VALUE='90.9K';
      TOL='1%';
      WATTAGE='1/16W';
      CLASS='DISCRETE';
      DESCRIPTION='RES_D,0402,90.9KOHM,1.00%,1/16W';
      HEIGHT='0.017 IN';
      COMPONENT_TYPE='CHIP0402';
      LEAD_LENGTH='';
      LPID='1141';
      SPEED_URL='http://speed.intel.com:8081/speed/module/pdm/item/pdm_item_deta~
il_direct.asp?item_cde=G21796-058&item_rev=01&url_param=unused';
      STATUS='UNQUAL';
      RPL='NO';
      AML='4';
      BUS_UNIT='GMPO_BD_EXMPFREE';
      DAYS='???';
      PARENT_PART_TYPE='RES';
      PARENT_PPT='RES';
      PARENT_PPT_PART='RES_0402-90.9K,1%,1/16W,CHIP,G21796-058';
  end_body;
end_primitive;
primitive 'RES_0603-0,5.0%,1/10W,CHIP,G22A';
  pin
    'A':
      PIN_GROUP='1';
      PIN_NUMBER='(1)';
      PIN_TYPE='UNSPEC';
      PINUSE='UNSPEC';
    'B':
      PIN_GROUP='1';
      PIN_NUMBER='(2)';
      PIN_TYPE='UNSPEC';
      PINUSE='UNSPEC';
  end_pin;
  body
      PART_NAME='RES';
      PHYS_DES_PREFIX='R';
      ENVCOMP='YES;YES;YES;UNK;OK;VLD';
      PART_NUMBER='G22178-002';
      JEDEC_TYPE='SMR0603A';
      ALT_SYMBOLS='(SMX0603)';
      VALUE='0';
      TOL='5.0%';
      WATTAGE='1/10W';
      CLASS='DISCRETE';
      DESCRIPTION='RES_D,0603,0.00OHM,5.00%,1/10W,';
      HEIGHT='0.024 IN';
      COMPONENT_TYPE='CHIP0603';
      LEAD_LENGTH='';
      LPID='247';
      SPEED_URL='http://speed.intel.com:8081/speed/module/pdm/item/pdm_item_deta~
il_direct.asp?item_cde=G22178-002&item_rev=01&url_param=unused';
      STATUS='UNQUAL';
      RPL='NO';
      AML='3';
      BUS_UNIT='GMPO_BD_EXMPFREE';
      DAYS='???';
      PARENT_PART_TYPE='RES';
      PARENT_PPT='RES';
      PARENT_PPT_PART='RES_0603-0,5.0%,1/10W,CHIP,G22178-002';
  end_body;
end_primitive;
primitive 'RES_0603-0,5.0%,1/10W,EMPTY,G2A';
  pin
    'A':
      PIN_GROUP='1';
      PIN_NUMBER='(1)';
      PIN_TYPE='UNSPEC';
      PINUSE='UNSPEC';
    'B':
      PIN_GROUP='1';
      PIN_NUMBER='(2)';
      PIN_TYPE='UNSPEC';
      PINUSE='UNSPEC';
  end_pin;
  body
      PART_NAME='RES';
      PHYS_DES_PREFIX='R';
      ENVCOMP='YES;YES;YES;UNK;OK;VLD';
      PART_NUMBER='G22178-002';
      JEDEC_TYPE='SMR0603A';
      ALT_SYMBOLS='(SMX0603)';
      VALUE='NA';
      TOL='5.0%';
      WATTAGE='1/10W';
      CLASS='DISCRETE';
      DESCRIPTION='RES_D,0603,0.00OHM,5.00%,1/10W,';
      HEIGHT='0.024 IN';
      COMPONENT_TYPE='CHIP0603';
      LEAD_LENGTH='';
      LPID='247';
      SPEED_URL='http://speed.intel.com:8081/speed/module/pdm/item/pdm_item_deta~
il_direct.asp?item_cde=G22178-002&item_rev=01&url_param=unused';
      STATUS='UNQUAL';
      RPL='NO';
      AML='3';
      BUS_UNIT='GMPO_BD_EXMPFREE';
      DAYS='???';
      PARENT_PART_TYPE='RES';
      PARENT_PPT='RES';
      PARENT_PPT_PART='RES_0603-0,5.0%,1/10W,EMPTY,G22178-002';
  end_body;
end_primitive;
primitive 'RES_0603-10.0,1%,1/10W,CHIP,G2A';
  pin
    'A':
      PIN_GROUP='1';
      PIN_NUMBER='(1)';
      PIN_TYPE='UNSPEC';
      PINUSE='UNSPEC';
    'B':
      PIN_GROUP='1';
      PIN_NUMBER='(2)';
      PIN_TYPE='UNSPEC';
      PINUSE='UNSPEC';
  end_pin;
  body
      PART_NAME='RES';
      PHYS_DES_PREFIX='R';
      ENVCOMP='YES;YES;YES;UNK;OK;VLD';
      PART_NUMBER='G22026-041';
      JEDEC_TYPE='SMR0603A';
      ALT_SYMBOLS='(SMX0603)';
      VALUE='10.0';
      TOL='1%';
      WATTAGE='1/10W';
      CLASS='DISCRETE';
      DESCRIPTION='RES_D,0603,10.00OHM,1.00%,1/10W';
      HEIGHT='0.024 IN';
      COMPONENT_TYPE='CHIP0603';
      LEAD_LENGTH='';
      LPID='247';
      SPEED_URL='http://speed.intel.com:8081/speed/module/pdm/item/pdm_item_deta~
il_direct.asp?item_cde=G22026-041&item_rev=01&url_param=unused';
      STATUS='UNQUAL';
      RPL='NO';
      AML='3';
      BUS_UNIT='GMPO_BD_EXMPFREE';
      DAYS='???';
      PARENT_PART_TYPE='RES';
      PARENT_PPT='RES';
      PARENT_PPT_PART='RES_0603-10.0,1%,1/10W,CHIP,G22026-041';
  end_body;
end_primitive;
primitive 'RES_0603-100.0,1%,1/10W,CHIP,GA';
  pin
    'A':
      PIN_GROUP='1';
      PIN_NUMBER='(1)';
      PIN_TYPE='UNSPEC';
      PINUSE='UNSPEC';
    'B':
      PIN_GROUP='1';
      PIN_NUMBER='(2)';
      PIN_TYPE='UNSPEC';
      PINUSE='UNSPEC';
  end_pin;
  body
      PART_NAME='RES';
      PHYS_DES_PREFIX='R';
      ENVCOMP='YES;YES;YES;UNK;OK;VLD';
      PART_NUMBER='G22026-038';
      JEDEC_TYPE='SMR0603A';
      ALT_SYMBOLS='(SMX0603)';
      VALUE='100.0';
      TOL='1%';
      WATTAGE='1/10W';
      CLASS='DISCRETE';
      DESCRIPTION='RES_D,0603,100.00OHM,1.00%,1/10W';
      HEIGHT='0.024 IN';
      COMPONENT_TYPE='CHIP0603';
      LEAD_LENGTH='';
      LPID='247';
      SPEED_URL='http://speed.intel.com:8081/speed/module/pdm/item/pdm_item_deta~
il_direct.asp?item_cde=G22026-038&item_rev=01&url_param=unused';
      STATUS='DESIGN';
      RPL='NO';
      AML='4';
      BUS_UNIT='GMPO_BD_EXMPFREE';
      DAYS='???';
      PARENT_PART_TYPE='RES';
      PARENT_PPT='RES';
      PARENT_PPT_PART='RES_0603-100.0,1%,1/10W,CHIP,G22026-038';
  end_body;
end_primitive;
primitive 'RES_0603-100.0K,1%,1/10W,CHIP,A';
  pin
    'A':
      PIN_GROUP='1';
      PIN_NUMBER='(1)';
      PIN_TYPE='UNSPEC';
      PINUSE='UNSPEC';
    'B':
      PIN_GROUP='1';
      PIN_NUMBER='(2)';
      PIN_TYPE='UNSPEC';
      PINUSE='UNSPEC';
  end_pin;
  body
      PART_NAME='RES';
      PHYS_DES_PREFIX='R';
      ENVCOMP='YES;YES;YES;UNK;OK;VLD';
      PART_NUMBER='G22026-050';
      JEDEC_TYPE='SMR0603A';
      ALT_SYMBOLS='(SMX0603)';
      VALUE='100.0K';
      TOL='1%';
      WATTAGE='1/10W';
      CLASS='DISCRETE';
      DESCRIPTION='RES_D,0603,100.00KOHM,1.00%,1/10W';
      HEIGHT='0.024 IN';
      COMPONENT_TYPE='CHIP0603';
      LEAD_LENGTH='';
      LPID='247';
      SPEED_URL='http://speed.intel.com:8081/speed/module/pdm/item/pdm_item_deta~
il_direct.asp?item_cde=G22026-050&item_rev=01&url_param=unused';
      STATUS='DESIGN';
      RPL='NO';
      AML='3';
      BUS_UNIT='GMPO_BD_EXMPFREE';
      DAYS='???';
      PARENT_PART_TYPE='RES';
      PARENT_PPT='RES';
      PARENT_PPT_PART='RES_0603-100.0K,1%,1/10W,CHIP,G22026-050';
  end_body;
end_primitive;
primitive 'RES_0603-10M,1.0%,1/10W,CHIP,GA';
  pin
    'A':
      PIN_GROUP='1';
      PIN_NUMBER='(1)';
      PIN_TYPE='UNSPEC';
      PINUSE='UNSPEC';
    'B':
      PIN_GROUP='1';
      PIN_NUMBER='(2)';
      PIN_TYPE='UNSPEC';
      PINUSE='UNSPEC';
  end_pin;
  body
      PART_NAME='RES';
      PHYS_DES_PREFIX='R';
      ENVCOMP='YES;YES;YES;UNK;OK;VLD';
      PART_NUMBER='G22026-112';
      JEDEC_TYPE='SMR0603A';
      ALT_SYMBOLS='(SMX0603)';
      VALUE='10M';
      TOL='1.0%';
      WATTAGE='1/10W';
      CLASS='DISCRETE';
      DESCRIPTION='RES_D,0603,10.00MOHM,1.00%,1/10W,';
      HEIGHT='0.024 IN';
      COMPONENT_TYPE='CHIP0603';
      LEAD_LENGTH='';
      LPID='247';
      SPEED_URL='http://speed.intel.com:8081/speed/module/pdm/item/pdm_item_deta~
il_direct.asp?item_cde=G22026-112&item_rev=01&url_param=unused';
      STATUS='DESIGN';
      RPL='NO';
      AML='2';
      BUS_UNIT='GMPO_BD_EXMPFREE';
      DAYS='???';
      PARENT_PART_TYPE='RES';
      PARENT_PPT='RES';
      PARENT_PPT_PART='RES_0603-10M,1.0%,1/10W,CHIP,G22026-112';
  end_body;
end_primitive;
primitive 'RES_0603-120.0,1%,1/10W,CHIP,GA';
  pin
    'A':
      PIN_GROUP='1';
      PIN_NUMBER='(1)';
      PIN_TYPE='UNSPEC';
      PINUSE='UNSPEC';
    'B':
      PIN_GROUP='1';
      PIN_NUMBER='(2)';
      PIN_TYPE='UNSPEC';
      PINUSE='UNSPEC';
  end_pin;
  body
      PART_NAME='RES';
      PHYS_DES_PREFIX='R';
      ENVCOMP='YES;YES;YES;UNK;OK;VLD';
      PART_NUMBER='G22026-003';
      JEDEC_TYPE='SMR0603A';
      ALT_SYMBOLS='(SMX0603)';
      VALUE='120.0';
      TOL='1%';
      WATTAGE='1/10W';
      CLASS='DISCRETE';
      DESCRIPTION='RES_D,0603,120.0OHM,1.00%,1/10W';
      HEIGHT='0.024 IN';
      COMPONENT_TYPE='CHIP0603';
      LEAD_LENGTH='';
      LPID='247';
      SPEED_URL='http://speed.intel.com:8081/speed/module/pdm/item/pdm_item_deta~
il_direct.asp?item_cde=G22026-003&item_rev=01&url_param=unused';
      STATUS='DESIGN';
      RPL='NO';
      AML='3';
      BUS_UNIT='GMPO_BD_EXMPFREE';
      DAYS='???';
      PARENT_PART_TYPE='RES';
      PARENT_PPT='RES';
      PARENT_PPT_PART='RES_0603-120.0,1%,1/10W,CHIP,G22026-003';
  end_body;
end_primitive;
primitive 'RES_0603-2.2,1.0%,1/10W,CHIP,GA';
  pin
    'A':
      PIN_GROUP='1';
      PIN_NUMBER='(1)';
      PIN_TYPE='UNSPEC';
      PINUSE='UNSPEC';
    'B':
      PIN_GROUP='1';
      PIN_NUMBER='(2)';
      PIN_TYPE='UNSPEC';
      PINUSE='UNSPEC';
  end_pin;
  body
      PART_NAME='RES';
      PHYS_DES_PREFIX='R';
      ENVCOMP='UNK;UNK;UNK;UNK;OK;CIP';
      PART_NUMBER='G22026-127';
      JEDEC_TYPE='SMR0603A';
      ALT_SYMBOLS='(SMX0603)';
      VALUE='2.2';
      TOL='1.0%';
      WATTAGE='1/10W';
      CLASS='DISCRETE';
      DESCRIPTION='RES_D,0603,2.20OHM,1.00%,1/10W,';
      HEIGHT='0.024 IN';
      COMPONENT_TYPE='CHIP0603';
      LEAD_LENGTH='';
      LPID='247';
      SPEED_URL='http://speed.intel.com:8081/speed/module/pdm/item/pdm_item_deta~
il_direct.asp?item_cde=G22026-127&item_rev=01&url_param=unused';
      STATUS='DESIGN';
      RPL='NO';
      AML='2';
      BUS_UNIT='GMPO_BD_EXMPFREE';
      DAYS='???';
      PARENT_PART_TYPE='RES';
      PARENT_PPT='RES';
      PARENT_PPT_PART='RES_0603-2.2,1.0%,1/10W,CHIP,G22026-127';
  end_body;
end_primitive;
primitive 'RES_0603-200K,0.1%,1/10W,CHIP,A';
  pin
    'A':
      PIN_GROUP='1';
      PIN_NUMBER='(1)';
      PIN_TYPE='UNSPEC';
      PINUSE='UNSPEC';
    'B':
      PIN_GROUP='1';
      PIN_NUMBER='(2)';
      PIN_TYPE='UNSPEC';
      PINUSE='UNSPEC';
  end_pin;
  body
      PART_NAME='RES';
      PHYS_DES_PREFIX='R';
      ENVCOMP='';
      PART_NUMBER='G22369-010';
      JEDEC_TYPE='SMR0603A';
      ALT_SYMBOLS='(SMX0603)';
      VALUE='200K';
      TOL='0.1%';
      WATTAGE='1/10W';
      CLASS='DISCRETE';
      DESCRIPTION='RES_D,0603,200.00kOHM,0.1%,1/10W,';
      HEIGHT='0.024 IN';
      COMPONENT_TYPE='CHIP0603';
      LEAD_LENGTH='';
      LPID='247';
      SPEED_URL='http://speed.intel.com:8081/speed/module/pdm/item/pdm_item_deta~
il_direct.asp?item_cde=G22369-010&item_rev=01&url_param=unused';
      STATUS='';
      RPL='';
      AML='';
      BUS_UNIT='';
      DAYS='';
      PARENT_PART_TYPE='RES';
      PARENT_PPT='RES';
      PARENT_PPT_PART='RES_0603-200K,0.1%,1/10W,CHIP,G22369-010';
  end_body;
end_primitive;
primitive 'RES_0603-475.0,1%,1/10W,CHIP,GA';
  pin
    'A':
      PIN_GROUP='1';
      PIN_NUMBER='(1)';
      PIN_TYPE='UNSPEC';
      PINUSE='UNSPEC';
    'B':
      PIN_GROUP='1';
      PIN_NUMBER='(2)';
      PIN_TYPE='UNSPEC';
      PINUSE='UNSPEC';
  end_pin;
  body
      PART_NAME='RES';
      PHYS_DES_PREFIX='R';
      ENVCOMP='YES;YES;YES;UNK;OK;VLD';
      PART_NUMBER='G22026-030';
      JEDEC_TYPE='SMR0603A';
      ALT_SYMBOLS='(SMX0603)';
      VALUE='475.0';
      TOL='1%';
      WATTAGE='1/10W';
      CLASS='DISCRETE';
      DESCRIPTION='RES_D,0603,475.0OHM,1.00%,1/10W';
      HEIGHT='0.024 IN';
      COMPONENT_TYPE='CHIP0603';
      LEAD_LENGTH='';
      LPID='247';
      SPEED_URL='http://speed.intel.com:8081/speed/module/pdm/item/pdm_item_deta~
il_direct.asp?item_cde=G22026-030&item_rev=01&url_param=unused';
      STATUS='DESIGN';
      RPL='NO';
      AML='3';
      BUS_UNIT='GMPO_BD_EXMPFREE';
      DAYS='???';
      PARENT_PART_TYPE='RES';
      PARENT_PPT='RES';
      PARENT_PPT_PART='RES_0603-475.0,1%,1/10W,CHIP,G22026-030';
  end_body;
end_primitive;
primitive 'RES_0805-0.0,5%,1/8W,CHIP,G221A';
  pin
    'A':
      PIN_GROUP='1';
      PIN_NUMBER='(1)';
      PIN_TYPE='UNSPEC';
      PINUSE='UNSPEC';
    'B':
      PIN_GROUP='1';
      PIN_NUMBER='(2)';
      PIN_TYPE='UNSPEC';
      PINUSE='UNSPEC';
  end_pin;
  body
      PART_NAME='RES';
      PHYS_DES_PREFIX='R';
      ENVCOMP='YES;YES;YES;UNK;OK;VLD';
      PART_NUMBER='G22179-004';
      JEDEC_TYPE='SMR0805A';
      ALT_SYMBOLS='(SMX0805)';
      VALUE='0.0';
      TOL='5%';
      WATTAGE='1/8W';
      CLASS='DISCRETE';
      DESCRIPTION='RES_D,0805,0.00OHM,5.00%,1/8W';
      HEIGHT='0.026 IN';
      COMPONENT_TYPE='CHIP0805';
      LEAD_LENGTH='';
      LPID='248';
      SPEED_URL='http://speed.intel.com:8081/speed/module/pdm/item/pdm_item_deta~
il_direct.asp?item_cde=G22179-004&item_rev=01&url_param=unused';
      STATUS='UNQUAL';
      RPL='NO';
      AML='2';
      BUS_UNIT='GMPO_BD_EXMPFREE';
      DAYS='???';
      PARENT_PART_TYPE='RES';
      PARENT_PPT='RES';
      PARENT_PPT_PART='RES_0805-0.0,5%,1/8W,CHIP,G22179-004';
  end_body;
end_primitive;
primitive 'RES_0805-0.0,5%,1/8W,EMPTY,G22A';
  pin
    'A':
      PIN_GROUP='1';
      PIN_NUMBER='(1)';
      PIN_TYPE='UNSPEC';
      PINUSE='UNSPEC';
    'B':
      PIN_GROUP='1';
      PIN_NUMBER='(2)';
      PIN_TYPE='UNSPEC';
      PINUSE='UNSPEC';
  end_pin;
  body
      PART_NAME='RES';
      PHYS_DES_PREFIX='R';
      ENVCOMP='YES;YES;YES;UNK;OK;VLD';
      PART_NUMBER='G22179-004';
      JEDEC_TYPE='SMR0805A';
      ALT_SYMBOLS='(SMX0805)';
      VALUE='NA';
      TOL='5%';
      WATTAGE='1/8W';
      CLASS='DISCRETE';
      DESCRIPTION='RES_D,0805,0.00OHM,5.00%,1/8W';
      HEIGHT='0.026 IN';
      COMPONENT_TYPE='CHIP0805';
      LEAD_LENGTH='';
      LPID='248';
      SPEED_URL='http://speed.intel.com:8081/speed/module/pdm/item/pdm_item_deta~
il_direct.asp?item_cde=G22179-004&item_rev=01&url_param=unused';
      STATUS='UNQUAL';
      RPL='NO';
      AML='2';
      BUS_UNIT='GMPO_BD_EXMPFREE';
      DAYS='???';
      PARENT_PART_TYPE='RES';
      PARENT_PPT='RES';
      PARENT_PPT_PART='RES_0805-0.0,5%,1/8W,EMPTY,G22179-004';
  end_body;
end_primitive;
primitive 'RES_1206-0.002,1%,1W,CHIP,G521A';
  pin
    'A':
      PIN_GROUP='1';
      PIN_NUMBER='(1)';
      PIN_TYPE='UNSPEC';
      PINUSE='UNSPEC';
    'B':
      PIN_GROUP='1';
      PIN_NUMBER='(2)';
      PIN_TYPE='UNSPEC';
      PINUSE='UNSPEC';
  end_pin;
  body
      PART_NAME='RES';
      PHYS_DES_PREFIX='R';
      ENVCOMP='YES;YES;YES;UNK;OK;VLD';
      PART_NUMBER='G52199-004';
      JEDEC_TYPE='SMR1206A';
      ALT_SYMBOLS='';
      VALUE='0.002';
      TOL='1%';
      WATTAGE='1W';
      CLASS='DISCRETE';
      DESCRIPTION='0.002OHM 1206LF';
      HEIGHT='0.035 IN';
      COMPONENT_TYPE='CHIP';
      LEAD_LENGTH='';
      LPID='249';
      SPEED_URL='http://speed.intel.com:8081/speed/module/pdm/item/pdm_item_deta~
il_direct.asp?item_cde=G52199-004&item_rev=01&url_param=unused';
      STATUS='DESIGN';
      RPL='NO';
      AML='1';
      BUS_UNIT='SMO_BOARDS';
      DAYS='???';
      PARENT_PART_TYPE='RES';
      PARENT_PPT='RES';
      PARENT_PPT_PART='RES_1206-0.002,1%,1W,CHIP,G52199-004';
  end_body;
end_primitive;
primitive 'RES_PWR_6PAD-0.001,1%,3W,CHIP,A';
  pin
    '1':
      PIN_NUMBER='(1)';
      PIN_TYPE='ANALOG';
      NO_LOAD_CHECK='Both';
      NO_IO_CHECK='Both';
      NO_ASSERT_CHECK='TRUE';
      NO_DIR_CHECK='TRUE';
      ALLOW_CONNECT='TRUE';
      PINUSE='UNSPEC';
    '2':
      PIN_NUMBER='(2)';
      PIN_TYPE='ANALOG';
      NO_LOAD_CHECK='Both';
      NO_IO_CHECK='Both';
      NO_ASSERT_CHECK='TRUE';
      NO_DIR_CHECK='TRUE';
      ALLOW_CONNECT='TRUE';
      PINUSE='UNSPEC';
    '3':
      PIN_NUMBER='(3)';
      PIN_TYPE='ANALOG';
      NO_LOAD_CHECK='Both';
      NO_IO_CHECK='Both';
      NO_ASSERT_CHECK='TRUE';
      NO_DIR_CHECK='TRUE';
      ALLOW_CONNECT='TRUE';
      PINUSE='UNSPEC';
    '4':
      PIN_NUMBER='(4)';
      PIN_TYPE='ANALOG';
      NO_LOAD_CHECK='Both';
      NO_IO_CHECK='Both';
      NO_ASSERT_CHECK='TRUE';
      NO_DIR_CHECK='TRUE';
      ALLOW_CONNECT='TRUE';
      PINUSE='UNSPEC';
    '5':
      PIN_NUMBER='(5)';
      PIN_TYPE='ANALOG';
      NO_LOAD_CHECK='Both';
      NO_IO_CHECK='Both';
      NO_ASSERT_CHECK='TRUE';
      NO_DIR_CHECK='TRUE';
      ALLOW_CONNECT='TRUE';
      PINUSE='UNSPEC';
    '6':
      PIN_NUMBER='(6)';
      PIN_TYPE='ANALOG';
      NO_LOAD_CHECK='Both';
      NO_IO_CHECK='Both';
      NO_ASSERT_CHECK='TRUE';
      NO_DIR_CHECK='TRUE';
      ALLOW_CONNECT='TRUE';
      PINUSE='UNSPEC';
  end_pin;
  body
      PART_NAME='RES_PWR';
      PHYS_DES_PREFIX='R';
      ENVCOMP='YES;YES;YES;UNK;ok;VLD';
      PART_NUMBER='E74391-005';
      JEDEC_TYPE='SMR2512D';
      ALT_SYMBOLS='';
      VALUE='0.001';
      TOL='1%';
      WATTAGE='3W';
      CLASS='DISCRETE';
      DESCRIPTION='RES_D,2512,1.00mOHM,1.00%,3W';
      HEIGHT='0.035 IN';
      COMPONENT_TYPE='SMTOTHER';
      LPID='2341';
      SPEED_URL='http://speed.intel.com:8081/speed/module/pdm/item/pdm_item_deta~
il_direct.asp?item_cde=E74391-005&item_rev=01&url_param=unused';
      STATUS='Design';
      RPL='NO';
      AML='2';
      BUS_UNIT='SMO_BOARDS';
      DAYS='???';
      PARENT_PART_TYPE='RES_PWR_6PAD';
      PARENT_PPT='RES_PWR';
      PARENT_PPT_PART='RES_PWR_6PAD-0.001,1%,3W,CHIP,E74391-005';
  end_body;
end_primitive;
primitive 'RT8240_QFN-IC,H66262-001';
  pin
    'BOOT':
      PIN_NUMBER='(4)';
      INPUT_LOAD='(-0.01,0.01)';
      PINUSE='IN';
    'CS':
      PIN_NUMBER='(10)';
      INPUT_LOAD='(-0.01,0.01)';
      PINUSE='IN';
    'EN':
      PIN_NUMBER='(8)';
      INPUT_LOAD='(-0.01,0.01)';
      PINUSE='IN';
    'G0':
      PIN_NUMBER='(11)';
      INPUT_LOAD='(-0.01,0.01)';
      PINUSE='IN';
    'GND'<1>:
      PIN_NUMBER='(13)';
      PINUSE='GROUND';
      NO_LOAD_CHECK='Both';
      NO_IO_CHECK='Both';
      NO_ASSERT_CHECK='TRUE';
      NO_DIR_CHECK='TRUE';
      ALLOW_CONNECT='TRUE';
    'GND'<0>:
      PIN_NUMBER='(12)';
      PINUSE='GROUND';
      NO_LOAD_CHECK='Both';
      NO_IO_CHECK='Both';
      NO_ASSERT_CHECK='TRUE';
      NO_DIR_CHECK='TRUE';
      ALLOW_CONNECT='TRUE';
    'LGATE':
      PIN_NUMBER='(1)';
      OUTPUT_LOAD='(1.0,-1.0)';
      PINUSE='OUT';
    'PGOOD':
      PIN_NUMBER='(9)';
      INPUT_LOAD='(-0.01,0.01)';
      PINUSE='IN';
    'PHASE':
      PIN_NUMBER='(2)';
      INPUT_LOAD='(-0.01,0.01)';
      PINUSE='IN';
    'RGND':
      PIN_NUMBER='(7)';
      PINUSE='GROUND';
      NO_LOAD_CHECK='Both';
      NO_IO_CHECK='Both';
      NO_ASSERT_CHECK='TRUE';
      NO_DIR_CHECK='TRUE';
      ALLOW_CONNECT='TRUE';
    'UGATE':
      PIN_NUMBER='(3)';
      OUTPUT_LOAD='(1.0,-1.0)';
      PINUSE='OUT';
    'VCC':
      PIN_NUMBER='(5)';
      PINUSE='POWER';
      NO_LOAD_CHECK='Both';
      NO_IO_CHECK='Both';
      NO_ASSERT_CHECK='TRUE';
      NO_DIR_CHECK='TRUE';
      ALLOW_CONNECT='TRUE';
    'VOUT':
      PIN_NUMBER='(6)';
      OUTPUT_LOAD='(1.0,-1.0)';
      PINUSE='OUT';
  end_pin;
  body
      PART_NAME='RT8240';
      PHYS_DES_PREFIX='EU';
      ENVCOMP='';
      PART_NUMBER='H66262-001';
      JEDEC_TYPE='QFN12_8_4MA';
      DESCRIPTION='IC,LIN,WQFN,RT8240C,VREG';
      CLASS='IC';
      COMPONENT_TYPE='LCC';
      HEIGHT='0.031 IN';
      LPID='3810';
      SPEED_URL='http://speed.intel.com:8081/speed/module/pdm/item/pdm_item_deta~
il_direct.asp?item_cde=H66262-001&item_rev=01&url_param=unused';
      STATUS='';
      RPL='';
      AML='';
      BUS_UNIT='';
      DAYS='';
      PARENT_PART_TYPE='RT8240_QFN';
      PARENT_PPT='RT8240';
      PARENT_PPT_PART='RT8240_QFN-IC,H66262-001';
  end_body;
end_primitive;
primitive 'RT9059_DFN-IC,H65765-001';
  pin
    'ADJ_NC':
      PIN_NUMBER='(4)';
      OUTPUT_LOAD='(1.0,-1.0)';
      PINUSE='OUT';
    'EN':
      PIN_NUMBER='(6)';
      INPUT_LOAD='(-0.01,0.01)';
      PINUSE='IN';
    'GND':
      PIN_NUMBER='(11)';
      PINUSE='GROUND';
      NO_LOAD_CHECK='Both';
      NO_IO_CHECK='Both';
      NO_ASSERT_CHECK='TRUE';
      NO_DIR_CHECK='TRUE';
      ALLOW_CONNECT='TRUE';
    'PGOOD':
      PIN_NUMBER='(5)';
      OUTPUT_LOAD='(1.0,-1.0)';
      PINUSE='OUT';
    'VDD':
      PIN_NUMBER='(10)';
      PINUSE='POWER';
      NO_LOAD_CHECK='Both';
      NO_IO_CHECK='Both';
      NO_ASSERT_CHECK='TRUE';
      NO_DIR_CHECK='TRUE';
      ALLOW_CONNECT='TRUE';
    'VIN'<2>:
      PIN_NUMBER='(9)';
      INPUT_LOAD='(-0.01,0.01)';
      PINUSE='IN';
    'VIN'<1>:
      PIN_NUMBER='(8)';
      INPUT_LOAD='(-0.01,0.01)';
      PINUSE='IN';
    'VIN'<0>:
      PIN_NUMBER='(7)';
      INPUT_LOAD='(-0.01,0.01)';
      PINUSE='IN';
    'VOUT'<2>:
      PIN_NUMBER='(3)';
      OUTPUT_LOAD='(1.0,-1.0)';
      PINUSE='OUT';
    'VOUT'<1>:
      PIN_NUMBER='(2)';
      OUTPUT_LOAD='(1.0,-1.0)';
      PINUSE='OUT';
    'VOUT'<0>:
      PIN_NUMBER='(1)';
      OUTPUT_LOAD='(1.0,-1.0)';
      PINUSE='OUT';
  end_pin;
  body
      PART_NAME='RT9059';
      PHYS_DES_PREFIX='EU';
      ENVCOMP='';
      PART_NUMBER='H65765-001';
      JEDEC_TYPE='DFN10_12_50MF';
      DESCRIPTION='IC,LIN,DFN,RT9059,VREG W/E';
      CLASS='IC';
      COMPONENT_TYPE='LCC';
      HEIGHT='0.031 IN';
      LPID='3373';
      SPEED_URL='http://speed.intel.com:8081/speed/module/pdm/item/pdm_item_deta~
il_direct.asp?item_cde=H65765-001&item_rev=01&url_param=unused';
      STATUS='';
      RPL='';
      AML='';
      BUS_UNIT='';
      DAYS='';
      PARENT_PART_TYPE='RT9059_DFN';
      PARENT_PPT='RT9059';
      PARENT_PPT_PART='RT9059_DFN-IC,H65765-001';
  end_body;
end_primitive;
primitive 'SC1U10V2KX-4-GP_SMD-BCG6-SC1U1A';
  pin
    '1':
      PIN_NUMBER='(1)';
      PIN_TYPE='ANALOG';
      NO_LOAD_CHECK='Both';
      NO_IO_CHECK='Both';
      NO_ASSERT_CHECK='TRUE';
      NO_DIR_CHECK='TRUE';
      ALLOW_CONNECT='TRUE';
      PINUSE='UNSPEC';
    '2':
      PIN_NUMBER='(2)';
      PIN_TYPE='ANALOG';
      NO_LOAD_CHECK='Both';
      NO_IO_CHECK='Both';
      NO_ASSERT_CHECK='TRUE';
      NO_DIR_CHECK='TRUE';
      ALLOW_CONNECT='TRUE';
      PINUSE='UNSPEC';
  end_pin;
  body
      PART_NAME='SC1U10V2KX-4-GP';
      BODY_NAME='SC1U10V2KX-4-GP';
      PHYS_DES_PREFIX='C';
      CLASS='DISCRETE';
      DESCRIPTION='CHIP CAP C 1U 10V K 0402 X6S';
      JEDEC_TYPE='C402H22';
      PARENT_PART_TYPE='SC1U10V2KX-4-GP';
      PARENT_PPT='SC1U10V2KX-4-GP';
      PARENT_PPT_PART='SC1U10V2KX-4-GP_SMD-BCG6-SC1U10V2KX-4-GP,78.10523.8FL,1UF,10%,10V,0402';
  end_body;
end_primitive;
primitive 'SC1U16V3KX-2GP_SMD-BCG-SC1U16VA';
  pin
    '1':
      PIN_NUMBER='(1)';
      PIN_TYPE='ANALOG';
      NO_LOAD_CHECK='Both';
      NO_IO_CHECK='Both';
      NO_ASSERT_CHECK='TRUE';
      NO_DIR_CHECK='TRUE';
      ALLOW_CONNECT='TRUE';
      PINUSE='UNSPEC';
    '2':
      PIN_NUMBER='(2)';
      PIN_TYPE='ANALOG';
      NO_LOAD_CHECK='Both';
      NO_IO_CHECK='Both';
      NO_ASSERT_CHECK='TRUE';
      NO_DIR_CHECK='TRUE';
      ALLOW_CONNECT='TRUE';
      PINUSE='UNSPEC';
  end_pin;
  body
      PART_NAME='SC1U16V3KX-2GP';
      BODY_NAME='SC1U16V3KX-2GP';
      PHYS_DES_PREFIX='C';
      CLASS='DISCRETE';
      DESCRIPTION='CHIP CAP C 1U 16V K0603 X5R';
      JEDEC_TYPE='C603H36';
      PARENT_PART_TYPE='SC1U16V3KX-2GP_SMD-BCG';
      PARENT_PPT='SC1U16V3KX-2GP';
      PARENT_PPT_PART='SC1U16V3KX-2GP_SMD-BCG-SC1U16V3KX-2GP,78.10521.5BL,1UF,10%,16V,0603,X5R';
  end_body;
end_primitive;
primitive 'SC22P50V2JN-4GP_SMD-BCG-SC22P5A';
  pin
    '1':
      PIN_NUMBER='(1)';
      PIN_TYPE='ANALOG';
      NO_LOAD_CHECK='Both';
      NO_IO_CHECK='Both';
      NO_ASSERT_CHECK='TRUE';
      NO_DIR_CHECK='TRUE';
      ALLOW_CONNECT='TRUE';
      PINUSE='UNSPEC';
    '2':
      PIN_NUMBER='(2)';
      PIN_TYPE='ANALOG';
      NO_LOAD_CHECK='Both';
      NO_IO_CHECK='Both';
      NO_ASSERT_CHECK='TRUE';
      NO_DIR_CHECK='TRUE';
      ALLOW_CONNECT='TRUE';
      PINUSE='UNSPEC';
  end_pin;
  body
      PART_NAME='SC22P50V2JN-4GP';
      BODY_NAME='SC22P50V2JN-4GP';
      PHYS_DES_PREFIX='C';
      CLASS='DISCRETE';
      DESCRIPTION='CHIP CAP C 22P 50V J0402 NPO';
      JEDEC_TYPE='C402H22';
      PARENT_PART_TYPE='SC22P50V2JN-4GP_SMD-BCG';
      PARENT_PPT='SC22P50V2JN-4GP';
      PARENT_PPT_PART='SC22P50V2JN-4GP_SMD-BCG-SC22P50V2JN-4GP,78.22034.1FL,22PF,5%,50V,0402,NPO';
  end_body;
end_primitive;
primitive 'SC22U16V5MX-4-GP_SMD-BCG5-SC22A';
  pin
    '1':
      PIN_NUMBER='(1)';
      PIN_TYPE='ANALOG';
      NO_LOAD_CHECK='Both';
      NO_IO_CHECK='Both';
      NO_ASSERT_CHECK='TRUE';
      NO_DIR_CHECK='TRUE';
      ALLOW_CONNECT='TRUE';
      PINUSE='UNSPEC';
    '2':
      PIN_NUMBER='(2)';
      PIN_TYPE='ANALOG';
      NO_LOAD_CHECK='Both';
      NO_IO_CHECK='Both';
      NO_ASSERT_CHECK='TRUE';
      NO_DIR_CHECK='TRUE';
      ALLOW_CONNECT='TRUE';
      PINUSE='UNSPEC';
  end_pin;
  body
      PART_NAME='SC22U16V5MX-4-GP';
      BODY_NAME='SC22U16V5MX-4-GP';
      PHYS_DES_PREFIX='C';
      CLASS='DISCRETE';
      DESCRIPTION='CHIP CAP C 22U 16V M0805 X6S';
      JEDEC_TYPE='C805H58';
      PARENT_PART_TYPE='SC22U16V5MX-4-GP';
      PARENT_PPT='SC22U16V5MX-4-GP';
      PARENT_PPT_PART='SC22U16V5MX-4-GP_SMD-BCG5-SC22U16V5MX-4-GP,078.22611.0811,22UF,20%,16V,0805,X6S';
  end_body;
end_primitive;
primitive 'SC4D7U16V3KX-GP_SMD-BCG5-SC4D7A';
  pin
    '1':
      PIN_NUMBER='(1)';
      PIN_TYPE='ANALOG';
      NO_LOAD_CHECK='Both';
      NO_IO_CHECK='Both';
      NO_ASSERT_CHECK='TRUE';
      NO_DIR_CHECK='TRUE';
      ALLOW_CONNECT='TRUE';
      PINUSE='UNSPEC';
    '2':
      PIN_NUMBER='(2)';
      PIN_TYPE='ANALOG';
      NO_LOAD_CHECK='Both';
      NO_IO_CHECK='Both';
      NO_ASSERT_CHECK='TRUE';
      NO_DIR_CHECK='TRUE';
      ALLOW_CONNECT='TRUE';
      PINUSE='UNSPEC';
  end_pin;
  body
      PART_NAME='SC4D7U16V3KX-GP';
      BODY_NAME='SC4D7U16V3KX-GP';
      PHYS_DES_PREFIX='C';
      CLASS='DISCRETE';
      DESCRIPTION='CHIP CAP C 4.7U 16V K0603 X6S';
      JEDEC_TYPE='C603H38';
      PARENT_PART_TYPE='SC4D7U16V3KX-GP';
      PARENT_PPT='SC4D7U16V3KX-GP';
      PARENT_PPT_PART='SC4D7U16V3KX-GP_SMD-BCG5-SC4D7U16V3KX-GP,078.47521.08BD,4.7UF,10%,16V,0603';
  end_body;
end_primitive;
primitive 'SCONN10_C12536004_SMLF-CONN,C1A';
  pin
    'IO1':
      PIN_NUMBER='(1)';
      PINUSE='UNSPEC';
      NO_LOAD_CHECK='BOTH';
      NO_IO_CHECK='BOTH';
      ALLOW_CONNECT='TRUE';
    'IO2':
      PIN_NUMBER='(2)';
      PINUSE='UNSPEC';
      NO_LOAD_CHECK='BOTH';
      NO_IO_CHECK='BOTH';
      ALLOW_CONNECT='TRUE';
    'IO3':
      PIN_NUMBER='(3)';
      PINUSE='UNSPEC';
      NO_LOAD_CHECK='BOTH';
      NO_IO_CHECK='BOTH';
      ALLOW_CONNECT='TRUE';
    'IO4':
      PIN_NUMBER='(4)';
      PINUSE='UNSPEC';
      NO_LOAD_CHECK='BOTH';
      NO_IO_CHECK='BOTH';
      ALLOW_CONNECT='TRUE';
    'IO5':
      PIN_NUMBER='(5)';
      PINUSE='UNSPEC';
      NO_LOAD_CHECK='BOTH';
      NO_IO_CHECK='BOTH';
      ALLOW_CONNECT='TRUE';
    'IO6':
      PIN_NUMBER='(6)';
      PINUSE='UNSPEC';
      NO_LOAD_CHECK='BOTH';
      NO_IO_CHECK='BOTH';
      ALLOW_CONNECT='TRUE';
    'IO7':
      PIN_NUMBER='(7)';
      PINUSE='UNSPEC';
      NO_LOAD_CHECK='BOTH';
      NO_IO_CHECK='BOTH';
      ALLOW_CONNECT='TRUE';
    'IO8':
      PIN_NUMBER='(8)';
      PINUSE='UNSPEC';
      NO_LOAD_CHECK='BOTH';
      NO_IO_CHECK='BOTH';
      ALLOW_CONNECT='TRUE';
    'IO9':
      PIN_NUMBER='(9)';
      PINUSE='UNSPEC';
      NO_LOAD_CHECK='BOTH';
      NO_IO_CHECK='BOTH';
      ALLOW_CONNECT='TRUE';
    'IO10':
      PIN_NUMBER='(10)';
      PINUSE='UNSPEC';
      NO_LOAD_CHECK='BOTH';
      NO_IO_CHECK='BOTH';
      ALLOW_CONNECT='TRUE';
  end_pin;
  body
      PART_NAME='SCONN10_C12536004';
      PHYS_DES_PREFIX='J';
      ENVCOMP='YES;YES;UNK;UNK;ok;VLD';
      PART_NUMBER='C12536-004';
      JEDEC_TYPE='SCONN10_C12536004';
      CLASS='IO';
      DESCRIPTION='2X5 SMT HDR 2MM';
      HEIGHT='0.307 IN';
      COMPONENT_TYPE='SMTCONN';
      LEAD_LENGTH='';
      LPID='3197';
      SPEED_URL='http://speed.intel.com:8081/speed/module/pdm/item/pdm_item_deta~
il_direct.asp?item_cde=C12536-004&item_rev=01&url_param=unused';
      STATUS='Design';
      RPL='NO';
      AML='1';
      BUS_UNIT='SMO_BOARDS';
      DAYS='56';
      PARENT_PART_TYPE='SCONN10_C12536004';
      PARENT_PPT='SCONN10_C12536004';
      PARENT_PPT_PART='SCONN10_C12536004_SMLF-CONN,C12536-004';
  end_body;
end_primitive;
primitive 'SCONN11_H67026001_SM-CONN,H670A';
  pin
    'IO1':
      PIN_NUMBER='(1)';
      BIDIRECTIONAL='TRUE';
      INPUT_LOAD='(-0.01,0.01)';
      OUTPUT_LOAD='(1.0,-1.0)';
      PINUSE='BI';
    'IO2':
      PIN_NUMBER='(2)';
      BIDIRECTIONAL='TRUE';
      INPUT_LOAD='(-0.01,0.01)';
      OUTPUT_LOAD='(1.0,-1.0)';
      PINUSE='BI';
    'IO3':
      PIN_NUMBER='(3)';
      BIDIRECTIONAL='TRUE';
      INPUT_LOAD='(-0.01,0.01)';
      OUTPUT_LOAD='(1.0,-1.0)';
      PINUSE='BI';
    'IO4':
      PIN_NUMBER='(4)';
      BIDIRECTIONAL='TRUE';
      INPUT_LOAD='(-0.01,0.01)';
      OUTPUT_LOAD='(1.0,-1.0)';
      PINUSE='BI';
    'IO5':
      PIN_NUMBER='(5)';
      BIDIRECTIONAL='TRUE';
      INPUT_LOAD='(-0.01,0.01)';
      OUTPUT_LOAD='(1.0,-1.0)';
      PINUSE='BI';
    'IO6':
      PIN_NUMBER='(6)';
      BIDIRECTIONAL='TRUE';
      INPUT_LOAD='(-0.01,0.01)';
      OUTPUT_LOAD='(1.0,-1.0)';
      PINUSE='BI';
    'IO7':
      PIN_NUMBER='(7)';
      BIDIRECTIONAL='TRUE';
      INPUT_LOAD='(-0.01,0.01)';
      OUTPUT_LOAD='(1.0,-1.0)';
      PINUSE='BI';
    'IO8':
      PIN_NUMBER='(8)';
      BIDIRECTIONAL='TRUE';
      INPUT_LOAD='(-0.01,0.01)';
      OUTPUT_LOAD='(1.0,-1.0)';
      PINUSE='BI';
    'IO9':
      PIN_NUMBER='(9)';
      BIDIRECTIONAL='TRUE';
      INPUT_LOAD='(-0.01,0.01)';
      OUTPUT_LOAD='(1.0,-1.0)';
      PINUSE='BI';
    'IO10':
      PIN_NUMBER='(10)';
      BIDIRECTIONAL='TRUE';
      INPUT_LOAD='(-0.01,0.01)';
      OUTPUT_LOAD='(1.0,-1.0)';
      PINUSE='BI';
    'IO11':
      PIN_NUMBER='(11)';
      BIDIRECTIONAL='TRUE';
      INPUT_LOAD='(-0.01,0.01)';
      OUTPUT_LOAD='(1.0,-1.0)';
      PINUSE='BI';
    'MP1':
      PIN_NUMBER='(MP1)';
      PINUSE='GROUND';
      NO_LOAD_CHECK='Both';
      NO_IO_CHECK='Both';
      NO_ASSERT_CHECK='TRUE';
      NO_DIR_CHECK='TRUE';
      ALLOW_CONNECT='TRUE';
    'MP2':
      PIN_NUMBER='(MP2)';
      PINUSE='GROUND';
      NO_LOAD_CHECK='Both';
      NO_IO_CHECK='Both';
      NO_ASSERT_CHECK='TRUE';
      NO_DIR_CHECK='TRUE';
      ALLOW_CONNECT='TRUE';
  end_pin;
  body
      PART_NAME='SCONN11_H67026001';
      BODY_NAME='SCONN11_H67026001';
      PHYS_DES_PREFIX='J';
      ENVCOMP='';
      PART_NUMBER='H67026-001';
      JEDEC_TYPE='SCONN11_H67026001';
      DESCRIPTION='CONN,BTB,11P,RCP,VT,4MM,1MM';
      CLASS='IO';
      COMPONENT_TYPE='SMTCONN';
      HEIGHT='0.164 IN';
      LPID='3814';
      SPEED_URL='http://speed.intel.com:8081/speed/module/pdm/item/pdm_item_deta~
il_direct.asp?item_cde=H67026-001&item_rev=01&url_param=unused';
      STATUS='';
      RPL='';
      AML='';
      BUS_UNIT='';
      DAYS='';
      PARENT_PART_TYPE='SCONN11_H67026001_SM';
      PARENT_PPT='SCONN11_H67026001';
      PARENT_PPT_PART='SCONN11_H67026001_SM-CONN,H67026-001';
  end_body;
end_primitive;
primitive 'SCONN120_A28699018_SM-SCONN,A2A';
  pin
    'IO1':
      PIN_NUMBER='(1)';
      BIDIRECTIONAL='TRUE';
      INPUT_LOAD='(-0.01,0.01)';
      OUTPUT_LOAD='(1.0,-1.0)';
      PINUSE='BI';
    'IO10':
      PIN_NUMBER='(10)';
      BIDIRECTIONAL='TRUE';
      INPUT_LOAD='(-0.01,0.01)';
      OUTPUT_LOAD='(1.0,-1.0)';
      PINUSE='BI';
    'IO100':
      PIN_NUMBER='(100)';
      BIDIRECTIONAL='TRUE';
      INPUT_LOAD='(-0.01,0.01)';
      OUTPUT_LOAD='(1.0,-1.0)';
      PINUSE='BI';
    'IO101':
      PIN_NUMBER='(101)';
      BIDIRECTIONAL='TRUE';
      INPUT_LOAD='(-0.01,0.01)';
      OUTPUT_LOAD='(1.0,-1.0)';
      PINUSE='BI';
    'IO102':
      PIN_NUMBER='(102)';
      BIDIRECTIONAL='TRUE';
      INPUT_LOAD='(-0.01,0.01)';
      OUTPUT_LOAD='(1.0,-1.0)';
      PINUSE='BI';
    'IO103':
      PIN_NUMBER='(103)';
      BIDIRECTIONAL='TRUE';
      INPUT_LOAD='(-0.01,0.01)';
      OUTPUT_LOAD='(1.0,-1.0)';
      PINUSE='BI';
    'IO104':
      PIN_NUMBER='(104)';
      BIDIRECTIONAL='TRUE';
      INPUT_LOAD='(-0.01,0.01)';
      OUTPUT_LOAD='(1.0,-1.0)';
      PINUSE='BI';
    'IO105':
      PIN_NUMBER='(105)';
      BIDIRECTIONAL='TRUE';
      INPUT_LOAD='(-0.01,0.01)';
      OUTPUT_LOAD='(1.0,-1.0)';
      PINUSE='BI';
    'IO106':
      PIN_NUMBER='(106)';
      BIDIRECTIONAL='TRUE';
      INPUT_LOAD='(-0.01,0.01)';
      OUTPUT_LOAD='(1.0,-1.0)';
      PINUSE='BI';
    'IO107':
      PIN_NUMBER='(107)';
      BIDIRECTIONAL='TRUE';
      INPUT_LOAD='(-0.01,0.01)';
      OUTPUT_LOAD='(1.0,-1.0)';
      PINUSE='BI';
    'IO108':
      PIN_NUMBER='(108)';
      BIDIRECTIONAL='TRUE';
      INPUT_LOAD='(-0.01,0.01)';
      OUTPUT_LOAD='(1.0,-1.0)';
      PINUSE='BI';
    'IO109':
      PIN_NUMBER='(109)';
      BIDIRECTIONAL='TRUE';
      INPUT_LOAD='(-0.01,0.01)';
      OUTPUT_LOAD='(1.0,-1.0)';
      PINUSE='BI';
    'IO11':
      PIN_NUMBER='(11)';
      BIDIRECTIONAL='TRUE';
      INPUT_LOAD='(-0.01,0.01)';
      OUTPUT_LOAD='(1.0,-1.0)';
      PINUSE='BI';
    'IO110':
      PIN_NUMBER='(110)';
      BIDIRECTIONAL='TRUE';
      INPUT_LOAD='(-0.01,0.01)';
      OUTPUT_LOAD='(1.0,-1.0)';
      PINUSE='BI';
    'IO111':
      PIN_NUMBER='(111)';
      BIDIRECTIONAL='TRUE';
      INPUT_LOAD='(-0.01,0.01)';
      OUTPUT_LOAD='(1.0,-1.0)';
      PINUSE='BI';
    'IO112':
      PIN_NUMBER='(112)';
      BIDIRECTIONAL='TRUE';
      INPUT_LOAD='(-0.01,0.01)';
      OUTPUT_LOAD='(1.0,-1.0)';
      PINUSE='BI';
    'IO113':
      PIN_NUMBER='(113)';
      BIDIRECTIONAL='TRUE';
      INPUT_LOAD='(-0.01,0.01)';
      OUTPUT_LOAD='(1.0,-1.0)';
      PINUSE='BI';
    'IO114':
      PIN_NUMBER='(114)';
      BIDIRECTIONAL='TRUE';
      INPUT_LOAD='(-0.01,0.01)';
      OUTPUT_LOAD='(1.0,-1.0)';
      PINUSE='BI';
    'IO115':
      PIN_NUMBER='(115)';
      BIDIRECTIONAL='TRUE';
      INPUT_LOAD='(-0.01,0.01)';
      OUTPUT_LOAD='(1.0,-1.0)';
      PINUSE='BI';
    'IO116':
      PIN_NUMBER='(116)';
      BIDIRECTIONAL='TRUE';
      INPUT_LOAD='(-0.01,0.01)';
      OUTPUT_LOAD='(1.0,-1.0)';
      PINUSE='BI';
    'IO117':
      PIN_NUMBER='(117)';
      BIDIRECTIONAL='TRUE';
      INPUT_LOAD='(-0.01,0.01)';
      OUTPUT_LOAD='(1.0,-1.0)';
      PINUSE='BI';
    'IO118':
      PIN_NUMBER='(118)';
      BIDIRECTIONAL='TRUE';
      INPUT_LOAD='(-0.01,0.01)';
      OUTPUT_LOAD='(1.0,-1.0)';
      PINUSE='BI';
    'IO119':
      PIN_NUMBER='(119)';
      BIDIRECTIONAL='TRUE';
      INPUT_LOAD='(-0.01,0.01)';
      OUTPUT_LOAD='(1.0,-1.0)';
      PINUSE='BI';
    'IO12':
      PIN_NUMBER='(12)';
      BIDIRECTIONAL='TRUE';
      INPUT_LOAD='(-0.01,0.01)';
      OUTPUT_LOAD='(1.0,-1.0)';
      PINUSE='BI';
    'IO120':
      PIN_NUMBER='(120)';
      BIDIRECTIONAL='TRUE';
      INPUT_LOAD='(-0.01,0.01)';
      OUTPUT_LOAD='(1.0,-1.0)';
      PINUSE='BI';
    'IO13':
      PIN_NUMBER='(13)';
      BIDIRECTIONAL='TRUE';
      INPUT_LOAD='(-0.01,0.01)';
      OUTPUT_LOAD='(1.0,-1.0)';
      PINUSE='BI';
    'IO14':
      PIN_NUMBER='(14)';
      BIDIRECTIONAL='TRUE';
      INPUT_LOAD='(-0.01,0.01)';
      OUTPUT_LOAD='(1.0,-1.0)';
      PINUSE='BI';
    'IO15':
      PIN_NUMBER='(15)';
      BIDIRECTIONAL='TRUE';
      INPUT_LOAD='(-0.01,0.01)';
      OUTPUT_LOAD='(1.0,-1.0)';
      PINUSE='BI';
    'IO16':
      PIN_NUMBER='(16)';
      BIDIRECTIONAL='TRUE';
      INPUT_LOAD='(-0.01,0.01)';
      OUTPUT_LOAD='(1.0,-1.0)';
      PINUSE='BI';
    'IO17':
      PIN_NUMBER='(17)';
      BIDIRECTIONAL='TRUE';
      INPUT_LOAD='(-0.01,0.01)';
      OUTPUT_LOAD='(1.0,-1.0)';
      PINUSE='BI';
    'IO18':
      PIN_NUMBER='(18)';
      BIDIRECTIONAL='TRUE';
      INPUT_LOAD='(-0.01,0.01)';
      OUTPUT_LOAD='(1.0,-1.0)';
      PINUSE='BI';
    'IO19':
      PIN_NUMBER='(19)';
      BIDIRECTIONAL='TRUE';
      INPUT_LOAD='(-0.01,0.01)';
      OUTPUT_LOAD='(1.0,-1.0)';
      PINUSE='BI';
    'IO2':
      PIN_NUMBER='(2)';
      BIDIRECTIONAL='TRUE';
      INPUT_LOAD='(-0.01,0.01)';
      OUTPUT_LOAD='(1.0,-1.0)';
      PINUSE='BI';
    'IO20':
      PIN_NUMBER='(20)';
      BIDIRECTIONAL='TRUE';
      INPUT_LOAD='(-0.01,0.01)';
      OUTPUT_LOAD='(1.0,-1.0)';
      PINUSE='BI';
    'IO21':
      PIN_NUMBER='(21)';
      BIDIRECTIONAL='TRUE';
      INPUT_LOAD='(-0.01,0.01)';
      OUTPUT_LOAD='(1.0,-1.0)';
      PINUSE='BI';
    'IO22':
      PIN_NUMBER='(22)';
      BIDIRECTIONAL='TRUE';
      INPUT_LOAD='(-0.01,0.01)';
      OUTPUT_LOAD='(1.0,-1.0)';
      PINUSE='BI';
    'IO23':
      PIN_NUMBER='(23)';
      BIDIRECTIONAL='TRUE';
      INPUT_LOAD='(-0.01,0.01)';
      OUTPUT_LOAD='(1.0,-1.0)';
      PINUSE='BI';
    'IO24':
      PIN_NUMBER='(24)';
      BIDIRECTIONAL='TRUE';
      INPUT_LOAD='(-0.01,0.01)';
      OUTPUT_LOAD='(1.0,-1.0)';
      PINUSE='BI';
    'IO25':
      PIN_NUMBER='(25)';
      BIDIRECTIONAL='TRUE';
      INPUT_LOAD='(-0.01,0.01)';
      OUTPUT_LOAD='(1.0,-1.0)';
      PINUSE='BI';
    'IO26':
      PIN_NUMBER='(26)';
      BIDIRECTIONAL='TRUE';
      INPUT_LOAD='(-0.01,0.01)';
      OUTPUT_LOAD='(1.0,-1.0)';
      PINUSE='BI';
    'IO27':
      PIN_NUMBER='(27)';
      BIDIRECTIONAL='TRUE';
      INPUT_LOAD='(-0.01,0.01)';
      OUTPUT_LOAD='(1.0,-1.0)';
      PINUSE='BI';
    'IO28':
      PIN_NUMBER='(28)';
      BIDIRECTIONAL='TRUE';
      INPUT_LOAD='(-0.01,0.01)';
      OUTPUT_LOAD='(1.0,-1.0)';
      PINUSE='BI';
    'IO29':
      PIN_NUMBER='(29)';
      BIDIRECTIONAL='TRUE';
      INPUT_LOAD='(-0.01,0.01)';
      OUTPUT_LOAD='(1.0,-1.0)';
      PINUSE='BI';
    'IO3':
      PIN_NUMBER='(3)';
      BIDIRECTIONAL='TRUE';
      INPUT_LOAD='(-0.01,0.01)';
      OUTPUT_LOAD='(1.0,-1.0)';
      PINUSE='BI';
    'IO30':
      PIN_NUMBER='(30)';
      BIDIRECTIONAL='TRUE';
      INPUT_LOAD='(-0.01,0.01)';
      OUTPUT_LOAD='(1.0,-1.0)';
      PINUSE='BI';
    'IO31':
      PIN_NUMBER='(31)';
      BIDIRECTIONAL='TRUE';
      INPUT_LOAD='(-0.01,0.01)';
      OUTPUT_LOAD='(1.0,-1.0)';
      PINUSE='BI';
    'IO32':
      PIN_NUMBER='(32)';
      BIDIRECTIONAL='TRUE';
      INPUT_LOAD='(-0.01,0.01)';
      OUTPUT_LOAD='(1.0,-1.0)';
      PINUSE='BI';
    'IO33':
      PIN_NUMBER='(33)';
      BIDIRECTIONAL='TRUE';
      INPUT_LOAD='(-0.01,0.01)';
      OUTPUT_LOAD='(1.0,-1.0)';
      PINUSE='BI';
    'IO34':
      PIN_NUMBER='(34)';
      BIDIRECTIONAL='TRUE';
      INPUT_LOAD='(-0.01,0.01)';
      OUTPUT_LOAD='(1.0,-1.0)';
      PINUSE='BI';
    'IO35':
      PIN_NUMBER='(35)';
      BIDIRECTIONAL='TRUE';
      INPUT_LOAD='(-0.01,0.01)';
      OUTPUT_LOAD='(1.0,-1.0)';
      PINUSE='BI';
    'IO36':
      PIN_NUMBER='(36)';
      BIDIRECTIONAL='TRUE';
      INPUT_LOAD='(-0.01,0.01)';
      OUTPUT_LOAD='(1.0,-1.0)';
      PINUSE='BI';
    'IO37':
      PIN_NUMBER='(37)';
      BIDIRECTIONAL='TRUE';
      INPUT_LOAD='(-0.01,0.01)';
      OUTPUT_LOAD='(1.0,-1.0)';
      PINUSE='BI';
    'IO38':
      PIN_NUMBER='(38)';
      BIDIRECTIONAL='TRUE';
      INPUT_LOAD='(-0.01,0.01)';
      OUTPUT_LOAD='(1.0,-1.0)';
      PINUSE='BI';
    'IO39':
      PIN_NUMBER='(39)';
      BIDIRECTIONAL='TRUE';
      INPUT_LOAD='(-0.01,0.01)';
      OUTPUT_LOAD='(1.0,-1.0)';
      PINUSE='BI';
    'IO4':
      PIN_NUMBER='(4)';
      BIDIRECTIONAL='TRUE';
      INPUT_LOAD='(-0.01,0.01)';
      OUTPUT_LOAD='(1.0,-1.0)';
      PINUSE='BI';
    'IO40':
      PIN_NUMBER='(40)';
      BIDIRECTIONAL='TRUE';
      INPUT_LOAD='(-0.01,0.01)';
      OUTPUT_LOAD='(1.0,-1.0)';
      PINUSE='BI';
    'IO41':
      PIN_NUMBER='(41)';
      BIDIRECTIONAL='TRUE';
      INPUT_LOAD='(-0.01,0.01)';
      OUTPUT_LOAD='(1.0,-1.0)';
      PINUSE='BI';
    'IO42':
      PIN_NUMBER='(42)';
      BIDIRECTIONAL='TRUE';
      INPUT_LOAD='(-0.01,0.01)';
      OUTPUT_LOAD='(1.0,-1.0)';
      PINUSE='BI';
    'IO43':
      PIN_NUMBER='(43)';
      BIDIRECTIONAL='TRUE';
      INPUT_LOAD='(-0.01,0.01)';
      OUTPUT_LOAD='(1.0,-1.0)';
      PINUSE='BI';
    'IO44':
      PIN_NUMBER='(44)';
      BIDIRECTIONAL='TRUE';
      INPUT_LOAD='(-0.01,0.01)';
      OUTPUT_LOAD='(1.0,-1.0)';
      PINUSE='BI';
    'IO45':
      PIN_NUMBER='(45)';
      BIDIRECTIONAL='TRUE';
      INPUT_LOAD='(-0.01,0.01)';
      OUTPUT_LOAD='(1.0,-1.0)';
      PINUSE='BI';
    'IO46':
      PIN_NUMBER='(46)';
      BIDIRECTIONAL='TRUE';
      INPUT_LOAD='(-0.01,0.01)';
      OUTPUT_LOAD='(1.0,-1.0)';
      PINUSE='BI';
    'IO47':
      PIN_NUMBER='(47)';
      BIDIRECTIONAL='TRUE';
      INPUT_LOAD='(-0.01,0.01)';
      OUTPUT_LOAD='(1.0,-1.0)';
      PINUSE='BI';
    'IO48':
      PIN_NUMBER='(48)';
      BIDIRECTIONAL='TRUE';
      INPUT_LOAD='(-0.01,0.01)';
      OUTPUT_LOAD='(1.0,-1.0)';
      PINUSE='BI';
    'IO49':
      PIN_NUMBER='(49)';
      BIDIRECTIONAL='TRUE';
      INPUT_LOAD='(-0.01,0.01)';
      OUTPUT_LOAD='(1.0,-1.0)';
      PINUSE='BI';
    'IO5':
      PIN_NUMBER='(5)';
      BIDIRECTIONAL='TRUE';
      INPUT_LOAD='(-0.01,0.01)';
      OUTPUT_LOAD='(1.0,-1.0)';
      PINUSE='BI';
    'IO50':
      PIN_NUMBER='(50)';
      BIDIRECTIONAL='TRUE';
      INPUT_LOAD='(-0.01,0.01)';
      OUTPUT_LOAD='(1.0,-1.0)';
      PINUSE='BI';
    'IO51':
      PIN_NUMBER='(51)';
      BIDIRECTIONAL='TRUE';
      INPUT_LOAD='(-0.01,0.01)';
      OUTPUT_LOAD='(1.0,-1.0)';
      PINUSE='BI';
    'IO52':
      PIN_NUMBER='(52)';
      BIDIRECTIONAL='TRUE';
      INPUT_LOAD='(-0.01,0.01)';
      OUTPUT_LOAD='(1.0,-1.0)';
      PINUSE='BI';
    'IO53':
      PIN_NUMBER='(53)';
      BIDIRECTIONAL='TRUE';
      INPUT_LOAD='(-0.01,0.01)';
      OUTPUT_LOAD='(1.0,-1.0)';
      PINUSE='BI';
    'IO54':
      PIN_NUMBER='(54)';
      BIDIRECTIONAL='TRUE';
      INPUT_LOAD='(-0.01,0.01)';
      OUTPUT_LOAD='(1.0,-1.0)';
      PINUSE='BI';
    'IO55':
      PIN_NUMBER='(55)';
      BIDIRECTIONAL='TRUE';
      INPUT_LOAD='(-0.01,0.01)';
      OUTPUT_LOAD='(1.0,-1.0)';
      PINUSE='BI';
    'IO56':
      PIN_NUMBER='(56)';
      BIDIRECTIONAL='TRUE';
      INPUT_LOAD='(-0.01,0.01)';
      OUTPUT_LOAD='(1.0,-1.0)';
      PINUSE='BI';
    'IO57':
      PIN_NUMBER='(57)';
      BIDIRECTIONAL='TRUE';
      INPUT_LOAD='(-0.01,0.01)';
      OUTPUT_LOAD='(1.0,-1.0)';
      PINUSE='BI';
    'IO58':
      PIN_NUMBER='(58)';
      BIDIRECTIONAL='TRUE';
      INPUT_LOAD='(-0.01,0.01)';
      OUTPUT_LOAD='(1.0,-1.0)';
      PINUSE='BI';
    'IO59':
      PIN_NUMBER='(59)';
      BIDIRECTIONAL='TRUE';
      INPUT_LOAD='(-0.01,0.01)';
      OUTPUT_LOAD='(1.0,-1.0)';
      PINUSE='BI';
    'IO6':
      PIN_NUMBER='(6)';
      BIDIRECTIONAL='TRUE';
      INPUT_LOAD='(-0.01,0.01)';
      OUTPUT_LOAD='(1.0,-1.0)';
      PINUSE='BI';
    'IO60':
      PIN_NUMBER='(60)';
      BIDIRECTIONAL='TRUE';
      INPUT_LOAD='(-0.01,0.01)';
      OUTPUT_LOAD='(1.0,-1.0)';
      PINUSE='BI';
    'IO61':
      PIN_NUMBER='(61)';
      BIDIRECTIONAL='TRUE';
      INPUT_LOAD='(-0.01,0.01)';
      OUTPUT_LOAD='(1.0,-1.0)';
      PINUSE='BI';
    'IO62':
      PIN_NUMBER='(62)';
      BIDIRECTIONAL='TRUE';
      INPUT_LOAD='(-0.01,0.01)';
      OUTPUT_LOAD='(1.0,-1.0)';
      PINUSE='BI';
    'IO63':
      PIN_NUMBER='(63)';
      BIDIRECTIONAL='TRUE';
      INPUT_LOAD='(-0.01,0.01)';
      OUTPUT_LOAD='(1.0,-1.0)';
      PINUSE='BI';
    'IO64':
      PIN_NUMBER='(64)';
      BIDIRECTIONAL='TRUE';
      INPUT_LOAD='(-0.01,0.01)';
      OUTPUT_LOAD='(1.0,-1.0)';
      PINUSE='BI';
    'IO65':
      PIN_NUMBER='(65)';
      BIDIRECTIONAL='TRUE';
      INPUT_LOAD='(-0.01,0.01)';
      OUTPUT_LOAD='(1.0,-1.0)';
      PINUSE='BI';
    'IO66':
      PIN_NUMBER='(66)';
      BIDIRECTIONAL='TRUE';
      INPUT_LOAD='(-0.01,0.01)';
      OUTPUT_LOAD='(1.0,-1.0)';
      PINUSE='BI';
    'IO67':
      PIN_NUMBER='(67)';
      BIDIRECTIONAL='TRUE';
      INPUT_LOAD='(-0.01,0.01)';
      OUTPUT_LOAD='(1.0,-1.0)';
      PINUSE='BI';
    'IO68':
      PIN_NUMBER='(68)';
      BIDIRECTIONAL='TRUE';
      INPUT_LOAD='(-0.01,0.01)';
      OUTPUT_LOAD='(1.0,-1.0)';
      PINUSE='BI';
    'IO69':
      PIN_NUMBER='(69)';
      BIDIRECTIONAL='TRUE';
      INPUT_LOAD='(-0.01,0.01)';
      OUTPUT_LOAD='(1.0,-1.0)';
      PINUSE='BI';
    'IO7':
      PIN_NUMBER='(7)';
      BIDIRECTIONAL='TRUE';
      INPUT_LOAD='(-0.01,0.01)';
      OUTPUT_LOAD='(1.0,-1.0)';
      PINUSE='BI';
    'IO70':
      PIN_NUMBER='(70)';
      BIDIRECTIONAL='TRUE';
      INPUT_LOAD='(-0.01,0.01)';
      OUTPUT_LOAD='(1.0,-1.0)';
      PINUSE='BI';
    'IO71':
      PIN_NUMBER='(71)';
      BIDIRECTIONAL='TRUE';
      INPUT_LOAD='(-0.01,0.01)';
      OUTPUT_LOAD='(1.0,-1.0)';
      PINUSE='BI';
    'IO72':
      PIN_NUMBER='(72)';
      BIDIRECTIONAL='TRUE';
      INPUT_LOAD='(-0.01,0.01)';
      OUTPUT_LOAD='(1.0,-1.0)';
      PINUSE='BI';
    'IO73':
      PIN_NUMBER='(73)';
      BIDIRECTIONAL='TRUE';
      INPUT_LOAD='(-0.01,0.01)';
      OUTPUT_LOAD='(1.0,-1.0)';
      PINUSE='BI';
    'IO74':
      PIN_NUMBER='(74)';
      BIDIRECTIONAL='TRUE';
      INPUT_LOAD='(-0.01,0.01)';
      OUTPUT_LOAD='(1.0,-1.0)';
      PINUSE='BI';
    'IO75':
      PIN_NUMBER='(75)';
      BIDIRECTIONAL='TRUE';
      INPUT_LOAD='(-0.01,0.01)';
      OUTPUT_LOAD='(1.0,-1.0)';
      PINUSE='BI';
    'IO76':
      PIN_NUMBER='(76)';
      BIDIRECTIONAL='TRUE';
      INPUT_LOAD='(-0.01,0.01)';
      OUTPUT_LOAD='(1.0,-1.0)';
      PINUSE='BI';
    'IO77':
      PIN_NUMBER='(77)';
      BIDIRECTIONAL='TRUE';
      INPUT_LOAD='(-0.01,0.01)';
      OUTPUT_LOAD='(1.0,-1.0)';
      PINUSE='BI';
    'IO78':
      PIN_NUMBER='(78)';
      BIDIRECTIONAL='TRUE';
      INPUT_LOAD='(-0.01,0.01)';
      OUTPUT_LOAD='(1.0,-1.0)';
      PINUSE='BI';
    'IO79':
      PIN_NUMBER='(79)';
      BIDIRECTIONAL='TRUE';
      INPUT_LOAD='(-0.01,0.01)';
      OUTPUT_LOAD='(1.0,-1.0)';
      PINUSE='BI';
    'IO8':
      PIN_NUMBER='(8)';
      BIDIRECTIONAL='TRUE';
      INPUT_LOAD='(-0.01,0.01)';
      OUTPUT_LOAD='(1.0,-1.0)';
      PINUSE='BI';
    'IO80':
      PIN_NUMBER='(80)';
      BIDIRECTIONAL='TRUE';
      INPUT_LOAD='(-0.01,0.01)';
      OUTPUT_LOAD='(1.0,-1.0)';
      PINUSE='BI';
    'IO81':
      PIN_NUMBER='(81)';
      BIDIRECTIONAL='TRUE';
      INPUT_LOAD='(-0.01,0.01)';
      OUTPUT_LOAD='(1.0,-1.0)';
      PINUSE='BI';
    'IO82':
      PIN_NUMBER='(82)';
      BIDIRECTIONAL='TRUE';
      INPUT_LOAD='(-0.01,0.01)';
      OUTPUT_LOAD='(1.0,-1.0)';
      PINUSE='BI';
    'IO83':
      PIN_NUMBER='(83)';
      BIDIRECTIONAL='TRUE';
      INPUT_LOAD='(-0.01,0.01)';
      OUTPUT_LOAD='(1.0,-1.0)';
      PINUSE='BI';
    'IO84':
      PIN_NUMBER='(84)';
      BIDIRECTIONAL='TRUE';
      INPUT_LOAD='(-0.01,0.01)';
      OUTPUT_LOAD='(1.0,-1.0)';
      PINUSE='BI';
    'IO85':
      PIN_NUMBER='(85)';
      BIDIRECTIONAL='TRUE';
      INPUT_LOAD='(-0.01,0.01)';
      OUTPUT_LOAD='(1.0,-1.0)';
      PINUSE='BI';
    'IO86':
      PIN_NUMBER='(86)';
      BIDIRECTIONAL='TRUE';
      INPUT_LOAD='(-0.01,0.01)';
      OUTPUT_LOAD='(1.0,-1.0)';
      PINUSE='BI';
    'IO87':
      PIN_NUMBER='(87)';
      BIDIRECTIONAL='TRUE';
      INPUT_LOAD='(-0.01,0.01)';
      OUTPUT_LOAD='(1.0,-1.0)';
      PINUSE='BI';
    'IO88':
      PIN_NUMBER='(88)';
      BIDIRECTIONAL='TRUE';
      INPUT_LOAD='(-0.01,0.01)';
      OUTPUT_LOAD='(1.0,-1.0)';
      PINUSE='BI';
    'IO89':
      PIN_NUMBER='(89)';
      BIDIRECTIONAL='TRUE';
      INPUT_LOAD='(-0.01,0.01)';
      OUTPUT_LOAD='(1.0,-1.0)';
      PINUSE='BI';
    'IO9':
      PIN_NUMBER='(9)';
      BIDIRECTIONAL='TRUE';
      INPUT_LOAD='(-0.01,0.01)';
      OUTPUT_LOAD='(1.0,-1.0)';
      PINUSE='BI';
    'IO90':
      PIN_NUMBER='(90)';
      BIDIRECTIONAL='TRUE';
      INPUT_LOAD='(-0.01,0.01)';
      OUTPUT_LOAD='(1.0,-1.0)';
      PINUSE='BI';
    'IO91':
      PIN_NUMBER='(91)';
      BIDIRECTIONAL='TRUE';
      INPUT_LOAD='(-0.01,0.01)';
      OUTPUT_LOAD='(1.0,-1.0)';
      PINUSE='BI';
    'IO92':
      PIN_NUMBER='(92)';
      BIDIRECTIONAL='TRUE';
      INPUT_LOAD='(-0.01,0.01)';
      OUTPUT_LOAD='(1.0,-1.0)';
      PINUSE='BI';
    'IO93':
      PIN_NUMBER='(93)';
      BIDIRECTIONAL='TRUE';
      INPUT_LOAD='(-0.01,0.01)';
      OUTPUT_LOAD='(1.0,-1.0)';
      PINUSE='BI';
    'IO94':
      PIN_NUMBER='(94)';
      BIDIRECTIONAL='TRUE';
      INPUT_LOAD='(-0.01,0.01)';
      OUTPUT_LOAD='(1.0,-1.0)';
      PINUSE='BI';
    'IO95':
      PIN_NUMBER='(95)';
      BIDIRECTIONAL='TRUE';
      INPUT_LOAD='(-0.01,0.01)';
      OUTPUT_LOAD='(1.0,-1.0)';
      PINUSE='BI';
    'IO96':
      PIN_NUMBER='(96)';
      BIDIRECTIONAL='TRUE';
      INPUT_LOAD='(-0.01,0.01)';
      OUTPUT_LOAD='(1.0,-1.0)';
      PINUSE='BI';
    'IO97':
      PIN_NUMBER='(97)';
      BIDIRECTIONAL='TRUE';
      INPUT_LOAD='(-0.01,0.01)';
      OUTPUT_LOAD='(1.0,-1.0)';
      PINUSE='BI';
    'IO98':
      PIN_NUMBER='(98)';
      BIDIRECTIONAL='TRUE';
      INPUT_LOAD='(-0.01,0.01)';
      OUTPUT_LOAD='(1.0,-1.0)';
      PINUSE='BI';
    'IO99':
      PIN_NUMBER='(99)';
      BIDIRECTIONAL='TRUE';
      INPUT_LOAD='(-0.01,0.01)';
      OUTPUT_LOAD='(1.0,-1.0)';
      PINUSE='BI';
  end_pin;
  body
      PART_NAME='SCONN120_A28699018';
      PHYS_DES_PREFIX='J';
      ENVCOMP='';
      PART_NUMBER='A28699-018';
      JEDEC_TYPE='SCONN120_A28699018';
      CLASS='IO';
      DESCRIPTION='CONN,BTB,120P,RCP,VT,0MM,.8MM';
      HEIGHT='0.472 IN';
      COMPONENT_TYPE='SMTCONN';
      LPID='3924';
      SPEED_URL='http://speed.intel.com:8081/speed/module/pdm/item/pdm_item_deta~
il_direct.asp?item_cde=A28699-018&item_rev=01&url_param=unused';
      STATUS='';
      RPL='';
      AML='';
      BUS_UNIT='';
      DAYS='';
      PARENT_PART_TYPE='SCONN120_A28699018_SM';
      PARENT_PPT='SCONN120_A28699018';
      PARENT_PPT_PART='SCONN120_A28699018_SM-SCONN,A28699-018';
  end_body;
end_primitive;
primitive 'SCONN120_H61426002_SM-CONN,H61A';
  pin
    'IOA1':
      PIN_NUMBER='(A1)';
      BIDIRECTIONAL='TRUE';
      INPUT_LOAD='(-0.01,0.01)';
      OUTPUT_LOAD='(1.0,-1.0)';
      PINUSE='BI';
    'IOA10':
      PIN_NUMBER='(A10)';
      BIDIRECTIONAL='TRUE';
      INPUT_LOAD='(-0.01,0.01)';
      OUTPUT_LOAD='(1.0,-1.0)';
      PINUSE='BI';
    'IOA11':
      PIN_NUMBER='(A11)';
      BIDIRECTIONAL='TRUE';
      INPUT_LOAD='(-0.01,0.01)';
      OUTPUT_LOAD='(1.0,-1.0)';
      PINUSE='BI';
    'IOA12':
      PIN_NUMBER='(A12)';
      BIDIRECTIONAL='TRUE';
      INPUT_LOAD='(-0.01,0.01)';
      OUTPUT_LOAD='(1.0,-1.0)';
      PINUSE='BI';
    'IOA13':
      PIN_NUMBER='(A13)';
      BIDIRECTIONAL='TRUE';
      INPUT_LOAD='(-0.01,0.01)';
      OUTPUT_LOAD='(1.0,-1.0)';
      PINUSE='BI';
    'IOA14':
      PIN_NUMBER='(A14)';
      BIDIRECTIONAL='TRUE';
      INPUT_LOAD='(-0.01,0.01)';
      OUTPUT_LOAD='(1.0,-1.0)';
      PINUSE='BI';
    'IOA15':
      PIN_NUMBER='(A15)';
      BIDIRECTIONAL='TRUE';
      INPUT_LOAD='(-0.01,0.01)';
      OUTPUT_LOAD='(1.0,-1.0)';
      PINUSE='BI';
    'IOA16':
      PIN_NUMBER='(A16)';
      BIDIRECTIONAL='TRUE';
      INPUT_LOAD='(-0.01,0.01)';
      OUTPUT_LOAD='(1.0,-1.0)';
      PINUSE='BI';
    'IOA17':
      PIN_NUMBER='(A17)';
      BIDIRECTIONAL='TRUE';
      INPUT_LOAD='(-0.01,0.01)';
      OUTPUT_LOAD='(1.0,-1.0)';
      PINUSE='BI';
    'IOA18':
      PIN_NUMBER='(A18)';
      BIDIRECTIONAL='TRUE';
      INPUT_LOAD='(-0.01,0.01)';
      OUTPUT_LOAD='(1.0,-1.0)';
      PINUSE='BI';
    'IOA19':
      PIN_NUMBER='(A19)';
      BIDIRECTIONAL='TRUE';
      INPUT_LOAD='(-0.01,0.01)';
      OUTPUT_LOAD='(1.0,-1.0)';
      PINUSE='BI';
    'IOA2':
      PIN_NUMBER='(A2)';
      BIDIRECTIONAL='TRUE';
      INPUT_LOAD='(-0.01,0.01)';
      OUTPUT_LOAD='(1.0,-1.0)';
      PINUSE='BI';
    'IOA20':
      PIN_NUMBER='(A20)';
      BIDIRECTIONAL='TRUE';
      INPUT_LOAD='(-0.01,0.01)';
      OUTPUT_LOAD='(1.0,-1.0)';
      PINUSE='BI';
    'IOA3':
      PIN_NUMBER='(A3)';
      BIDIRECTIONAL='TRUE';
      INPUT_LOAD='(-0.01,0.01)';
      OUTPUT_LOAD='(1.0,-1.0)';
      PINUSE='BI';
    'IOA4':
      PIN_NUMBER='(A4)';
      BIDIRECTIONAL='TRUE';
      INPUT_LOAD='(-0.01,0.01)';
      OUTPUT_LOAD='(1.0,-1.0)';
      PINUSE='BI';
    'IOA5':
      PIN_NUMBER='(A5)';
      BIDIRECTIONAL='TRUE';
      INPUT_LOAD='(-0.01,0.01)';
      OUTPUT_LOAD='(1.0,-1.0)';
      PINUSE='BI';
    'IOA6':
      PIN_NUMBER='(A6)';
      BIDIRECTIONAL='TRUE';
      INPUT_LOAD='(-0.01,0.01)';
      OUTPUT_LOAD='(1.0,-1.0)';
      PINUSE='BI';
    'IOA7':
      PIN_NUMBER='(A7)';
      BIDIRECTIONAL='TRUE';
      INPUT_LOAD='(-0.01,0.01)';
      OUTPUT_LOAD='(1.0,-1.0)';
      PINUSE='BI';
    'IOA8':
      PIN_NUMBER='(A8)';
      BIDIRECTIONAL='TRUE';
      INPUT_LOAD='(-0.01,0.01)';
      OUTPUT_LOAD='(1.0,-1.0)';
      PINUSE='BI';
    'IOA9':
      PIN_NUMBER='(A9)';
      BIDIRECTIONAL='TRUE';
      INPUT_LOAD='(-0.01,0.01)';
      OUTPUT_LOAD='(1.0,-1.0)';
      PINUSE='BI';
    'IOB1':
      PIN_NUMBER='(B1)';
      BIDIRECTIONAL='TRUE';
      INPUT_LOAD='(-0.01,0.01)';
      OUTPUT_LOAD='(1.0,-1.0)';
      PINUSE='BI';
    'IOB10':
      PIN_NUMBER='(B10)';
      BIDIRECTIONAL='TRUE';
      INPUT_LOAD='(-0.01,0.01)';
      OUTPUT_LOAD='(1.0,-1.0)';
      PINUSE='BI';
    'IOB11':
      PIN_NUMBER='(B11)';
      BIDIRECTIONAL='TRUE';
      INPUT_LOAD='(-0.01,0.01)';
      OUTPUT_LOAD='(1.0,-1.0)';
      PINUSE='BI';
    'IOB12':
      PIN_NUMBER='(B12)';
      BIDIRECTIONAL='TRUE';
      INPUT_LOAD='(-0.01,0.01)';
      OUTPUT_LOAD='(1.0,-1.0)';
      PINUSE='BI';
    'IOB13':
      PIN_NUMBER='(B13)';
      BIDIRECTIONAL='TRUE';
      INPUT_LOAD='(-0.01,0.01)';
      OUTPUT_LOAD='(1.0,-1.0)';
      PINUSE='BI';
    'IOB14':
      PIN_NUMBER='(B14)';
      BIDIRECTIONAL='TRUE';
      INPUT_LOAD='(-0.01,0.01)';
      OUTPUT_LOAD='(1.0,-1.0)';
      PINUSE='BI';
    'IOB15':
      PIN_NUMBER='(B15)';
      BIDIRECTIONAL='TRUE';
      INPUT_LOAD='(-0.01,0.01)';
      OUTPUT_LOAD='(1.0,-1.0)';
      PINUSE='BI';
    'IOB16':
      PIN_NUMBER='(B16)';
      BIDIRECTIONAL='TRUE';
      INPUT_LOAD='(-0.01,0.01)';
      OUTPUT_LOAD='(1.0,-1.0)';
      PINUSE='BI';
    'IOB17':
      PIN_NUMBER='(B17)';
      BIDIRECTIONAL='TRUE';
      INPUT_LOAD='(-0.01,0.01)';
      OUTPUT_LOAD='(1.0,-1.0)';
      PINUSE='BI';
    'IOB18':
      PIN_NUMBER='(B18)';
      BIDIRECTIONAL='TRUE';
      INPUT_LOAD='(-0.01,0.01)';
      OUTPUT_LOAD='(1.0,-1.0)';
      PINUSE='BI';
    'IOB19':
      PIN_NUMBER='(B19)';
      BIDIRECTIONAL='TRUE';
      INPUT_LOAD='(-0.01,0.01)';
      OUTPUT_LOAD='(1.0,-1.0)';
      PINUSE='BI';
    'IOB2':
      PIN_NUMBER='(B2)';
      BIDIRECTIONAL='TRUE';
      INPUT_LOAD='(-0.01,0.01)';
      OUTPUT_LOAD='(1.0,-1.0)';
      PINUSE='BI';
    'IOB20':
      PIN_NUMBER='(B20)';
      BIDIRECTIONAL='TRUE';
      INPUT_LOAD='(-0.01,0.01)';
      OUTPUT_LOAD='(1.0,-1.0)';
      PINUSE='BI';
    'IOB3':
      PIN_NUMBER='(B3)';
      BIDIRECTIONAL='TRUE';
      INPUT_LOAD='(-0.01,0.01)';
      OUTPUT_LOAD='(1.0,-1.0)';
      PINUSE='BI';
    'IOB4':
      PIN_NUMBER='(B4)';
      BIDIRECTIONAL='TRUE';
      INPUT_LOAD='(-0.01,0.01)';
      OUTPUT_LOAD='(1.0,-1.0)';
      PINUSE='BI';
    'IOB5':
      PIN_NUMBER='(B5)';
      BIDIRECTIONAL='TRUE';
      INPUT_LOAD='(-0.01,0.01)';
      OUTPUT_LOAD='(1.0,-1.0)';
      PINUSE='BI';
    'IOB6':
      PIN_NUMBER='(B6)';
      BIDIRECTIONAL='TRUE';
      INPUT_LOAD='(-0.01,0.01)';
      OUTPUT_LOAD='(1.0,-1.0)';
      PINUSE='BI';
    'IOB7':
      PIN_NUMBER='(B7)';
      BIDIRECTIONAL='TRUE';
      INPUT_LOAD='(-0.01,0.01)';
      OUTPUT_LOAD='(1.0,-1.0)';
      PINUSE='BI';
    'IOB8':
      PIN_NUMBER='(B8)';
      BIDIRECTIONAL='TRUE';
      INPUT_LOAD='(-0.01,0.01)';
      OUTPUT_LOAD='(1.0,-1.0)';
      PINUSE='BI';
    'IOB9':
      PIN_NUMBER='(B9)';
      BIDIRECTIONAL='TRUE';
      INPUT_LOAD='(-0.01,0.01)';
      OUTPUT_LOAD='(1.0,-1.0)';
      PINUSE='BI';
    'IOC1':
      PIN_NUMBER='(C1)';
      BIDIRECTIONAL='TRUE';
      INPUT_LOAD='(-0.01,0.01)';
      OUTPUT_LOAD='(1.0,-1.0)';
      PINUSE='BI';
    'IOC10':
      PIN_NUMBER='(C10)';
      BIDIRECTIONAL='TRUE';
      INPUT_LOAD='(-0.01,0.01)';
      OUTPUT_LOAD='(1.0,-1.0)';
      PINUSE='BI';
    'IOC11':
      PIN_NUMBER='(C11)';
      BIDIRECTIONAL='TRUE';
      INPUT_LOAD='(-0.01,0.01)';
      OUTPUT_LOAD='(1.0,-1.0)';
      PINUSE='BI';
    'IOC12':
      PIN_NUMBER='(C12)';
      BIDIRECTIONAL='TRUE';
      INPUT_LOAD='(-0.01,0.01)';
      OUTPUT_LOAD='(1.0,-1.0)';
      PINUSE='BI';
    'IOC13':
      PIN_NUMBER='(C13)';
      BIDIRECTIONAL='TRUE';
      INPUT_LOAD='(-0.01,0.01)';
      OUTPUT_LOAD='(1.0,-1.0)';
      PINUSE='BI';
    'IOC14':
      PIN_NUMBER='(C14)';
      BIDIRECTIONAL='TRUE';
      INPUT_LOAD='(-0.01,0.01)';
      OUTPUT_LOAD='(1.0,-1.0)';
      PINUSE='BI';
    'IOC15':
      PIN_NUMBER='(C15)';
      BIDIRECTIONAL='TRUE';
      INPUT_LOAD='(-0.01,0.01)';
      OUTPUT_LOAD='(1.0,-1.0)';
      PINUSE='BI';
    'IOC16':
      PIN_NUMBER='(C16)';
      BIDIRECTIONAL='TRUE';
      INPUT_LOAD='(-0.01,0.01)';
      OUTPUT_LOAD='(1.0,-1.0)';
      PINUSE='BI';
    'IOC17':
      PIN_NUMBER='(C17)';
      BIDIRECTIONAL='TRUE';
      INPUT_LOAD='(-0.01,0.01)';
      OUTPUT_LOAD='(1.0,-1.0)';
      PINUSE='BI';
    'IOC18':
      PIN_NUMBER='(C18)';
      BIDIRECTIONAL='TRUE';
      INPUT_LOAD='(-0.01,0.01)';
      OUTPUT_LOAD='(1.0,-1.0)';
      PINUSE='BI';
    'IOC19':
      PIN_NUMBER='(C19)';
      BIDIRECTIONAL='TRUE';
      INPUT_LOAD='(-0.01,0.01)';
      OUTPUT_LOAD='(1.0,-1.0)';
      PINUSE='BI';
    'IOC2':
      PIN_NUMBER='(C2)';
      BIDIRECTIONAL='TRUE';
      INPUT_LOAD='(-0.01,0.01)';
      OUTPUT_LOAD='(1.0,-1.0)';
      PINUSE='BI';
    'IOC20':
      PIN_NUMBER='(C20)';
      BIDIRECTIONAL='TRUE';
      INPUT_LOAD='(-0.01,0.01)';
      OUTPUT_LOAD='(1.0,-1.0)';
      PINUSE='BI';
    'IOC3':
      PIN_NUMBER='(C3)';
      BIDIRECTIONAL='TRUE';
      INPUT_LOAD='(-0.01,0.01)';
      OUTPUT_LOAD='(1.0,-1.0)';
      PINUSE='BI';
    'IOC4':
      PIN_NUMBER='(C4)';
      BIDIRECTIONAL='TRUE';
      INPUT_LOAD='(-0.01,0.01)';
      OUTPUT_LOAD='(1.0,-1.0)';
      PINUSE='BI';
    'IOC5':
      PIN_NUMBER='(C5)';
      BIDIRECTIONAL='TRUE';
      INPUT_LOAD='(-0.01,0.01)';
      OUTPUT_LOAD='(1.0,-1.0)';
      PINUSE='BI';
    'IOC6':
      PIN_NUMBER='(C6)';
      BIDIRECTIONAL='TRUE';
      INPUT_LOAD='(-0.01,0.01)';
      OUTPUT_LOAD='(1.0,-1.0)';
      PINUSE='BI';
    'IOC7':
      PIN_NUMBER='(C7)';
      BIDIRECTIONAL='TRUE';
      INPUT_LOAD='(-0.01,0.01)';
      OUTPUT_LOAD='(1.0,-1.0)';
      PINUSE='BI';
    'IOC8':
      PIN_NUMBER='(C8)';
      BIDIRECTIONAL='TRUE';
      INPUT_LOAD='(-0.01,0.01)';
      OUTPUT_LOAD='(1.0,-1.0)';
      PINUSE='BI';
    'IOC9':
      PIN_NUMBER='(C9)';
      BIDIRECTIONAL='TRUE';
      INPUT_LOAD='(-0.01,0.01)';
      OUTPUT_LOAD='(1.0,-1.0)';
      PINUSE='BI';
    'IOD1':
      PIN_NUMBER='(D1)';
      BIDIRECTIONAL='TRUE';
      INPUT_LOAD='(-0.01,0.01)';
      OUTPUT_LOAD='(1.0,-1.0)';
      PINUSE='BI';
    'IOD10':
      PIN_NUMBER='(D10)';
      BIDIRECTIONAL='TRUE';
      INPUT_LOAD='(-0.01,0.01)';
      OUTPUT_LOAD='(1.0,-1.0)';
      PINUSE='BI';
    'IOD11':
      PIN_NUMBER='(D11)';
      BIDIRECTIONAL='TRUE';
      INPUT_LOAD='(-0.01,0.01)';
      OUTPUT_LOAD='(1.0,-1.0)';
      PINUSE='BI';
    'IOD12':
      PIN_NUMBER='(D12)';
      BIDIRECTIONAL='TRUE';
      INPUT_LOAD='(-0.01,0.01)';
      OUTPUT_LOAD='(1.0,-1.0)';
      PINUSE='BI';
    'IOD13':
      PIN_NUMBER='(D13)';
      BIDIRECTIONAL='TRUE';
      INPUT_LOAD='(-0.01,0.01)';
      OUTPUT_LOAD='(1.0,-1.0)';
      PINUSE='BI';
    'IOD14':
      PIN_NUMBER='(D14)';
      BIDIRECTIONAL='TRUE';
      INPUT_LOAD='(-0.01,0.01)';
      OUTPUT_LOAD='(1.0,-1.0)';
      PINUSE='BI';
    'IOD15':
      PIN_NUMBER='(D15)';
      BIDIRECTIONAL='TRUE';
      INPUT_LOAD='(-0.01,0.01)';
      OUTPUT_LOAD='(1.0,-1.0)';
      PINUSE='BI';
    'IOD16':
      PIN_NUMBER='(D16)';
      BIDIRECTIONAL='TRUE';
      INPUT_LOAD='(-0.01,0.01)';
      OUTPUT_LOAD='(1.0,-1.0)';
      PINUSE='BI';
    'IOD17':
      PIN_NUMBER='(D17)';
      BIDIRECTIONAL='TRUE';
      INPUT_LOAD='(-0.01,0.01)';
      OUTPUT_LOAD='(1.0,-1.0)';
      PINUSE='BI';
    'IOD18':
      PIN_NUMBER='(D18)';
      BIDIRECTIONAL='TRUE';
      INPUT_LOAD='(-0.01,0.01)';
      OUTPUT_LOAD='(1.0,-1.0)';
      PINUSE='BI';
    'IOD19':
      PIN_NUMBER='(D19)';
      BIDIRECTIONAL='TRUE';
      INPUT_LOAD='(-0.01,0.01)';
      OUTPUT_LOAD='(1.0,-1.0)';
      PINUSE='BI';
    'IOD2':
      PIN_NUMBER='(D2)';
      BIDIRECTIONAL='TRUE';
      INPUT_LOAD='(-0.01,0.01)';
      OUTPUT_LOAD='(1.0,-1.0)';
      PINUSE='BI';
    'IOD20':
      PIN_NUMBER='(D20)';
      BIDIRECTIONAL='TRUE';
      INPUT_LOAD='(-0.01,0.01)';
      OUTPUT_LOAD='(1.0,-1.0)';
      PINUSE='BI';
    'IOD3':
      PIN_NUMBER='(D3)';
      BIDIRECTIONAL='TRUE';
      INPUT_LOAD='(-0.01,0.01)';
      OUTPUT_LOAD='(1.0,-1.0)';
      PINUSE='BI';
    'IOD4':
      PIN_NUMBER='(D4)';
      BIDIRECTIONAL='TRUE';
      INPUT_LOAD='(-0.01,0.01)';
      OUTPUT_LOAD='(1.0,-1.0)';
      PINUSE='BI';
    'IOD5':
      PIN_NUMBER='(D5)';
      BIDIRECTIONAL='TRUE';
      INPUT_LOAD='(-0.01,0.01)';
      OUTPUT_LOAD='(1.0,-1.0)';
      PINUSE='BI';
    'IOD6':
      PIN_NUMBER='(D6)';
      BIDIRECTIONAL='TRUE';
      INPUT_LOAD='(-0.01,0.01)';
      OUTPUT_LOAD='(1.0,-1.0)';
      PINUSE='BI';
    'IOD7':
      PIN_NUMBER='(D7)';
      BIDIRECTIONAL='TRUE';
      INPUT_LOAD='(-0.01,0.01)';
      OUTPUT_LOAD='(1.0,-1.0)';
      PINUSE='BI';
    'IOD8':
      PIN_NUMBER='(D8)';
      BIDIRECTIONAL='TRUE';
      INPUT_LOAD='(-0.01,0.01)';
      OUTPUT_LOAD='(1.0,-1.0)';
      PINUSE='BI';
    'IOD9':
      PIN_NUMBER='(D9)';
      BIDIRECTIONAL='TRUE';
      INPUT_LOAD='(-0.01,0.01)';
      OUTPUT_LOAD='(1.0,-1.0)';
      PINUSE='BI';
    'IOE1':
      PIN_NUMBER='(E1)';
      BIDIRECTIONAL='TRUE';
      INPUT_LOAD='(-0.01,0.01)';
      OUTPUT_LOAD='(1.0,-1.0)';
      PINUSE='BI';
    'IOE10':
      PIN_NUMBER='(E10)';
      BIDIRECTIONAL='TRUE';
      INPUT_LOAD='(-0.01,0.01)';
      OUTPUT_LOAD='(1.0,-1.0)';
      PINUSE='BI';
    'IOE11':
      PIN_NUMBER='(E11)';
      BIDIRECTIONAL='TRUE';
      INPUT_LOAD='(-0.01,0.01)';
      OUTPUT_LOAD='(1.0,-1.0)';
      PINUSE='BI';
    'IOE12':
      PIN_NUMBER='(E12)';
      BIDIRECTIONAL='TRUE';
      INPUT_LOAD='(-0.01,0.01)';
      OUTPUT_LOAD='(1.0,-1.0)';
      PINUSE='BI';
    'IOE13':
      PIN_NUMBER='(E13)';
      BIDIRECTIONAL='TRUE';
      INPUT_LOAD='(-0.01,0.01)';
      OUTPUT_LOAD='(1.0,-1.0)';
      PINUSE='BI';
    'IOE14':
      PIN_NUMBER='(E14)';
      BIDIRECTIONAL='TRUE';
      INPUT_LOAD='(-0.01,0.01)';
      OUTPUT_LOAD='(1.0,-1.0)';
      PINUSE='BI';
    'IOE15':
      PIN_NUMBER='(E15)';
      BIDIRECTIONAL='TRUE';
      INPUT_LOAD='(-0.01,0.01)';
      OUTPUT_LOAD='(1.0,-1.0)';
      PINUSE='BI';
    'IOE16':
      PIN_NUMBER='(E16)';
      BIDIRECTIONAL='TRUE';
      INPUT_LOAD='(-0.01,0.01)';
      OUTPUT_LOAD='(1.0,-1.0)';
      PINUSE='BI';
    'IOE17':
      PIN_NUMBER='(E17)';
      BIDIRECTIONAL='TRUE';
      INPUT_LOAD='(-0.01,0.01)';
      OUTPUT_LOAD='(1.0,-1.0)';
      PINUSE='BI';
    'IOE18':
      PIN_NUMBER='(E18)';
      BIDIRECTIONAL='TRUE';
      INPUT_LOAD='(-0.01,0.01)';
      OUTPUT_LOAD='(1.0,-1.0)';
      PINUSE='BI';
    'IOE19':
      PIN_NUMBER='(E19)';
      BIDIRECTIONAL='TRUE';
      INPUT_LOAD='(-0.01,0.01)';
      OUTPUT_LOAD='(1.0,-1.0)';
      PINUSE='BI';
    'IOE2':
      PIN_NUMBER='(E2)';
      BIDIRECTIONAL='TRUE';
      INPUT_LOAD='(-0.01,0.01)';
      OUTPUT_LOAD='(1.0,-1.0)';
      PINUSE='BI';
    'IOE20':
      PIN_NUMBER='(E20)';
      BIDIRECTIONAL='TRUE';
      INPUT_LOAD='(-0.01,0.01)';
      OUTPUT_LOAD='(1.0,-1.0)';
      PINUSE='BI';
    'IOE3':
      PIN_NUMBER='(E3)';
      BIDIRECTIONAL='TRUE';
      INPUT_LOAD='(-0.01,0.01)';
      OUTPUT_LOAD='(1.0,-1.0)';
      PINUSE='BI';
    'IOE4':
      PIN_NUMBER='(E4)';
      BIDIRECTIONAL='TRUE';
      INPUT_LOAD='(-0.01,0.01)';
      OUTPUT_LOAD='(1.0,-1.0)';
      PINUSE='BI';
    'IOE5':
      PIN_NUMBER='(E5)';
      BIDIRECTIONAL='TRUE';
      INPUT_LOAD='(-0.01,0.01)';
      OUTPUT_LOAD='(1.0,-1.0)';
      PINUSE='BI';
    'IOE6':
      PIN_NUMBER='(E6)';
      BIDIRECTIONAL='TRUE';
      INPUT_LOAD='(-0.01,0.01)';
      OUTPUT_LOAD='(1.0,-1.0)';
      PINUSE='BI';
    'IOE7':
      PIN_NUMBER='(E7)';
      BIDIRECTIONAL='TRUE';
      INPUT_LOAD='(-0.01,0.01)';
      OUTPUT_LOAD='(1.0,-1.0)';
      PINUSE='BI';
    'IOE8':
      PIN_NUMBER='(E8)';
      BIDIRECTIONAL='TRUE';
      INPUT_LOAD='(-0.01,0.01)';
      OUTPUT_LOAD='(1.0,-1.0)';
      PINUSE='BI';
    'IOE9':
      PIN_NUMBER='(E9)';
      BIDIRECTIONAL='TRUE';
      INPUT_LOAD='(-0.01,0.01)';
      OUTPUT_LOAD='(1.0,-1.0)';
      PINUSE='BI';
    'IOF1':
      PIN_NUMBER='(F1)';
      BIDIRECTIONAL='TRUE';
      INPUT_LOAD='(-0.01,0.01)';
      OUTPUT_LOAD='(1.0,-1.0)';
      PINUSE='BI';
    'IOF10':
      PIN_NUMBER='(F10)';
      BIDIRECTIONAL='TRUE';
      INPUT_LOAD='(-0.01,0.01)';
      OUTPUT_LOAD='(1.0,-1.0)';
      PINUSE='BI';
    'IOF11':
      PIN_NUMBER='(F11)';
      BIDIRECTIONAL='TRUE';
      INPUT_LOAD='(-0.01,0.01)';
      OUTPUT_LOAD='(1.0,-1.0)';
      PINUSE='BI';
    'IOF12':
      PIN_NUMBER='(F12)';
      BIDIRECTIONAL='TRUE';
      INPUT_LOAD='(-0.01,0.01)';
      OUTPUT_LOAD='(1.0,-1.0)';
      PINUSE='BI';
    'IOF13':
      PIN_NUMBER='(F13)';
      BIDIRECTIONAL='TRUE';
      INPUT_LOAD='(-0.01,0.01)';
      OUTPUT_LOAD='(1.0,-1.0)';
      PINUSE='BI';
    'IOF14':
      PIN_NUMBER='(F14)';
      BIDIRECTIONAL='TRUE';
      INPUT_LOAD='(-0.01,0.01)';
      OUTPUT_LOAD='(1.0,-1.0)';
      PINUSE='BI';
    'IOF15':
      PIN_NUMBER='(F15)';
      BIDIRECTIONAL='TRUE';
      INPUT_LOAD='(-0.01,0.01)';
      OUTPUT_LOAD='(1.0,-1.0)';
      PINUSE='BI';
    'IOF16':
      PIN_NUMBER='(F16)';
      BIDIRECTIONAL='TRUE';
      INPUT_LOAD='(-0.01,0.01)';
      OUTPUT_LOAD='(1.0,-1.0)';
      PINUSE='BI';
    'IOF17':
      PIN_NUMBER='(F17)';
      BIDIRECTIONAL='TRUE';
      INPUT_LOAD='(-0.01,0.01)';
      OUTPUT_LOAD='(1.0,-1.0)';
      PINUSE='BI';
    'IOF18':
      PIN_NUMBER='(F18)';
      BIDIRECTIONAL='TRUE';
      INPUT_LOAD='(-0.01,0.01)';
      OUTPUT_LOAD='(1.0,-1.0)';
      PINUSE='BI';
    'IOF19':
      PIN_NUMBER='(F19)';
      BIDIRECTIONAL='TRUE';
      INPUT_LOAD='(-0.01,0.01)';
      OUTPUT_LOAD='(1.0,-1.0)';
      PINUSE='BI';
    'IOF2':
      PIN_NUMBER='(F2)';
      BIDIRECTIONAL='TRUE';
      INPUT_LOAD='(-0.01,0.01)';
      OUTPUT_LOAD='(1.0,-1.0)';
      PINUSE='BI';
    'IOF20':
      PIN_NUMBER='(F20)';
      BIDIRECTIONAL='TRUE';
      INPUT_LOAD='(-0.01,0.01)';
      OUTPUT_LOAD='(1.0,-1.0)';
      PINUSE='BI';
    'IOF3':
      PIN_NUMBER='(F3)';
      BIDIRECTIONAL='TRUE';
      INPUT_LOAD='(-0.01,0.01)';
      OUTPUT_LOAD='(1.0,-1.0)';
      PINUSE='BI';
    'IOF4':
      PIN_NUMBER='(F4)';
      BIDIRECTIONAL='TRUE';
      INPUT_LOAD='(-0.01,0.01)';
      OUTPUT_LOAD='(1.0,-1.0)';
      PINUSE='BI';
    'IOF5':
      PIN_NUMBER='(F5)';
      BIDIRECTIONAL='TRUE';
      INPUT_LOAD='(-0.01,0.01)';
      OUTPUT_LOAD='(1.0,-1.0)';
      PINUSE='BI';
    'IOF6':
      PIN_NUMBER='(F6)';
      BIDIRECTIONAL='TRUE';
      INPUT_LOAD='(-0.01,0.01)';
      OUTPUT_LOAD='(1.0,-1.0)';
      PINUSE='BI';
    'IOF7':
      PIN_NUMBER='(F7)';
      BIDIRECTIONAL='TRUE';
      INPUT_LOAD='(-0.01,0.01)';
      OUTPUT_LOAD='(1.0,-1.0)';
      PINUSE='BI';
    'IOF8':
      PIN_NUMBER='(F8)';
      BIDIRECTIONAL='TRUE';
      INPUT_LOAD='(-0.01,0.01)';
      OUTPUT_LOAD='(1.0,-1.0)';
      PINUSE='BI';
    'IOF9':
      PIN_NUMBER='(F9)';
      BIDIRECTIONAL='TRUE';
      INPUT_LOAD='(-0.01,0.01)';
      OUTPUT_LOAD='(1.0,-1.0)';
      PINUSE='BI';
  end_pin;
  body
      PART_NAME='SCONN120_H61426002';
      PHYS_DES_PREFIX='J';
      ENVCOMP='';
      PART_NUMBER='H61426-002';
      JEDEC_TYPE='SCONN120_H61426002';
      CLASS='IO';
      DESCRIPTION='CONN,BTB,120P,RCP,VT,0MM,1.27MM';
      HEIGHT='0.258 IN';
      COMPONENT_TYPE='SMTCONN';
      LPID='3749';
      SPEED_URL='http://speed.intel.com:8081/speed/module/pdm/item/pdm_item_deta~
il_direct.asp?item_cde=H61426-002&item_rev=01&url_param=unused';
      STATUS='';
      RPL='';
      AML='';
      BUS_UNIT='';
      DAYS='';
      PARENT_PART_TYPE='SCONN120_H61426002_SM';
      PARENT_PPT='SCONN120_H61426002';
      PARENT_PPT_PART='SCONN120_H61426002_SM-CONN,H61426-002';
  end_body;
end_primitive;
primitive 'SCONN200_H68296001_SM-CONN,H68A';
  pin
    'IO1':
      PIN_NUMBER='(1,0)';
      BIDIRECTIONAL='TRUE';
      INPUT_LOAD='(-0.01,0.01)';
      OUTPUT_LOAD='(1.0,-1.0)';
      PINUSE='BI';
    'IO2':
      PIN_NUMBER='(2,0)';
      BIDIRECTIONAL='TRUE';
      INPUT_LOAD='(-0.01,0.01)';
      OUTPUT_LOAD='(1.0,-1.0)';
      PINUSE='BI';
    'IO3':
      PIN_NUMBER='(3,0)';
      BIDIRECTIONAL='TRUE';
      INPUT_LOAD='(-0.01,0.01)';
      OUTPUT_LOAD='(1.0,-1.0)';
      PINUSE='BI';
    'IO4':
      PIN_NUMBER='(4,0)';
      BIDIRECTIONAL='TRUE';
      INPUT_LOAD='(-0.01,0.01)';
      OUTPUT_LOAD='(1.0,-1.0)';
      PINUSE='BI';
    'IO5':
      PIN_NUMBER='(5,0)';
      BIDIRECTIONAL='TRUE';
      INPUT_LOAD='(-0.01,0.01)';
      OUTPUT_LOAD='(1.0,-1.0)';
      PINUSE='BI';
    'IO6':
      PIN_NUMBER='(6,0)';
      BIDIRECTIONAL='TRUE';
      INPUT_LOAD='(-0.01,0.01)';
      OUTPUT_LOAD='(1.0,-1.0)';
      PINUSE='BI';
    'IO7':
      PIN_NUMBER='(7,0)';
      BIDIRECTIONAL='TRUE';
      INPUT_LOAD='(-0.01,0.01)';
      OUTPUT_LOAD='(1.0,-1.0)';
      PINUSE='BI';
    'IO8':
      PIN_NUMBER='(8,0)';
      BIDIRECTIONAL='TRUE';
      INPUT_LOAD='(-0.01,0.01)';
      OUTPUT_LOAD='(1.0,-1.0)';
      PINUSE='BI';
    'IO9':
      PIN_NUMBER='(9,0)';
      BIDIRECTIONAL='TRUE';
      INPUT_LOAD='(-0.01,0.01)';
      OUTPUT_LOAD='(1.0,-1.0)';
      PINUSE='BI';
    'IO10':
      PIN_NUMBER='(10,0)';
      BIDIRECTIONAL='TRUE';
      INPUT_LOAD='(-0.01,0.01)';
      OUTPUT_LOAD='(1.0,-1.0)';
      PINUSE='BI';
    'IO11':
      PIN_NUMBER='(11,0)';
      BIDIRECTIONAL='TRUE';
      INPUT_LOAD='(-0.01,0.01)';
      OUTPUT_LOAD='(1.0,-1.0)';
      PINUSE='BI';
    'IO12':
      PIN_NUMBER='(12,0)';
      BIDIRECTIONAL='TRUE';
      INPUT_LOAD='(-0.01,0.01)';
      OUTPUT_LOAD='(1.0,-1.0)';
      PINUSE='BI';
    'IO13':
      PIN_NUMBER='(13,0)';
      BIDIRECTIONAL='TRUE';
      INPUT_LOAD='(-0.01,0.01)';
      OUTPUT_LOAD='(1.0,-1.0)';
      PINUSE='BI';
    'IO14':
      PIN_NUMBER='(14,0)';
      BIDIRECTIONAL='TRUE';
      INPUT_LOAD='(-0.01,0.01)';
      OUTPUT_LOAD='(1.0,-1.0)';
      PINUSE='BI';
    'IO15':
      PIN_NUMBER='(15,0)';
      BIDIRECTIONAL='TRUE';
      INPUT_LOAD='(-0.01,0.01)';
      OUTPUT_LOAD='(1.0,-1.0)';
      PINUSE='BI';
    'IO16':
      PIN_NUMBER='(16,0)';
      BIDIRECTIONAL='TRUE';
      INPUT_LOAD='(-0.01,0.01)';
      OUTPUT_LOAD='(1.0,-1.0)';
      PINUSE='BI';
    'IO17':
      PIN_NUMBER='(17,0)';
      BIDIRECTIONAL='TRUE';
      INPUT_LOAD='(-0.01,0.01)';
      OUTPUT_LOAD='(1.0,-1.0)';
      PINUSE='BI';
    'IO18':
      PIN_NUMBER='(18,0)';
      BIDIRECTIONAL='TRUE';
      INPUT_LOAD='(-0.01,0.01)';
      OUTPUT_LOAD='(1.0,-1.0)';
      PINUSE='BI';
    'IO19':
      PIN_NUMBER='(19,0)';
      BIDIRECTIONAL='TRUE';
      INPUT_LOAD='(-0.01,0.01)';
      OUTPUT_LOAD='(1.0,-1.0)';
      PINUSE='BI';
    'IO20':
      PIN_NUMBER='(20,0)';
      BIDIRECTIONAL='TRUE';
      INPUT_LOAD='(-0.01,0.01)';
      OUTPUT_LOAD='(1.0,-1.0)';
      PINUSE='BI';
    'IO21':
      PIN_NUMBER='(21,0)';
      BIDIRECTIONAL='TRUE';
      INPUT_LOAD='(-0.01,0.01)';
      OUTPUT_LOAD='(1.0,-1.0)';
      PINUSE='BI';
    'IO22':
      PIN_NUMBER='(22,0)';
      BIDIRECTIONAL='TRUE';
      INPUT_LOAD='(-0.01,0.01)';
      OUTPUT_LOAD='(1.0,-1.0)';
      PINUSE='BI';
    'IO23':
      PIN_NUMBER='(23,0)';
      BIDIRECTIONAL='TRUE';
      INPUT_LOAD='(-0.01,0.01)';
      OUTPUT_LOAD='(1.0,-1.0)';
      PINUSE='BI';
    'IO24':
      PIN_NUMBER='(24,0)';
      BIDIRECTIONAL='TRUE';
      INPUT_LOAD='(-0.01,0.01)';
      OUTPUT_LOAD='(1.0,-1.0)';
      PINUSE='BI';
    'IO25':
      PIN_NUMBER='(25,0)';
      BIDIRECTIONAL='TRUE';
      INPUT_LOAD='(-0.01,0.01)';
      OUTPUT_LOAD='(1.0,-1.0)';
      PINUSE='BI';
    'IO26':
      PIN_NUMBER='(26,0)';
      BIDIRECTIONAL='TRUE';
      INPUT_LOAD='(-0.01,0.01)';
      OUTPUT_LOAD='(1.0,-1.0)';
      PINUSE='BI';
    'IO27':
      PIN_NUMBER='(27,0)';
      BIDIRECTIONAL='TRUE';
      INPUT_LOAD='(-0.01,0.01)';
      OUTPUT_LOAD='(1.0,-1.0)';
      PINUSE='BI';
    'IO28':
      PIN_NUMBER='(28,0)';
      BIDIRECTIONAL='TRUE';
      INPUT_LOAD='(-0.01,0.01)';
      OUTPUT_LOAD='(1.0,-1.0)';
      PINUSE='BI';
    'IO29':
      PIN_NUMBER='(29,0)';
      BIDIRECTIONAL='TRUE';
      INPUT_LOAD='(-0.01,0.01)';
      OUTPUT_LOAD='(1.0,-1.0)';
      PINUSE='BI';
    'IO30':
      PIN_NUMBER='(30,0)';
      BIDIRECTIONAL='TRUE';
      INPUT_LOAD='(-0.01,0.01)';
      OUTPUT_LOAD='(1.0,-1.0)';
      PINUSE='BI';
    'IO31':
      PIN_NUMBER='(31,0)';
      BIDIRECTIONAL='TRUE';
      INPUT_LOAD='(-0.01,0.01)';
      OUTPUT_LOAD='(1.0,-1.0)';
      PINUSE='BI';
    'IO32':
      PIN_NUMBER='(32,0)';
      BIDIRECTIONAL='TRUE';
      INPUT_LOAD='(-0.01,0.01)';
      OUTPUT_LOAD='(1.0,-1.0)';
      PINUSE='BI';
    'IO33':
      PIN_NUMBER='(33,0)';
      BIDIRECTIONAL='TRUE';
      INPUT_LOAD='(-0.01,0.01)';
      OUTPUT_LOAD='(1.0,-1.0)';
      PINUSE='BI';
    'IO34':
      PIN_NUMBER='(34,0)';
      BIDIRECTIONAL='TRUE';
      INPUT_LOAD='(-0.01,0.01)';
      OUTPUT_LOAD='(1.0,-1.0)';
      PINUSE='BI';
    'IO35':
      PIN_NUMBER='(35,0)';
      BIDIRECTIONAL='TRUE';
      INPUT_LOAD='(-0.01,0.01)';
      OUTPUT_LOAD='(1.0,-1.0)';
      PINUSE='BI';
    'IO36':
      PIN_NUMBER='(36,0)';
      BIDIRECTIONAL='TRUE';
      INPUT_LOAD='(-0.01,0.01)';
      OUTPUT_LOAD='(1.0,-1.0)';
      PINUSE='BI';
    'IO37':
      PIN_NUMBER='(37,0)';
      BIDIRECTIONAL='TRUE';
      INPUT_LOAD='(-0.01,0.01)';
      OUTPUT_LOAD='(1.0,-1.0)';
      PINUSE='BI';
    'IO38':
      PIN_NUMBER='(38,0)';
      BIDIRECTIONAL='TRUE';
      INPUT_LOAD='(-0.01,0.01)';
      OUTPUT_LOAD='(1.0,-1.0)';
      PINUSE='BI';
    'IO39':
      PIN_NUMBER='(39,0)';
      BIDIRECTIONAL='TRUE';
      INPUT_LOAD='(-0.01,0.01)';
      OUTPUT_LOAD='(1.0,-1.0)';
      PINUSE='BI';
    'IO40':
      PIN_NUMBER='(40,0)';
      BIDIRECTIONAL='TRUE';
      INPUT_LOAD='(-0.01,0.01)';
      OUTPUT_LOAD='(1.0,-1.0)';
      PINUSE='BI';
    'IO41':
      PIN_NUMBER='(41,0)';
      BIDIRECTIONAL='TRUE';
      INPUT_LOAD='(-0.01,0.01)';
      OUTPUT_LOAD='(1.0,-1.0)';
      PINUSE='BI';
    'IO42':
      PIN_NUMBER='(42,0)';
      BIDIRECTIONAL='TRUE';
      INPUT_LOAD='(-0.01,0.01)';
      OUTPUT_LOAD='(1.0,-1.0)';
      PINUSE='BI';
    'IO43':
      PIN_NUMBER='(43,0)';
      BIDIRECTIONAL='TRUE';
      INPUT_LOAD='(-0.01,0.01)';
      OUTPUT_LOAD='(1.0,-1.0)';
      PINUSE='BI';
    'IO44':
      PIN_NUMBER='(44,0)';
      BIDIRECTIONAL='TRUE';
      INPUT_LOAD='(-0.01,0.01)';
      OUTPUT_LOAD='(1.0,-1.0)';
      PINUSE='BI';
    'IO45':
      PIN_NUMBER='(45,0)';
      BIDIRECTIONAL='TRUE';
      INPUT_LOAD='(-0.01,0.01)';
      OUTPUT_LOAD='(1.0,-1.0)';
      PINUSE='BI';
    'IO46':
      PIN_NUMBER='(46,0)';
      BIDIRECTIONAL='TRUE';
      INPUT_LOAD='(-0.01,0.01)';
      OUTPUT_LOAD='(1.0,-1.0)';
      PINUSE='BI';
    'IO47':
      PIN_NUMBER='(47,0)';
      BIDIRECTIONAL='TRUE';
      INPUT_LOAD='(-0.01,0.01)';
      OUTPUT_LOAD='(1.0,-1.0)';
      PINUSE='BI';
    'IO48':
      PIN_NUMBER='(48,0)';
      BIDIRECTIONAL='TRUE';
      INPUT_LOAD='(-0.01,0.01)';
      OUTPUT_LOAD='(1.0,-1.0)';
      PINUSE='BI';
    'IO49':
      PIN_NUMBER='(49,0)';
      BIDIRECTIONAL='TRUE';
      INPUT_LOAD='(-0.01,0.01)';
      OUTPUT_LOAD='(1.0,-1.0)';
      PINUSE='BI';
    'IO50':
      PIN_NUMBER='(50,0)';
      BIDIRECTIONAL='TRUE';
      INPUT_LOAD='(-0.01,0.01)';
      OUTPUT_LOAD='(1.0,-1.0)';
      PINUSE='BI';
    'IO51':
      PIN_NUMBER='(51,0)';
      BIDIRECTIONAL='TRUE';
      INPUT_LOAD='(-0.01,0.01)';
      OUTPUT_LOAD='(1.0,-1.0)';
      PINUSE='BI';
    'IO52':
      PIN_NUMBER='(52,0)';
      BIDIRECTIONAL='TRUE';
      INPUT_LOAD='(-0.01,0.01)';
      OUTPUT_LOAD='(1.0,-1.0)';
      PINUSE='BI';
    'IO53':
      PIN_NUMBER='(53,0)';
      BIDIRECTIONAL='TRUE';
      INPUT_LOAD='(-0.01,0.01)';
      OUTPUT_LOAD='(1.0,-1.0)';
      PINUSE='BI';
    'IO54':
      PIN_NUMBER='(54,0)';
      BIDIRECTIONAL='TRUE';
      INPUT_LOAD='(-0.01,0.01)';
      OUTPUT_LOAD='(1.0,-1.0)';
      PINUSE='BI';
    'IO55':
      PIN_NUMBER='(55,0)';
      BIDIRECTIONAL='TRUE';
      INPUT_LOAD='(-0.01,0.01)';
      OUTPUT_LOAD='(1.0,-1.0)';
      PINUSE='BI';
    'IO56':
      PIN_NUMBER='(56,0)';
      BIDIRECTIONAL='TRUE';
      INPUT_LOAD='(-0.01,0.01)';
      OUTPUT_LOAD='(1.0,-1.0)';
      PINUSE='BI';
    'IO57':
      PIN_NUMBER='(57,0)';
      BIDIRECTIONAL='TRUE';
      INPUT_LOAD='(-0.01,0.01)';
      OUTPUT_LOAD='(1.0,-1.0)';
      PINUSE='BI';
    'IO58':
      PIN_NUMBER='(58,0)';
      BIDIRECTIONAL='TRUE';
      INPUT_LOAD='(-0.01,0.01)';
      OUTPUT_LOAD='(1.0,-1.0)';
      PINUSE='BI';
    'IO59':
      PIN_NUMBER='(59,0)';
      BIDIRECTIONAL='TRUE';
      INPUT_LOAD='(-0.01,0.01)';
      OUTPUT_LOAD='(1.0,-1.0)';
      PINUSE='BI';
    'IO60':
      PIN_NUMBER='(60,0)';
      BIDIRECTIONAL='TRUE';
      INPUT_LOAD='(-0.01,0.01)';
      OUTPUT_LOAD='(1.0,-1.0)';
      PINUSE='BI';
    'IO61':
      PIN_NUMBER='(61,0)';
      BIDIRECTIONAL='TRUE';
      INPUT_LOAD='(-0.01,0.01)';
      OUTPUT_LOAD='(1.0,-1.0)';
      PINUSE='BI';
    'IO62':
      PIN_NUMBER='(62,0)';
      BIDIRECTIONAL='TRUE';
      INPUT_LOAD='(-0.01,0.01)';
      OUTPUT_LOAD='(1.0,-1.0)';
      PINUSE='BI';
    'IO63':
      PIN_NUMBER='(63,0)';
      BIDIRECTIONAL='TRUE';
      INPUT_LOAD='(-0.01,0.01)';
      OUTPUT_LOAD='(1.0,-1.0)';
      PINUSE='BI';
    'IO64':
      PIN_NUMBER='(64,0)';
      BIDIRECTIONAL='TRUE';
      INPUT_LOAD='(-0.01,0.01)';
      OUTPUT_LOAD='(1.0,-1.0)';
      PINUSE='BI';
    'IO65':
      PIN_NUMBER='(65,0)';
      BIDIRECTIONAL='TRUE';
      INPUT_LOAD='(-0.01,0.01)';
      OUTPUT_LOAD='(1.0,-1.0)';
      PINUSE='BI';
    'IO66':
      PIN_NUMBER='(66,0)';
      BIDIRECTIONAL='TRUE';
      INPUT_LOAD='(-0.01,0.01)';
      OUTPUT_LOAD='(1.0,-1.0)';
      PINUSE='BI';
    'IO67':
      PIN_NUMBER='(67,0)';
      BIDIRECTIONAL='TRUE';
      INPUT_LOAD='(-0.01,0.01)';
      OUTPUT_LOAD='(1.0,-1.0)';
      PINUSE='BI';
    'IO68':
      PIN_NUMBER='(68,0)';
      BIDIRECTIONAL='TRUE';
      INPUT_LOAD='(-0.01,0.01)';
      OUTPUT_LOAD='(1.0,-1.0)';
      PINUSE='BI';
    'IO69':
      PIN_NUMBER='(69,0)';
      BIDIRECTIONAL='TRUE';
      INPUT_LOAD='(-0.01,0.01)';
      OUTPUT_LOAD='(1.0,-1.0)';
      PINUSE='BI';
    'IO70':
      PIN_NUMBER='(70,0)';
      BIDIRECTIONAL='TRUE';
      INPUT_LOAD='(-0.01,0.01)';
      OUTPUT_LOAD='(1.0,-1.0)';
      PINUSE='BI';
    'IO71':
      PIN_NUMBER='(71,0)';
      BIDIRECTIONAL='TRUE';
      INPUT_LOAD='(-0.01,0.01)';
      OUTPUT_LOAD='(1.0,-1.0)';
      PINUSE='BI';
    'IO72':
      PIN_NUMBER='(72,0)';
      BIDIRECTIONAL='TRUE';
      INPUT_LOAD='(-0.01,0.01)';
      OUTPUT_LOAD='(1.0,-1.0)';
      PINUSE='BI';
    'IO73':
      PIN_NUMBER='(73,0)';
      BIDIRECTIONAL='TRUE';
      INPUT_LOAD='(-0.01,0.01)';
      OUTPUT_LOAD='(1.0,-1.0)';
      PINUSE='BI';
    'IO74':
      PIN_NUMBER='(74,0)';
      BIDIRECTIONAL='TRUE';
      INPUT_LOAD='(-0.01,0.01)';
      OUTPUT_LOAD='(1.0,-1.0)';
      PINUSE='BI';
    'IO75':
      PIN_NUMBER='(75,0)';
      BIDIRECTIONAL='TRUE';
      INPUT_LOAD='(-0.01,0.01)';
      OUTPUT_LOAD='(1.0,-1.0)';
      PINUSE='BI';
    'IO76':
      PIN_NUMBER='(76,0)';
      BIDIRECTIONAL='TRUE';
      INPUT_LOAD='(-0.01,0.01)';
      OUTPUT_LOAD='(1.0,-1.0)';
      PINUSE='BI';
    'IO77':
      PIN_NUMBER='(77,0)';
      BIDIRECTIONAL='TRUE';
      INPUT_LOAD='(-0.01,0.01)';
      OUTPUT_LOAD='(1.0,-1.0)';
      PINUSE='BI';
    'IO78':
      PIN_NUMBER='(78,0)';
      BIDIRECTIONAL='TRUE';
      INPUT_LOAD='(-0.01,0.01)';
      OUTPUT_LOAD='(1.0,-1.0)';
      PINUSE='BI';
    'IO79':
      PIN_NUMBER='(79,0)';
      BIDIRECTIONAL='TRUE';
      INPUT_LOAD='(-0.01,0.01)';
      OUTPUT_LOAD='(1.0,-1.0)';
      PINUSE='BI';
    'IO80':
      PIN_NUMBER='(80,0)';
      BIDIRECTIONAL='TRUE';
      INPUT_LOAD='(-0.01,0.01)';
      OUTPUT_LOAD='(1.0,-1.0)';
      PINUSE='BI';
    'IO81':
      PIN_NUMBER='(81,0)';
      BIDIRECTIONAL='TRUE';
      INPUT_LOAD='(-0.01,0.01)';
      OUTPUT_LOAD='(1.0,-1.0)';
      PINUSE='BI';
    'IO82':
      PIN_NUMBER='(82,0)';
      BIDIRECTIONAL='TRUE';
      INPUT_LOAD='(-0.01,0.01)';
      OUTPUT_LOAD='(1.0,-1.0)';
      PINUSE='BI';
    'IO83':
      PIN_NUMBER='(83,0)';
      BIDIRECTIONAL='TRUE';
      INPUT_LOAD='(-0.01,0.01)';
      OUTPUT_LOAD='(1.0,-1.0)';
      PINUSE='BI';
    'IO84':
      PIN_NUMBER='(84,0)';
      BIDIRECTIONAL='TRUE';
      INPUT_LOAD='(-0.01,0.01)';
      OUTPUT_LOAD='(1.0,-1.0)';
      PINUSE='BI';
    'IO85':
      PIN_NUMBER='(85,0)';
      BIDIRECTIONAL='TRUE';
      INPUT_LOAD='(-0.01,0.01)';
      OUTPUT_LOAD='(1.0,-1.0)';
      PINUSE='BI';
    'IO86':
      PIN_NUMBER='(86,0)';
      BIDIRECTIONAL='TRUE';
      INPUT_LOAD='(-0.01,0.01)';
      OUTPUT_LOAD='(1.0,-1.0)';
      PINUSE='BI';
    'IO87':
      PIN_NUMBER='(87,0)';
      BIDIRECTIONAL='TRUE';
      INPUT_LOAD='(-0.01,0.01)';
      OUTPUT_LOAD='(1.0,-1.0)';
      PINUSE='BI';
    'IO88':
      PIN_NUMBER='(88,0)';
      BIDIRECTIONAL='TRUE';
      INPUT_LOAD='(-0.01,0.01)';
      OUTPUT_LOAD='(1.0,-1.0)';
      PINUSE='BI';
    'IO89':
      PIN_NUMBER='(89,0)';
      BIDIRECTIONAL='TRUE';
      INPUT_LOAD='(-0.01,0.01)';
      OUTPUT_LOAD='(1.0,-1.0)';
      PINUSE='BI';
    'IO90':
      PIN_NUMBER='(90,0)';
      BIDIRECTIONAL='TRUE';
      INPUT_LOAD='(-0.01,0.01)';
      OUTPUT_LOAD='(1.0,-1.0)';
      PINUSE='BI';
    'IO91':
      PIN_NUMBER='(91,0)';
      BIDIRECTIONAL='TRUE';
      INPUT_LOAD='(-0.01,0.01)';
      OUTPUT_LOAD='(1.0,-1.0)';
      PINUSE='BI';
    'IO92':
      PIN_NUMBER='(92,0)';
      BIDIRECTIONAL='TRUE';
      INPUT_LOAD='(-0.01,0.01)';
      OUTPUT_LOAD='(1.0,-1.0)';
      PINUSE='BI';
    'IO93':
      PIN_NUMBER='(93,0)';
      BIDIRECTIONAL='TRUE';
      INPUT_LOAD='(-0.01,0.01)';
      OUTPUT_LOAD='(1.0,-1.0)';
      PINUSE='BI';
    'IO94':
      PIN_NUMBER='(94,0)';
      BIDIRECTIONAL='TRUE';
      INPUT_LOAD='(-0.01,0.01)';
      OUTPUT_LOAD='(1.0,-1.0)';
      PINUSE='BI';
    'IO95':
      PIN_NUMBER='(95,0)';
      BIDIRECTIONAL='TRUE';
      INPUT_LOAD='(-0.01,0.01)';
      OUTPUT_LOAD='(1.0,-1.0)';
      PINUSE='BI';
    'IO96':
      PIN_NUMBER='(96,0)';
      BIDIRECTIONAL='TRUE';
      INPUT_LOAD='(-0.01,0.01)';
      OUTPUT_LOAD='(1.0,-1.0)';
      PINUSE='BI';
    'IO97':
      PIN_NUMBER='(97,0)';
      BIDIRECTIONAL='TRUE';
      INPUT_LOAD='(-0.01,0.01)';
      OUTPUT_LOAD='(1.0,-1.0)';
      PINUSE='BI';
    'IO98':
      PIN_NUMBER='(98,0)';
      BIDIRECTIONAL='TRUE';
      INPUT_LOAD='(-0.01,0.01)';
      OUTPUT_LOAD='(1.0,-1.0)';
      PINUSE='BI';
    'IO99':
      PIN_NUMBER='(99,0)';
      BIDIRECTIONAL='TRUE';
      INPUT_LOAD='(-0.01,0.01)';
      OUTPUT_LOAD='(1.0,-1.0)';
      PINUSE='BI';
    'IO100':
      PIN_NUMBER='(100,0)';
      BIDIRECTIONAL='TRUE';
      INPUT_LOAD='(-0.01,0.01)';
      OUTPUT_LOAD='(1.0,-1.0)';
      PINUSE='BI';
    'IO101':
      PIN_NUMBER='(0,101)';
      BIDIRECTIONAL='TRUE';
      INPUT_LOAD='(-0.01,0.01)';
      OUTPUT_LOAD='(1.0,-1.0)';
      PINUSE='BI';
    'IO102':
      PIN_NUMBER='(0,102)';
      BIDIRECTIONAL='TRUE';
      INPUT_LOAD='(-0.01,0.01)';
      OUTPUT_LOAD='(1.0,-1.0)';
      PINUSE='BI';
    'IO103':
      PIN_NUMBER='(0,103)';
      BIDIRECTIONAL='TRUE';
      INPUT_LOAD='(-0.01,0.01)';
      OUTPUT_LOAD='(1.0,-1.0)';
      PINUSE='BI';
    'IO104':
      PIN_NUMBER='(0,104)';
      BIDIRECTIONAL='TRUE';
      INPUT_LOAD='(-0.01,0.01)';
      OUTPUT_LOAD='(1.0,-1.0)';
      PINUSE='BI';
    'IO105':
      PIN_NUMBER='(0,105)';
      BIDIRECTIONAL='TRUE';
      INPUT_LOAD='(-0.01,0.01)';
      OUTPUT_LOAD='(1.0,-1.0)';
      PINUSE='BI';
    'IO106':
      PIN_NUMBER='(0,106)';
      BIDIRECTIONAL='TRUE';
      INPUT_LOAD='(-0.01,0.01)';
      OUTPUT_LOAD='(1.0,-1.0)';
      PINUSE='BI';
    'IO107':
      PIN_NUMBER='(0,107)';
      BIDIRECTIONAL='TRUE';
      INPUT_LOAD='(-0.01,0.01)';
      OUTPUT_LOAD='(1.0,-1.0)';
      PINUSE='BI';
    'IO108':
      PIN_NUMBER='(0,108)';
      BIDIRECTIONAL='TRUE';
      INPUT_LOAD='(-0.01,0.01)';
      OUTPUT_LOAD='(1.0,-1.0)';
      PINUSE='BI';
    'IO109':
      PIN_NUMBER='(0,109)';
      BIDIRECTIONAL='TRUE';
      INPUT_LOAD='(-0.01,0.01)';
      OUTPUT_LOAD='(1.0,-1.0)';
      PINUSE='BI';
    'IO110':
      PIN_NUMBER='(0,110)';
      BIDIRECTIONAL='TRUE';
      INPUT_LOAD='(-0.01,0.01)';
      OUTPUT_LOAD='(1.0,-1.0)';
      PINUSE='BI';
    'IO111':
      PIN_NUMBER='(0,111)';
      BIDIRECTIONAL='TRUE';
      INPUT_LOAD='(-0.01,0.01)';
      OUTPUT_LOAD='(1.0,-1.0)';
      PINUSE='BI';
    'IO112':
      PIN_NUMBER='(0,112)';
      BIDIRECTIONAL='TRUE';
      INPUT_LOAD='(-0.01,0.01)';
      OUTPUT_LOAD='(1.0,-1.0)';
      PINUSE='BI';
    'IO113':
      PIN_NUMBER='(0,113)';
      BIDIRECTIONAL='TRUE';
      INPUT_LOAD='(-0.01,0.01)';
      OUTPUT_LOAD='(1.0,-1.0)';
      PINUSE='BI';
    'IO114':
      PIN_NUMBER='(0,114)';
      BIDIRECTIONAL='TRUE';
      INPUT_LOAD='(-0.01,0.01)';
      OUTPUT_LOAD='(1.0,-1.0)';
      PINUSE='BI';
    'IO115':
      PIN_NUMBER='(0,115)';
      BIDIRECTIONAL='TRUE';
      INPUT_LOAD='(-0.01,0.01)';
      OUTPUT_LOAD='(1.0,-1.0)';
      PINUSE='BI';
    'IO116':
      PIN_NUMBER='(0,116)';
      BIDIRECTIONAL='TRUE';
      INPUT_LOAD='(-0.01,0.01)';
      OUTPUT_LOAD='(1.0,-1.0)';
      PINUSE='BI';
    'IO117':
      PIN_NUMBER='(0,117)';
      BIDIRECTIONAL='TRUE';
      INPUT_LOAD='(-0.01,0.01)';
      OUTPUT_LOAD='(1.0,-1.0)';
      PINUSE='BI';
    'IO118':
      PIN_NUMBER='(0,118)';
      BIDIRECTIONAL='TRUE';
      INPUT_LOAD='(-0.01,0.01)';
      OUTPUT_LOAD='(1.0,-1.0)';
      PINUSE='BI';
    'IO119':
      PIN_NUMBER='(0,119)';
      BIDIRECTIONAL='TRUE';
      INPUT_LOAD='(-0.01,0.01)';
      OUTPUT_LOAD='(1.0,-1.0)';
      PINUSE='BI';
    'IO120':
      PIN_NUMBER='(0,120)';
      BIDIRECTIONAL='TRUE';
      INPUT_LOAD='(-0.01,0.01)';
      OUTPUT_LOAD='(1.0,-1.0)';
      PINUSE='BI';
    'IO121':
      PIN_NUMBER='(0,121)';
      BIDIRECTIONAL='TRUE';
      INPUT_LOAD='(-0.01,0.01)';
      OUTPUT_LOAD='(1.0,-1.0)';
      PINUSE='BI';
    'IO122':
      PIN_NUMBER='(0,122)';
      BIDIRECTIONAL='TRUE';
      INPUT_LOAD='(-0.01,0.01)';
      OUTPUT_LOAD='(1.0,-1.0)';
      PINUSE='BI';
    'IO123':
      PIN_NUMBER='(0,123)';
      BIDIRECTIONAL='TRUE';
      INPUT_LOAD='(-0.01,0.01)';
      OUTPUT_LOAD='(1.0,-1.0)';
      PINUSE='BI';
    'IO124':
      PIN_NUMBER='(0,124)';
      BIDIRECTIONAL='TRUE';
      INPUT_LOAD='(-0.01,0.01)';
      OUTPUT_LOAD='(1.0,-1.0)';
      PINUSE='BI';
    'IO125':
      PIN_NUMBER='(0,125)';
      BIDIRECTIONAL='TRUE';
      INPUT_LOAD='(-0.01,0.01)';
      OUTPUT_LOAD='(1.0,-1.0)';
      PINUSE='BI';
    'IO126':
      PIN_NUMBER='(0,126)';
      BIDIRECTIONAL='TRUE';
      INPUT_LOAD='(-0.01,0.01)';
      OUTPUT_LOAD='(1.0,-1.0)';
      PINUSE='BI';
    'IO127':
      PIN_NUMBER='(0,127)';
      BIDIRECTIONAL='TRUE';
      INPUT_LOAD='(-0.01,0.01)';
      OUTPUT_LOAD='(1.0,-1.0)';
      PINUSE='BI';
    'IO128':
      PIN_NUMBER='(0,128)';
      BIDIRECTIONAL='TRUE';
      INPUT_LOAD='(-0.01,0.01)';
      OUTPUT_LOAD='(1.0,-1.0)';
      PINUSE='BI';
    'IO129':
      PIN_NUMBER='(0,129)';
      BIDIRECTIONAL='TRUE';
      INPUT_LOAD='(-0.01,0.01)';
      OUTPUT_LOAD='(1.0,-1.0)';
      PINUSE='BI';
    'IO130':
      PIN_NUMBER='(0,130)';
      BIDIRECTIONAL='TRUE';
      INPUT_LOAD='(-0.01,0.01)';
      OUTPUT_LOAD='(1.0,-1.0)';
      PINUSE='BI';
    'IO131':
      PIN_NUMBER='(0,131)';
      BIDIRECTIONAL='TRUE';
      INPUT_LOAD='(-0.01,0.01)';
      OUTPUT_LOAD='(1.0,-1.0)';
      PINUSE='BI';
    'IO132':
      PIN_NUMBER='(0,132)';
      BIDIRECTIONAL='TRUE';
      INPUT_LOAD='(-0.01,0.01)';
      OUTPUT_LOAD='(1.0,-1.0)';
      PINUSE='BI';
    'IO133':
      PIN_NUMBER='(0,133)';
      BIDIRECTIONAL='TRUE';
      INPUT_LOAD='(-0.01,0.01)';
      OUTPUT_LOAD='(1.0,-1.0)';
      PINUSE='BI';
    'IO134':
      PIN_NUMBER='(0,134)';
      BIDIRECTIONAL='TRUE';
      INPUT_LOAD='(-0.01,0.01)';
      OUTPUT_LOAD='(1.0,-1.0)';
      PINUSE='BI';
    'IO135':
      PIN_NUMBER='(0,135)';
      BIDIRECTIONAL='TRUE';
      INPUT_LOAD='(-0.01,0.01)';
      OUTPUT_LOAD='(1.0,-1.0)';
      PINUSE='BI';
    'IO136':
      PIN_NUMBER='(0,136)';
      BIDIRECTIONAL='TRUE';
      INPUT_LOAD='(-0.01,0.01)';
      OUTPUT_LOAD='(1.0,-1.0)';
      PINUSE='BI';
    'IO137':
      PIN_NUMBER='(0,137)';
      BIDIRECTIONAL='TRUE';
      INPUT_LOAD='(-0.01,0.01)';
      OUTPUT_LOAD='(1.0,-1.0)';
      PINUSE='BI';
    'IO138':
      PIN_NUMBER='(0,138)';
      BIDIRECTIONAL='TRUE';
      INPUT_LOAD='(-0.01,0.01)';
      OUTPUT_LOAD='(1.0,-1.0)';
      PINUSE='BI';
    'IO139':
      PIN_NUMBER='(0,139)';
      BIDIRECTIONAL='TRUE';
      INPUT_LOAD='(-0.01,0.01)';
      OUTPUT_LOAD='(1.0,-1.0)';
      PINUSE='BI';
    'IO140':
      PIN_NUMBER='(0,140)';
      BIDIRECTIONAL='TRUE';
      INPUT_LOAD='(-0.01,0.01)';
      OUTPUT_LOAD='(1.0,-1.0)';
      PINUSE='BI';
    'IO141':
      PIN_NUMBER='(0,141)';
      BIDIRECTIONAL='TRUE';
      INPUT_LOAD='(-0.01,0.01)';
      OUTPUT_LOAD='(1.0,-1.0)';
      PINUSE='BI';
    'IO142':
      PIN_NUMBER='(0,142)';
      BIDIRECTIONAL='TRUE';
      INPUT_LOAD='(-0.01,0.01)';
      OUTPUT_LOAD='(1.0,-1.0)';
      PINUSE='BI';
    'IO143':
      PIN_NUMBER='(0,143)';
      BIDIRECTIONAL='TRUE';
      INPUT_LOAD='(-0.01,0.01)';
      OUTPUT_LOAD='(1.0,-1.0)';
      PINUSE='BI';
    'IO144':
      PIN_NUMBER='(0,144)';
      BIDIRECTIONAL='TRUE';
      INPUT_LOAD='(-0.01,0.01)';
      OUTPUT_LOAD='(1.0,-1.0)';
      PINUSE='BI';
    'IO145':
      PIN_NUMBER='(0,145)';
      BIDIRECTIONAL='TRUE';
      INPUT_LOAD='(-0.01,0.01)';
      OUTPUT_LOAD='(1.0,-1.0)';
      PINUSE='BI';
    'IO146':
      PIN_NUMBER='(0,146)';
      BIDIRECTIONAL='TRUE';
      INPUT_LOAD='(-0.01,0.01)';
      OUTPUT_LOAD='(1.0,-1.0)';
      PINUSE='BI';
    'IO147':
      PIN_NUMBER='(0,147)';
      BIDIRECTIONAL='TRUE';
      INPUT_LOAD='(-0.01,0.01)';
      OUTPUT_LOAD='(1.0,-1.0)';
      PINUSE='BI';
    'IO148':
      PIN_NUMBER='(0,148)';
      BIDIRECTIONAL='TRUE';
      INPUT_LOAD='(-0.01,0.01)';
      OUTPUT_LOAD='(1.0,-1.0)';
      PINUSE='BI';
    'IO149':
      PIN_NUMBER='(0,149)';
      BIDIRECTIONAL='TRUE';
      INPUT_LOAD='(-0.01,0.01)';
      OUTPUT_LOAD='(1.0,-1.0)';
      PINUSE='BI';
    'IO150':
      PIN_NUMBER='(0,150)';
      BIDIRECTIONAL='TRUE';
      INPUT_LOAD='(-0.01,0.01)';
      OUTPUT_LOAD='(1.0,-1.0)';
      PINUSE='BI';
    'IO151':
      PIN_NUMBER='(0,151)';
      BIDIRECTIONAL='TRUE';
      INPUT_LOAD='(-0.01,0.01)';
      OUTPUT_LOAD='(1.0,-1.0)';
      PINUSE='BI';
    'IO152':
      PIN_NUMBER='(0,152)';
      BIDIRECTIONAL='TRUE';
      INPUT_LOAD='(-0.01,0.01)';
      OUTPUT_LOAD='(1.0,-1.0)';
      PINUSE='BI';
    'IO153':
      PIN_NUMBER='(0,153)';
      BIDIRECTIONAL='TRUE';
      INPUT_LOAD='(-0.01,0.01)';
      OUTPUT_LOAD='(1.0,-1.0)';
      PINUSE='BI';
    'IO154':
      PIN_NUMBER='(0,154)';
      BIDIRECTIONAL='TRUE';
      INPUT_LOAD='(-0.01,0.01)';
      OUTPUT_LOAD='(1.0,-1.0)';
      PINUSE='BI';
    'IO155':
      PIN_NUMBER='(0,155)';
      BIDIRECTIONAL='TRUE';
      INPUT_LOAD='(-0.01,0.01)';
      OUTPUT_LOAD='(1.0,-1.0)';
      PINUSE='BI';
    'IO156':
      PIN_NUMBER='(0,156)';
      BIDIRECTIONAL='TRUE';
      INPUT_LOAD='(-0.01,0.01)';
      OUTPUT_LOAD='(1.0,-1.0)';
      PINUSE='BI';
    'IO157':
      PIN_NUMBER='(0,157)';
      BIDIRECTIONAL='TRUE';
      INPUT_LOAD='(-0.01,0.01)';
      OUTPUT_LOAD='(1.0,-1.0)';
      PINUSE='BI';
    'IO158':
      PIN_NUMBER='(0,158)';
      BIDIRECTIONAL='TRUE';
      INPUT_LOAD='(-0.01,0.01)';
      OUTPUT_LOAD='(1.0,-1.0)';
      PINUSE='BI';
    'IO159':
      PIN_NUMBER='(0,159)';
      BIDIRECTIONAL='TRUE';
      INPUT_LOAD='(-0.01,0.01)';
      OUTPUT_LOAD='(1.0,-1.0)';
      PINUSE='BI';
    'IO160':
      PIN_NUMBER='(0,160)';
      BIDIRECTIONAL='TRUE';
      INPUT_LOAD='(-0.01,0.01)';
      OUTPUT_LOAD='(1.0,-1.0)';
      PINUSE='BI';
    'IO161':
      PIN_NUMBER='(0,161)';
      BIDIRECTIONAL='TRUE';
      INPUT_LOAD='(-0.01,0.01)';
      OUTPUT_LOAD='(1.0,-1.0)';
      PINUSE='BI';
    'IO162':
      PIN_NUMBER='(0,162)';
      BIDIRECTIONAL='TRUE';
      INPUT_LOAD='(-0.01,0.01)';
      OUTPUT_LOAD='(1.0,-1.0)';
      PINUSE='BI';
    'IO163':
      PIN_NUMBER='(0,163)';
      BIDIRECTIONAL='TRUE';
      INPUT_LOAD='(-0.01,0.01)';
      OUTPUT_LOAD='(1.0,-1.0)';
      PINUSE='BI';
    'IO164':
      PIN_NUMBER='(0,164)';
      BIDIRECTIONAL='TRUE';
      INPUT_LOAD='(-0.01,0.01)';
      OUTPUT_LOAD='(1.0,-1.0)';
      PINUSE='BI';
    'IO165':
      PIN_NUMBER='(0,165)';
      BIDIRECTIONAL='TRUE';
      INPUT_LOAD='(-0.01,0.01)';
      OUTPUT_LOAD='(1.0,-1.0)';
      PINUSE='BI';
    'IO166':
      PIN_NUMBER='(0,166)';
      BIDIRECTIONAL='TRUE';
      INPUT_LOAD='(-0.01,0.01)';
      OUTPUT_LOAD='(1.0,-1.0)';
      PINUSE='BI';
    'IO167':
      PIN_NUMBER='(0,167)';
      BIDIRECTIONAL='TRUE';
      INPUT_LOAD='(-0.01,0.01)';
      OUTPUT_LOAD='(1.0,-1.0)';
      PINUSE='BI';
    'IO168':
      PIN_NUMBER='(0,168)';
      BIDIRECTIONAL='TRUE';
      INPUT_LOAD='(-0.01,0.01)';
      OUTPUT_LOAD='(1.0,-1.0)';
      PINUSE='BI';
    'IO169':
      PIN_NUMBER='(0,169)';
      BIDIRECTIONAL='TRUE';
      INPUT_LOAD='(-0.01,0.01)';
      OUTPUT_LOAD='(1.0,-1.0)';
      PINUSE='BI';
    'IO170':
      PIN_NUMBER='(0,170)';
      BIDIRECTIONAL='TRUE';
      INPUT_LOAD='(-0.01,0.01)';
      OUTPUT_LOAD='(1.0,-1.0)';
      PINUSE='BI';
    'IO171':
      PIN_NUMBER='(0,171)';
      BIDIRECTIONAL='TRUE';
      INPUT_LOAD='(-0.01,0.01)';
      OUTPUT_LOAD='(1.0,-1.0)';
      PINUSE='BI';
    'IO172':
      PIN_NUMBER='(0,172)';
      BIDIRECTIONAL='TRUE';
      INPUT_LOAD='(-0.01,0.01)';
      OUTPUT_LOAD='(1.0,-1.0)';
      PINUSE='BI';
    'IO173':
      PIN_NUMBER='(0,173)';
      BIDIRECTIONAL='TRUE';
      INPUT_LOAD='(-0.01,0.01)';
      OUTPUT_LOAD='(1.0,-1.0)';
      PINUSE='BI';
    'IO174':
      PIN_NUMBER='(0,174)';
      BIDIRECTIONAL='TRUE';
      INPUT_LOAD='(-0.01,0.01)';
      OUTPUT_LOAD='(1.0,-1.0)';
      PINUSE='BI';
    'IO175':
      PIN_NUMBER='(0,175)';
      BIDIRECTIONAL='TRUE';
      INPUT_LOAD='(-0.01,0.01)';
      OUTPUT_LOAD='(1.0,-1.0)';
      PINUSE='BI';
    'IO176':
      PIN_NUMBER='(0,176)';
      BIDIRECTIONAL='TRUE';
      INPUT_LOAD='(-0.01,0.01)';
      OUTPUT_LOAD='(1.0,-1.0)';
      PINUSE='BI';
    'IO177':
      PIN_NUMBER='(0,177)';
      BIDIRECTIONAL='TRUE';
      INPUT_LOAD='(-0.01,0.01)';
      OUTPUT_LOAD='(1.0,-1.0)';
      PINUSE='BI';
    'IO178':
      PIN_NUMBER='(0,178)';
      BIDIRECTIONAL='TRUE';
      INPUT_LOAD='(-0.01,0.01)';
      OUTPUT_LOAD='(1.0,-1.0)';
      PINUSE='BI';
    'IO179':
      PIN_NUMBER='(0,179)';
      BIDIRECTIONAL='TRUE';
      INPUT_LOAD='(-0.01,0.01)';
      OUTPUT_LOAD='(1.0,-1.0)';
      PINUSE='BI';
    'IO180':
      PIN_NUMBER='(0,180)';
      BIDIRECTIONAL='TRUE';
      INPUT_LOAD='(-0.01,0.01)';
      OUTPUT_LOAD='(1.0,-1.0)';
      PINUSE='BI';
    'IO181':
      PIN_NUMBER='(0,181)';
      BIDIRECTIONAL='TRUE';
      INPUT_LOAD='(-0.01,0.01)';
      OUTPUT_LOAD='(1.0,-1.0)';
      PINUSE='BI';
    'IO182':
      PIN_NUMBER='(0,182)';
      BIDIRECTIONAL='TRUE';
      INPUT_LOAD='(-0.01,0.01)';
      OUTPUT_LOAD='(1.0,-1.0)';
      PINUSE='BI';
    'IO183':
      PIN_NUMBER='(0,183)';
      BIDIRECTIONAL='TRUE';
      INPUT_LOAD='(-0.01,0.01)';
      OUTPUT_LOAD='(1.0,-1.0)';
      PINUSE='BI';
    'IO184':
      PIN_NUMBER='(0,184)';
      BIDIRECTIONAL='TRUE';
      INPUT_LOAD='(-0.01,0.01)';
      OUTPUT_LOAD='(1.0,-1.0)';
      PINUSE='BI';
    'IO185':
      PIN_NUMBER='(0,185)';
      BIDIRECTIONAL='TRUE';
      INPUT_LOAD='(-0.01,0.01)';
      OUTPUT_LOAD='(1.0,-1.0)';
      PINUSE='BI';
    'IO186':
      PIN_NUMBER='(0,186)';
      BIDIRECTIONAL='TRUE';
      INPUT_LOAD='(-0.01,0.01)';
      OUTPUT_LOAD='(1.0,-1.0)';
      PINUSE='BI';
    'IO187':
      PIN_NUMBER='(0,187)';
      BIDIRECTIONAL='TRUE';
      INPUT_LOAD='(-0.01,0.01)';
      OUTPUT_LOAD='(1.0,-1.0)';
      PINUSE='BI';
    'IO188':
      PIN_NUMBER='(0,188)';
      BIDIRECTIONAL='TRUE';
      INPUT_LOAD='(-0.01,0.01)';
      OUTPUT_LOAD='(1.0,-1.0)';
      PINUSE='BI';
    'IO189':
      PIN_NUMBER='(0,189)';
      BIDIRECTIONAL='TRUE';
      INPUT_LOAD='(-0.01,0.01)';
      OUTPUT_LOAD='(1.0,-1.0)';
      PINUSE='BI';
    'IO190':
      PIN_NUMBER='(0,190)';
      BIDIRECTIONAL='TRUE';
      INPUT_LOAD='(-0.01,0.01)';
      OUTPUT_LOAD='(1.0,-1.0)';
      PINUSE='BI';
    'IO191':
      PIN_NUMBER='(0,191)';
      BIDIRECTIONAL='TRUE';
      INPUT_LOAD='(-0.01,0.01)';
      OUTPUT_LOAD='(1.0,-1.0)';
      PINUSE='BI';
    'IO192':
      PIN_NUMBER='(0,192)';
      BIDIRECTIONAL='TRUE';
      INPUT_LOAD='(-0.01,0.01)';
      OUTPUT_LOAD='(1.0,-1.0)';
      PINUSE='BI';
    'IO193':
      PIN_NUMBER='(0,193)';
      BIDIRECTIONAL='TRUE';
      INPUT_LOAD='(-0.01,0.01)';
      OUTPUT_LOAD='(1.0,-1.0)';
      PINUSE='BI';
    'IO194':
      PIN_NUMBER='(0,194)';
      BIDIRECTIONAL='TRUE';
      INPUT_LOAD='(-0.01,0.01)';
      OUTPUT_LOAD='(1.0,-1.0)';
      PINUSE='BI';
    'IO195':
      PIN_NUMBER='(0,195)';
      BIDIRECTIONAL='TRUE';
      INPUT_LOAD='(-0.01,0.01)';
      OUTPUT_LOAD='(1.0,-1.0)';
      PINUSE='BI';
    'IO196':
      PIN_NUMBER='(0,196)';
      BIDIRECTIONAL='TRUE';
      INPUT_LOAD='(-0.01,0.01)';
      OUTPUT_LOAD='(1.0,-1.0)';
      PINUSE='BI';
    'IO197':
      PIN_NUMBER='(0,197)';
      BIDIRECTIONAL='TRUE';
      INPUT_LOAD='(-0.01,0.01)';
      OUTPUT_LOAD='(1.0,-1.0)';
      PINUSE='BI';
    'IO198':
      PIN_NUMBER='(0,198)';
      BIDIRECTIONAL='TRUE';
      INPUT_LOAD='(-0.01,0.01)';
      OUTPUT_LOAD='(1.0,-1.0)';
      PINUSE='BI';
    'IO199':
      PIN_NUMBER='(0,199)';
      BIDIRECTIONAL='TRUE';
      INPUT_LOAD='(-0.01,0.01)';
      OUTPUT_LOAD='(1.0,-1.0)';
      PINUSE='BI';
    'IO200':
      PIN_NUMBER='(0,200)';
      BIDIRECTIONAL='TRUE';
      INPUT_LOAD='(-0.01,0.01)';
      OUTPUT_LOAD='(1.0,-1.0)';
      PINUSE='BI';
    'MH1':
      PIN_NUMBER='(MH1,0)';
      PIN_TYPE='GROUND';
      NO_LOAD_CHECK='BOTH';
      NO_IO_CHECK='BOTH';
      ALLOW_CONNECT='TRUE';
      PINUSE='UNSPEC';
    'MH2':
      PIN_NUMBER='(MH2,0)';
      PIN_TYPE='GROUND';
      NO_LOAD_CHECK='BOTH';
      NO_IO_CHECK='BOTH';
      ALLOW_CONNECT='TRUE';
      PINUSE='UNSPEC';
  end_pin;
  body
      PART_NAME='SCONN200_H68296001';
      PHYS_DES_PREFIX='J';
      ENVCOMP='';
      PART_NUMBER='H68296-001';
      JEDEC_TYPE='SCONN200_H68296001';
      CLASS='IO';
      DESCRIPTION='CONN,MISC,200P,SAMT HSEC8,VERT RCPT';
      HEIGHT='0.320 IN';
      COMPONENT_TYPE='SMTCONN';
      LPID='3840';
      SPEED_URL='http://speed.intel.com:8081/speed/module/pdm/item/pdm_item_deta~
il_direct.asp?item_cde=H68296-001&item_rev=01&url_param=unused';
      STATUS='';
      RPL='';
      AML='';
      BUS_UNIT='';
      DAYS='';
      PARENT_PART_TYPE='SCONN200_H68296001_SM';
      PARENT_PPT='SCONN200_H68296001';
      PARENT_PPT_PART='SCONN200_H68296001_SM-CONN,H68296-001';
  end_body;
end_primitive;
primitive 'SCONN24_H46321001_SM-SCONN,H46A';
  pin
    'IO1':
      PIN_NUMBER='(1)';
      BIDIRECTIONAL='TRUE';
      INPUT_LOAD='(-0.01,0.01)';
      OUTPUT_LOAD='(1.0,-1.0)';
      PINUSE='BI';
    'IO10':
      PIN_NUMBER='(10)';
      BIDIRECTIONAL='TRUE';
      INPUT_LOAD='(-0.01,0.01)';
      OUTPUT_LOAD='(1.0,-1.0)';
      PINUSE='BI';
    'IO11':
      PIN_NUMBER='(11)';
      BIDIRECTIONAL='TRUE';
      INPUT_LOAD='(-0.01,0.01)';
      OUTPUT_LOAD='(1.0,-1.0)';
      PINUSE='BI';
    'IO12':
      PIN_NUMBER='(12)';
      BIDIRECTIONAL='TRUE';
      INPUT_LOAD='(-0.01,0.01)';
      OUTPUT_LOAD='(1.0,-1.0)';
      PINUSE='BI';
    'IO13':
      PIN_NUMBER='(13)';
      BIDIRECTIONAL='TRUE';
      INPUT_LOAD='(-0.01,0.01)';
      OUTPUT_LOAD='(1.0,-1.0)';
      PINUSE='BI';
    'IO14':
      PIN_NUMBER='(14)';
      BIDIRECTIONAL='TRUE';
      INPUT_LOAD='(-0.01,0.01)';
      OUTPUT_LOAD='(1.0,-1.0)';
      PINUSE='BI';
    'IO15':
      PIN_NUMBER='(15)';
      BIDIRECTIONAL='TRUE';
      INPUT_LOAD='(-0.01,0.01)';
      OUTPUT_LOAD='(1.0,-1.0)';
      PINUSE='BI';
    'IO16':
      PIN_NUMBER='(16)';
      BIDIRECTIONAL='TRUE';
      INPUT_LOAD='(-0.01,0.01)';
      OUTPUT_LOAD='(1.0,-1.0)';
      PINUSE='BI';
    'IO17':
      PIN_NUMBER='(17)';
      BIDIRECTIONAL='TRUE';
      INPUT_LOAD='(-0.01,0.01)';
      OUTPUT_LOAD='(1.0,-1.0)';
      PINUSE='BI';
    'IO18':
      PIN_NUMBER='(18)';
      BIDIRECTIONAL='TRUE';
      INPUT_LOAD='(-0.01,0.01)';
      OUTPUT_LOAD='(1.0,-1.0)';
      PINUSE='BI';
    'IO19':
      PIN_NUMBER='(19)';
      BIDIRECTIONAL='TRUE';
      INPUT_LOAD='(-0.01,0.01)';
      OUTPUT_LOAD='(1.0,-1.0)';
      PINUSE='BI';
    'IO2':
      PIN_NUMBER='(2)';
      BIDIRECTIONAL='TRUE';
      INPUT_LOAD='(-0.01,0.01)';
      OUTPUT_LOAD='(1.0,-1.0)';
      PINUSE='BI';
    'IO20':
      PIN_NUMBER='(20)';
      BIDIRECTIONAL='TRUE';
      INPUT_LOAD='(-0.01,0.01)';
      OUTPUT_LOAD='(1.0,-1.0)';
      PINUSE='BI';
    'IO21':
      PIN_NUMBER='(21)';
      BIDIRECTIONAL='TRUE';
      INPUT_LOAD='(-0.01,0.01)';
      OUTPUT_LOAD='(1.0,-1.0)';
      PINUSE='BI';
    'IO22':
      PIN_NUMBER='(22)';
      BIDIRECTIONAL='TRUE';
      INPUT_LOAD='(-0.01,0.01)';
      OUTPUT_LOAD='(1.0,-1.0)';
      PINUSE='BI';
    'IO23':
      PIN_NUMBER='(23)';
      BIDIRECTIONAL='TRUE';
      INPUT_LOAD='(-0.01,0.01)';
      OUTPUT_LOAD='(1.0,-1.0)';
      PINUSE='BI';
    'IO24':
      PIN_NUMBER='(24)';
      BIDIRECTIONAL='TRUE';
      INPUT_LOAD='(-0.01,0.01)';
      OUTPUT_LOAD='(1.0,-1.0)';
      PINUSE='BI';
    'IO3':
      PIN_NUMBER='(3)';
      BIDIRECTIONAL='TRUE';
      INPUT_LOAD='(-0.01,0.01)';
      OUTPUT_LOAD='(1.0,-1.0)';
      PINUSE='BI';
    'IO4':
      PIN_NUMBER='(4)';
      BIDIRECTIONAL='TRUE';
      INPUT_LOAD='(-0.01,0.01)';
      OUTPUT_LOAD='(1.0,-1.0)';
      PINUSE='BI';
    'IO5':
      PIN_NUMBER='(5)';
      BIDIRECTIONAL='TRUE';
      INPUT_LOAD='(-0.01,0.01)';
      OUTPUT_LOAD='(1.0,-1.0)';
      PINUSE='BI';
    'IO6':
      PIN_NUMBER='(6)';
      BIDIRECTIONAL='TRUE';
      INPUT_LOAD='(-0.01,0.01)';
      OUTPUT_LOAD='(1.0,-1.0)';
      PINUSE='BI';
    'IO7':
      PIN_NUMBER='(7)';
      BIDIRECTIONAL='TRUE';
      INPUT_LOAD='(-0.01,0.01)';
      OUTPUT_LOAD='(1.0,-1.0)';
      PINUSE='BI';
    'IO8':
      PIN_NUMBER='(8)';
      BIDIRECTIONAL='TRUE';
      INPUT_LOAD='(-0.01,0.01)';
      OUTPUT_LOAD='(1.0,-1.0)';
      PINUSE='BI';
    'IO9':
      PIN_NUMBER='(9)';
      BIDIRECTIONAL='TRUE';
      INPUT_LOAD='(-0.01,0.01)';
      OUTPUT_LOAD='(1.0,-1.0)';
      PINUSE='BI';
    'MP1':
      PIN_NUMBER='(MP1)';
      PINUSE='GROUND';
      NO_LOAD_CHECK='Both';
      NO_IO_CHECK='Both';
      NO_ASSERT_CHECK='TRUE';
      NO_DIR_CHECK='TRUE';
      ALLOW_CONNECT='TRUE';
    'MP2':
      PIN_NUMBER='(MP2)';
      PINUSE='GROUND';
      NO_LOAD_CHECK='Both';
      NO_IO_CHECK='Both';
      NO_ASSERT_CHECK='TRUE';
      NO_DIR_CHECK='TRUE';
      ALLOW_CONNECT='TRUE';
  end_pin;
  body
      PART_NAME='SCONN24_H46321001';
      PHYS_DES_PREFIX='J';
      ENVCOMP='';
      PART_NUMBER='H46321-001';
      JEDEC_TYPE='SCONN24_H46321001';
      DESCRIPTION='CONN_HDR,2X12,PLG,VT,1.00MM,SMT,BK';
      CLASS='IC';
      COMPONENT_TYPE='SMTCONN';
      HEIGHT='0.197 IN';
      LPID='3521';
      SPEED_URL='http://speed.intel.com:8081/speed/module/pdm/item/pdm_item_deta~
il_direct.asp?item_cde=H46321-001&item_rev=01&url_param=unused';
      STATUS='';
      RPL='';
      AML='';
      BUS_UNIT='';
      DAYS='';
      PARENT_PART_TYPE='SCONN24_H46321001_SM';
      PARENT_PPT='SCONN24_H46321001';
      PARENT_PPT_PART='SCONN24_H46321001_SM-SCONN,H46321-001';
  end_body;
end_primitive;
primitive 'SCONN288_H44441003_PIP-SCONN,HA';
  pin
    '12V'<1>:
      PIN_NUMBER='(0,0,0,1)';
      PINUSE='POWER';
      NO_LOAD_CHECK='Both';
      NO_IO_CHECK='Both';
      NO_ASSERT_CHECK='TRUE';
      NO_DIR_CHECK='TRUE';
      ALLOW_CONNECT='TRUE';
    '12V'<0>:
      PIN_NUMBER='(0,0,0,145)';
      PINUSE='POWER';
      NO_LOAD_CHECK='Both';
      NO_IO_CHECK='Both';
      NO_ASSERT_CHECK='TRUE';
      NO_DIR_CHECK='TRUE';
      ALLOW_CONNECT='TRUE';
    'A0':
      PIN_NUMBER='(79,0,0,0)';
      BIDIRECTIONAL='TRUE';
      INPUT_LOAD='(-0.01,0.01)';
      OUTPUT_LOAD='(1.0,-1.0)';
      PINUSE='BI';
    'A1':
      PIN_NUMBER='(72,0,0,0)';
      BIDIRECTIONAL='TRUE';
      INPUT_LOAD='(-0.01,0.01)';
      OUTPUT_LOAD='(1.0,-1.0)';
      PINUSE='BI';
    'A10':
      PIN_NUMBER='(225,0,0,0)';
      BIDIRECTIONAL='TRUE';
      INPUT_LOAD='(-0.01,0.01)';
      OUTPUT_LOAD='(1.0,-1.0)';
      PINUSE='BI';
    'A11':
      PIN_NUMBER='(210,0,0,0)';
      BIDIRECTIONAL='TRUE';
      INPUT_LOAD='(-0.01,0.01)';
      OUTPUT_LOAD='(1.0,-1.0)';
      PINUSE='BI';
    'A12':
      PIN_NUMBER='(65,0,0,0)';
      BIDIRECTIONAL='TRUE';
      INPUT_LOAD='(-0.01,0.01)';
      OUTPUT_LOAD='(1.0,-1.0)';
      PINUSE='BI';
    'A13':
      PIN_NUMBER='(232,0,0,0)';
      BIDIRECTIONAL='TRUE';
      INPUT_LOAD='(-0.01,0.01)';
      OUTPUT_LOAD='(1.0,-1.0)';
      PINUSE='BI';
    'A14_WE_N':
      PIN_NUMBER='(228,0,0,0)';
      BIDIRECTIONAL='TRUE';
      INPUT_LOAD='(-0.01,0.01)';
      OUTPUT_LOAD='(1.0,-1.0)';
      PINUSE='BI';
    'A15_CAS_N':
      PIN_NUMBER='(86,0,0,0)';
      BIDIRECTIONAL='TRUE';
      INPUT_LOAD='(-0.01,0.01)';
      OUTPUT_LOAD='(1.0,-1.0)';
      PINUSE='BI';
    'A16_RAS_N':
      PIN_NUMBER='(82,0,0,0)';
      BIDIRECTIONAL='TRUE';
      INPUT_LOAD='(-0.01,0.01)';
      OUTPUT_LOAD='(1.0,-1.0)';
      PINUSE='BI';
    'A17':
      PIN_NUMBER='(234,0,0,0)';
      BIDIRECTIONAL='TRUE';
      INPUT_LOAD='(-0.01,0.01)';
      OUTPUT_LOAD='(1.0,-1.0)';
      PINUSE='BI';
    'A2':
      PIN_NUMBER='(216,0,0,0)';
      BIDIRECTIONAL='TRUE';
      INPUT_LOAD='(-0.01,0.01)';
      OUTPUT_LOAD='(1.0,-1.0)';
      PINUSE='BI';
    'A3':
      PIN_NUMBER='(71,0,0,0)';
      BIDIRECTIONAL='TRUE';
      INPUT_LOAD='(-0.01,0.01)';
      OUTPUT_LOAD='(1.0,-1.0)';
      PINUSE='BI';
    'A4':
      PIN_NUMBER='(214,0,0,0)';
      BIDIRECTIONAL='TRUE';
      INPUT_LOAD='(-0.01,0.01)';
      OUTPUT_LOAD='(1.0,-1.0)';
      PINUSE='BI';
    'A5':
      PIN_NUMBER='(213,0,0,0)';
      BIDIRECTIONAL='TRUE';
      INPUT_LOAD='(-0.01,0.01)';
      OUTPUT_LOAD='(1.0,-1.0)';
      PINUSE='BI';
    'A6':
      PIN_NUMBER='(69,0,0,0)';
      BIDIRECTIONAL='TRUE';
      INPUT_LOAD='(-0.01,0.01)';
      OUTPUT_LOAD='(1.0,-1.0)';
      PINUSE='BI';
    'A7':
      PIN_NUMBER='(211,0,0,0)';
      BIDIRECTIONAL='TRUE';
      INPUT_LOAD='(-0.01,0.01)';
      OUTPUT_LOAD='(1.0,-1.0)';
      PINUSE='BI';
    'A8':
      PIN_NUMBER='(68,0,0,0)';
      BIDIRECTIONAL='TRUE';
      INPUT_LOAD='(-0.01,0.01)';
      OUTPUT_LOAD='(1.0,-1.0)';
      PINUSE='BI';
    'A9':
      PIN_NUMBER='(66,0,0,0)';
      BIDIRECTIONAL='TRUE';
      INPUT_LOAD='(-0.01,0.01)';
      OUTPUT_LOAD='(1.0,-1.0)';
      PINUSE='BI';
    'ACT_N':
      PIN_NUMBER='(62,0,0,0)';
      BIDIRECTIONAL='TRUE';
      INPUT_LOAD='(-0.01,0.01)';
      OUTPUT_LOAD='(1.0,-1.0)';
      PINUSE='BI';
    'ALERT_N':
      PIN_NUMBER='(208,0,0,0)';
      BIDIRECTIONAL='TRUE';
      INPUT_LOAD='(-0.01,0.01)';
      OUTPUT_LOAD='(1.0,-1.0)';
      PINUSE='BI';
    'BA'<1>:
      PIN_NUMBER='(224,0,0,0)';
      BIDIRECTIONAL='TRUE';
      INPUT_LOAD='(-0.01,0.01)';
      OUTPUT_LOAD='(1.0,-1.0)';
      PINUSE='BI';
    'BA'<0>:
      PIN_NUMBER='(81,0,0,0)';
      BIDIRECTIONAL='TRUE';
      INPUT_LOAD='(-0.01,0.01)';
      OUTPUT_LOAD='(1.0,-1.0)';
      PINUSE='BI';
    'BG'<1>:
      PIN_NUMBER='(207,0,0,0)';
      BIDIRECTIONAL='TRUE';
      INPUT_LOAD='(-0.01,0.01)';
      OUTPUT_LOAD='(1.0,-1.0)';
      PINUSE='BI';
    'BG'<0>:
      PIN_NUMBER='(63,0,0,0)';
      BIDIRECTIONAL='TRUE';
      INPUT_LOAD='(-0.01,0.01)';
      OUTPUT_LOAD='(1.0,-1.0)';
      PINUSE='BI';
    'C'<2>:
      PIN_NUMBER='(235,0,0,0)';
      BIDIRECTIONAL='TRUE';
      INPUT_LOAD='(-0.01,0.01)';
      OUTPUT_LOAD='(1.0,-1.0)';
      PINUSE='BI';
    'CB'<7>:
      PIN_NUMBER='(199,0,0,0)';
      BIDIRECTIONAL='TRUE';
      INPUT_LOAD='(-0.01,0.01)';
      OUTPUT_LOAD='(1.0,-1.0)';
      PINUSE='BI';
    'CB'<6>:
      PIN_NUMBER='(54,0,0,0)';
      BIDIRECTIONAL='TRUE';
      INPUT_LOAD='(-0.01,0.01)';
      OUTPUT_LOAD='(1.0,-1.0)';
      PINUSE='BI';
    'CB'<5>:
      PIN_NUMBER='(192,0,0,0)';
      BIDIRECTIONAL='TRUE';
      INPUT_LOAD='(-0.01,0.01)';
      OUTPUT_LOAD='(1.0,-1.0)';
      PINUSE='BI';
    'CB'<4>:
      PIN_NUMBER='(47,0,0,0)';
      BIDIRECTIONAL='TRUE';
      INPUT_LOAD='(-0.01,0.01)';
      OUTPUT_LOAD='(1.0,-1.0)';
      PINUSE='BI';
    'CB'<3>:
      PIN_NUMBER='(201,0,0,0)';
      BIDIRECTIONAL='TRUE';
      INPUT_LOAD='(-0.01,0.01)';
      OUTPUT_LOAD='(1.0,-1.0)';
      PINUSE='BI';
    'CB'<2>:
      PIN_NUMBER='(56,0,0,0)';
      BIDIRECTIONAL='TRUE';
      INPUT_LOAD='(-0.01,0.01)';
      OUTPUT_LOAD='(1.0,-1.0)';
      PINUSE='BI';
    'CB'<1>:
      PIN_NUMBER='(194,0,0,0)';
      BIDIRECTIONAL='TRUE';
      INPUT_LOAD='(-0.01,0.01)';
      OUTPUT_LOAD='(1.0,-1.0)';
      PINUSE='BI';
    'CB'<0>:
      PIN_NUMBER='(49,0,0,0)';
      BIDIRECTIONAL='TRUE';
      INPUT_LOAD='(-0.01,0.01)';
      OUTPUT_LOAD='(1.0,-1.0)';
      PINUSE='BI';
    'CK0N':
      PIN_NUMBER='(75,0,0,0)';
      BIDIRECTIONAL='TRUE';
      INPUT_LOAD='(-0.01,0.01)';
      OUTPUT_LOAD='(1.0,-1.0)';
      PINUSE='BI';
    'CK0P':
      PIN_NUMBER='(74,0,0,0)';
      BIDIRECTIONAL='TRUE';
      INPUT_LOAD='(-0.01,0.01)';
      OUTPUT_LOAD='(1.0,-1.0)';
      PINUSE='BI';
    'CK1N':
      PIN_NUMBER='(219,0,0,0)';
      BIDIRECTIONAL='TRUE';
      INPUT_LOAD='(-0.01,0.01)';
      OUTPUT_LOAD='(1.0,-1.0)';
      PINUSE='BI';
    'CK1P':
      PIN_NUMBER='(218,0,0,0)';
      BIDIRECTIONAL='TRUE';
      INPUT_LOAD='(-0.01,0.01)';
      OUTPUT_LOAD='(1.0,-1.0)';
      PINUSE='BI';
    'CKE'<1>:
      PIN_NUMBER='(203,0,0,0)';
      BIDIRECTIONAL='TRUE';
      INPUT_LOAD='(-0.01,0.01)';
      OUTPUT_LOAD='(1.0,-1.0)';
      PINUSE='BI';
    'CKE'<0>:
      PIN_NUMBER='(60,0,0,0)';
      BIDIRECTIONAL='TRUE';
      INPUT_LOAD='(-0.01,0.01)';
      OUTPUT_LOAD='(1.0,-1.0)';
      PINUSE='BI';
    'DQ'<63>:
      PIN_NUMBER='(280,0,0,0)';
      BIDIRECTIONAL='TRUE';
      INPUT_LOAD='(-0.01,0.01)';
      OUTPUT_LOAD='(1.0,-1.0)';
      PINUSE='BI';
    'DQ'<62>:
      PIN_NUMBER='(135,0,0,0)';
      BIDIRECTIONAL='TRUE';
      INPUT_LOAD='(-0.01,0.01)';
      OUTPUT_LOAD='(1.0,-1.0)';
      PINUSE='BI';
    'DQ'<61>:
      PIN_NUMBER='(273,0,0,0)';
      BIDIRECTIONAL='TRUE';
      INPUT_LOAD='(-0.01,0.01)';
      OUTPUT_LOAD='(1.0,-1.0)';
      PINUSE='BI';
    'DQ'<60>:
      PIN_NUMBER='(128,0,0,0)';
      BIDIRECTIONAL='TRUE';
      INPUT_LOAD='(-0.01,0.01)';
      OUTPUT_LOAD='(1.0,-1.0)';
      PINUSE='BI';
    'DQ'<59>:
      PIN_NUMBER='(282,0,0,0)';
      BIDIRECTIONAL='TRUE';
      INPUT_LOAD='(-0.01,0.01)';
      OUTPUT_LOAD='(1.0,-1.0)';
      PINUSE='BI';
    'DQ'<58>:
      PIN_NUMBER='(137,0,0,0)';
      BIDIRECTIONAL='TRUE';
      INPUT_LOAD='(-0.01,0.01)';
      OUTPUT_LOAD='(1.0,-1.0)';
      PINUSE='BI';
    'DQ'<57>:
      PIN_NUMBER='(275,0,0,0)';
      BIDIRECTIONAL='TRUE';
      INPUT_LOAD='(-0.01,0.01)';
      OUTPUT_LOAD='(1.0,-1.0)';
      PINUSE='BI';
    'DQ'<56>:
      PIN_NUMBER='(130,0,0,0)';
      BIDIRECTIONAL='TRUE';
      INPUT_LOAD='(-0.01,0.01)';
      OUTPUT_LOAD='(1.0,-1.0)';
      PINUSE='BI';
    'DQ'<55>:
      PIN_NUMBER='(269,0,0,0)';
      BIDIRECTIONAL='TRUE';
      INPUT_LOAD='(-0.01,0.01)';
      OUTPUT_LOAD='(1.0,-1.0)';
      PINUSE='BI';
    'DQ'<54>:
      PIN_NUMBER='(124,0,0,0)';
      BIDIRECTIONAL='TRUE';
      INPUT_LOAD='(-0.01,0.01)';
      OUTPUT_LOAD='(1.0,-1.0)';
      PINUSE='BI';
    'DQ'<53>:
      PIN_NUMBER='(262,0,0,0)';
      BIDIRECTIONAL='TRUE';
      INPUT_LOAD='(-0.01,0.01)';
      OUTPUT_LOAD='(1.0,-1.0)';
      PINUSE='BI';
    'DQ'<52>:
      PIN_NUMBER='(117,0,0,0)';
      BIDIRECTIONAL='TRUE';
      INPUT_LOAD='(-0.01,0.01)';
      OUTPUT_LOAD='(1.0,-1.0)';
      PINUSE='BI';
    'DQ'<51>:
      PIN_NUMBER='(271,0,0,0)';
      BIDIRECTIONAL='TRUE';
      INPUT_LOAD='(-0.01,0.01)';
      OUTPUT_LOAD='(1.0,-1.0)';
      PINUSE='BI';
    'DQ'<50>:
      PIN_NUMBER='(126,0,0,0)';
      BIDIRECTIONAL='TRUE';
      INPUT_LOAD='(-0.01,0.01)';
      OUTPUT_LOAD='(1.0,-1.0)';
      PINUSE='BI';
    'DQ'<49>:
      PIN_NUMBER='(264,0,0,0)';
      BIDIRECTIONAL='TRUE';
      INPUT_LOAD='(-0.01,0.01)';
      OUTPUT_LOAD='(1.0,-1.0)';
      PINUSE='BI';
    'DQ'<48>:
      PIN_NUMBER='(119,0,0,0)';
      BIDIRECTIONAL='TRUE';
      INPUT_LOAD='(-0.01,0.01)';
      OUTPUT_LOAD='(1.0,-1.0)';
      PINUSE='BI';
    'DQ'<47>:
      PIN_NUMBER='(258,0,0,0)';
      BIDIRECTIONAL='TRUE';
      INPUT_LOAD='(-0.01,0.01)';
      OUTPUT_LOAD='(1.0,-1.0)';
      PINUSE='BI';
    'DQ'<46>:
      PIN_NUMBER='(113,0,0,0)';
      BIDIRECTIONAL='TRUE';
      INPUT_LOAD='(-0.01,0.01)';
      OUTPUT_LOAD='(1.0,-1.0)';
      PINUSE='BI';
    'DQ'<45>:
      PIN_NUMBER='(251,0,0,0)';
      BIDIRECTIONAL='TRUE';
      INPUT_LOAD='(-0.01,0.01)';
      OUTPUT_LOAD='(1.0,-1.0)';
      PINUSE='BI';
    'DQ'<44>:
      PIN_NUMBER='(106,0,0,0)';
      BIDIRECTIONAL='TRUE';
      INPUT_LOAD='(-0.01,0.01)';
      OUTPUT_LOAD='(1.0,-1.0)';
      PINUSE='BI';
    'DQ'<43>:
      PIN_NUMBER='(260,0,0,0)';
      BIDIRECTIONAL='TRUE';
      INPUT_LOAD='(-0.01,0.01)';
      OUTPUT_LOAD='(1.0,-1.0)';
      PINUSE='BI';
    'DQ'<42>:
      PIN_NUMBER='(115,0,0,0)';
      BIDIRECTIONAL='TRUE';
      INPUT_LOAD='(-0.01,0.01)';
      OUTPUT_LOAD='(1.0,-1.0)';
      PINUSE='BI';
    'DQ'<41>:
      PIN_NUMBER='(253,0,0,0)';
      BIDIRECTIONAL='TRUE';
      INPUT_LOAD='(-0.01,0.01)';
      OUTPUT_LOAD='(1.0,-1.0)';
      PINUSE='BI';
    'DQ'<40>:
      PIN_NUMBER='(108,0,0,0)';
      BIDIRECTIONAL='TRUE';
      INPUT_LOAD='(-0.01,0.01)';
      OUTPUT_LOAD='(1.0,-1.0)';
      PINUSE='BI';
    'DQ'<39>:
      PIN_NUMBER='(247,0,0,0)';
      BIDIRECTIONAL='TRUE';
      INPUT_LOAD='(-0.01,0.01)';
      OUTPUT_LOAD='(1.0,-1.0)';
      PINUSE='BI';
    'DQ'<38>:
      PIN_NUMBER='(102,0,0,0)';
      BIDIRECTIONAL='TRUE';
      INPUT_LOAD='(-0.01,0.01)';
      OUTPUT_LOAD='(1.0,-1.0)';
      PINUSE='BI';
    'DQ'<37>:
      PIN_NUMBER='(240,0,0,0)';
      BIDIRECTIONAL='TRUE';
      INPUT_LOAD='(-0.01,0.01)';
      OUTPUT_LOAD='(1.0,-1.0)';
      PINUSE='BI';
    'DQ'<36>:
      PIN_NUMBER='(95,0,0,0)';
      BIDIRECTIONAL='TRUE';
      INPUT_LOAD='(-0.01,0.01)';
      OUTPUT_LOAD='(1.0,-1.0)';
      PINUSE='BI';
    'DQ'<35>:
      PIN_NUMBER='(249,0,0,0)';
      BIDIRECTIONAL='TRUE';
      INPUT_LOAD='(-0.01,0.01)';
      OUTPUT_LOAD='(1.0,-1.0)';
      PINUSE='BI';
    'DQ'<34>:
      PIN_NUMBER='(104,0,0,0)';
      BIDIRECTIONAL='TRUE';
      INPUT_LOAD='(-0.01,0.01)';
      OUTPUT_LOAD='(1.0,-1.0)';
      PINUSE='BI';
    'DQ'<33>:
      PIN_NUMBER='(242,0,0,0)';
      BIDIRECTIONAL='TRUE';
      INPUT_LOAD='(-0.01,0.01)';
      OUTPUT_LOAD='(1.0,-1.0)';
      PINUSE='BI';
    'DQ'<32>:
      PIN_NUMBER='(97,0,0,0)';
      BIDIRECTIONAL='TRUE';
      INPUT_LOAD='(-0.01,0.01)';
      OUTPUT_LOAD='(1.0,-1.0)';
      PINUSE='BI';
    'DQ'<31>:
      PIN_NUMBER='(188,0,0,0)';
      BIDIRECTIONAL='TRUE';
      INPUT_LOAD='(-0.01,0.01)';
      OUTPUT_LOAD='(1.0,-1.0)';
      PINUSE='BI';
    'DQ'<30>:
      PIN_NUMBER='(43,0,0,0)';
      BIDIRECTIONAL='TRUE';
      INPUT_LOAD='(-0.01,0.01)';
      OUTPUT_LOAD='(1.0,-1.0)';
      PINUSE='BI';
    'DQ'<29>:
      PIN_NUMBER='(181,0,0,0)';
      BIDIRECTIONAL='TRUE';
      INPUT_LOAD='(-0.01,0.01)';
      OUTPUT_LOAD='(1.0,-1.0)';
      PINUSE='BI';
    'DQ'<28>:
      PIN_NUMBER='(36,0,0,0)';
      BIDIRECTIONAL='TRUE';
      INPUT_LOAD='(-0.01,0.01)';
      OUTPUT_LOAD='(1.0,-1.0)';
      PINUSE='BI';
    'DQ'<27>:
      PIN_NUMBER='(190,0,0,0)';
      BIDIRECTIONAL='TRUE';
      INPUT_LOAD='(-0.01,0.01)';
      OUTPUT_LOAD='(1.0,-1.0)';
      PINUSE='BI';
    'DQ'<26>:
      PIN_NUMBER='(45,0,0,0)';
      BIDIRECTIONAL='TRUE';
      INPUT_LOAD='(-0.01,0.01)';
      OUTPUT_LOAD='(1.0,-1.0)';
      PINUSE='BI';
    'DQ'<25>:
      PIN_NUMBER='(183,0,0,0)';
      BIDIRECTIONAL='TRUE';
      INPUT_LOAD='(-0.01,0.01)';
      OUTPUT_LOAD='(1.0,-1.0)';
      PINUSE='BI';
    'DQ'<24>:
      PIN_NUMBER='(38,0,0,0)';
      BIDIRECTIONAL='TRUE';
      INPUT_LOAD='(-0.01,0.01)';
      OUTPUT_LOAD='(1.0,-1.0)';
      PINUSE='BI';
    'DQ'<23>:
      PIN_NUMBER='(177,0,0,0)';
      BIDIRECTIONAL='TRUE';
      INPUT_LOAD='(-0.01,0.01)';
      OUTPUT_LOAD='(1.0,-1.0)';
      PINUSE='BI';
    'DQ'<22>:
      PIN_NUMBER='(32,0,0,0)';
      BIDIRECTIONAL='TRUE';
      INPUT_LOAD='(-0.01,0.01)';
      OUTPUT_LOAD='(1.0,-1.0)';
      PINUSE='BI';
    'DQ'<21>:
      PIN_NUMBER='(170,0,0,0)';
      BIDIRECTIONAL='TRUE';
      INPUT_LOAD='(-0.01,0.01)';
      OUTPUT_LOAD='(1.0,-1.0)';
      PINUSE='BI';
    'DQ'<20>:
      PIN_NUMBER='(25,0,0,0)';
      BIDIRECTIONAL='TRUE';
      INPUT_LOAD='(-0.01,0.01)';
      OUTPUT_LOAD='(1.0,-1.0)';
      PINUSE='BI';
    'DQ'<19>:
      PIN_NUMBER='(179,0,0,0)';
      BIDIRECTIONAL='TRUE';
      INPUT_LOAD='(-0.01,0.01)';
      OUTPUT_LOAD='(1.0,-1.0)';
      PINUSE='BI';
    'DQ'<18>:
      PIN_NUMBER='(34,0,0,0)';
      BIDIRECTIONAL='TRUE';
      INPUT_LOAD='(-0.01,0.01)';
      OUTPUT_LOAD='(1.0,-1.0)';
      PINUSE='BI';
    'DQ'<17>:
      PIN_NUMBER='(172,0,0,0)';
      BIDIRECTIONAL='TRUE';
      INPUT_LOAD='(-0.01,0.01)';
      OUTPUT_LOAD='(1.0,-1.0)';
      PINUSE='BI';
    'DQ'<16>:
      PIN_NUMBER='(27,0,0,0)';
      BIDIRECTIONAL='TRUE';
      INPUT_LOAD='(-0.01,0.01)';
      OUTPUT_LOAD='(1.0,-1.0)';
      PINUSE='BI';
    'DQ'<15>:
      PIN_NUMBER='(166,0,0,0)';
      BIDIRECTIONAL='TRUE';
      INPUT_LOAD='(-0.01,0.01)';
      OUTPUT_LOAD='(1.0,-1.0)';
      PINUSE='BI';
    'DQ'<14>:
      PIN_NUMBER='(21,0,0,0)';
      BIDIRECTIONAL='TRUE';
      INPUT_LOAD='(-0.01,0.01)';
      OUTPUT_LOAD='(1.0,-1.0)';
      PINUSE='BI';
    'DQ'<13>:
      PIN_NUMBER='(159,0,0,0)';
      BIDIRECTIONAL='TRUE';
      INPUT_LOAD='(-0.01,0.01)';
      OUTPUT_LOAD='(1.0,-1.0)';
      PINUSE='BI';
    'DQ'<12>:
      PIN_NUMBER='(14,0,0,0)';
      BIDIRECTIONAL='TRUE';
      INPUT_LOAD='(-0.01,0.01)';
      OUTPUT_LOAD='(1.0,-1.0)';
      PINUSE='BI';
    'DQ'<11>:
      PIN_NUMBER='(168,0,0,0)';
      BIDIRECTIONAL='TRUE';
      INPUT_LOAD='(-0.01,0.01)';
      OUTPUT_LOAD='(1.0,-1.0)';
      PINUSE='BI';
    'DQ'<10>:
      PIN_NUMBER='(23,0,0,0)';
      BIDIRECTIONAL='TRUE';
      INPUT_LOAD='(-0.01,0.01)';
      OUTPUT_LOAD='(1.0,-1.0)';
      PINUSE='BI';
    'DQ'<9>:
      PIN_NUMBER='(161,0,0,0)';
      BIDIRECTIONAL='TRUE';
      INPUT_LOAD='(-0.01,0.01)';
      OUTPUT_LOAD='(1.0,-1.0)';
      PINUSE='BI';
    'DQ'<8>:
      PIN_NUMBER='(16,0,0,0)';
      BIDIRECTIONAL='TRUE';
      INPUT_LOAD='(-0.01,0.01)';
      OUTPUT_LOAD='(1.0,-1.0)';
      PINUSE='BI';
    'DQ'<7>:
      PIN_NUMBER='(155,0,0,0)';
      BIDIRECTIONAL='TRUE';
      INPUT_LOAD='(-0.01,0.01)';
      OUTPUT_LOAD='(1.0,-1.0)';
      PINUSE='BI';
    'DQ'<6>:
      PIN_NUMBER='(10,0,0,0)';
      BIDIRECTIONAL='TRUE';
      INPUT_LOAD='(-0.01,0.01)';
      OUTPUT_LOAD='(1.0,-1.0)';
      PINUSE='BI';
    'DQ'<5>:
      PIN_NUMBER='(148,0,0,0)';
      BIDIRECTIONAL='TRUE';
      INPUT_LOAD='(-0.01,0.01)';
      OUTPUT_LOAD='(1.0,-1.0)';
      PINUSE='BI';
    'DQ'<4>:
      PIN_NUMBER='(3,0,0,0)';
      BIDIRECTIONAL='TRUE';
      INPUT_LOAD='(-0.01,0.01)';
      OUTPUT_LOAD='(1.0,-1.0)';
      PINUSE='BI';
    'DQ'<3>:
      PIN_NUMBER='(157,0,0,0)';
      BIDIRECTIONAL='TRUE';
      INPUT_LOAD='(-0.01,0.01)';
      OUTPUT_LOAD='(1.0,-1.0)';
      PINUSE='BI';
    'DQ'<2>:
      PIN_NUMBER='(12,0,0,0)';
      BIDIRECTIONAL='TRUE';
      INPUT_LOAD='(-0.01,0.01)';
      OUTPUT_LOAD='(1.0,-1.0)';
      PINUSE='BI';
    'DQ'<1>:
      PIN_NUMBER='(150,0,0,0)';
      BIDIRECTIONAL='TRUE';
      INPUT_LOAD='(-0.01,0.01)';
      OUTPUT_LOAD='(1.0,-1.0)';
      PINUSE='BI';
    'DQ'<0>:
      PIN_NUMBER='(5,0,0,0)';
      BIDIRECTIONAL='TRUE';
      INPUT_LOAD='(-0.01,0.01)';
      OUTPUT_LOAD='(1.0,-1.0)';
      PINUSE='BI';
    'DQS0N':
      PIN_NUMBER='(0,152,0,0)';
      BIDIRECTIONAL='TRUE';
      INPUT_LOAD='(-0.01,0.01)';
      OUTPUT_LOAD='(1.0,-1.0)';
      PINUSE='BI';
    'DQS0P':
      PIN_NUMBER='(0,153,0,0)';
      BIDIRECTIONAL='TRUE';
      INPUT_LOAD='(-0.01,0.01)';
      OUTPUT_LOAD='(1.0,-1.0)';
      PINUSE='BI';
    'DQS10N':
      PIN_NUMBER='(0,19,0,0)';
      BIDIRECTIONAL='TRUE';
      INPUT_LOAD='(-0.01,0.01)';
      OUTPUT_LOAD='(1.0,-1.0)';
      PINUSE='BI';
    'DQS10P':
      PIN_NUMBER='(0,18,0,0)';
      BIDIRECTIONAL='TRUE';
      INPUT_LOAD='(-0.01,0.01)';
      OUTPUT_LOAD='(1.0,-1.0)';
      PINUSE='BI';
    'DQS11N':
      PIN_NUMBER='(0,30,0,0)';
      BIDIRECTIONAL='TRUE';
      INPUT_LOAD='(-0.01,0.01)';
      OUTPUT_LOAD='(1.0,-1.0)';
      PINUSE='BI';
    'DQS11P':
      PIN_NUMBER='(0,29,0,0)';
      BIDIRECTIONAL='TRUE';
      INPUT_LOAD='(-0.01,0.01)';
      OUTPUT_LOAD='(1.0,-1.0)';
      PINUSE='BI';
    'DQS12N':
      PIN_NUMBER='(0,41,0,0)';
      BIDIRECTIONAL='TRUE';
      INPUT_LOAD='(-0.01,0.01)';
      OUTPUT_LOAD='(1.0,-1.0)';
      PINUSE='BI';
    'DQS12P':
      PIN_NUMBER='(0,40,0,0)';
      BIDIRECTIONAL='TRUE';
      INPUT_LOAD='(-0.01,0.01)';
      OUTPUT_LOAD='(1.0,-1.0)';
      PINUSE='BI';
    'DQS13N':
      PIN_NUMBER='(0,100,0,0)';
      BIDIRECTIONAL='TRUE';
      INPUT_LOAD='(-0.01,0.01)';
      OUTPUT_LOAD='(1.0,-1.0)';
      PINUSE='BI';
    'DQS13P':
      PIN_NUMBER='(0,99,0,0)';
      BIDIRECTIONAL='TRUE';
      INPUT_LOAD='(-0.01,0.01)';
      OUTPUT_LOAD='(1.0,-1.0)';
      PINUSE='BI';
    'DQS14N':
      PIN_NUMBER='(0,111,0,0)';
      BIDIRECTIONAL='TRUE';
      INPUT_LOAD='(-0.01,0.01)';
      OUTPUT_LOAD='(1.0,-1.0)';
      PINUSE='BI';
    'DQS14P':
      PIN_NUMBER='(0,110,0,0)';
      BIDIRECTIONAL='TRUE';
      INPUT_LOAD='(-0.01,0.01)';
      OUTPUT_LOAD='(1.0,-1.0)';
      PINUSE='BI';
    'DQS15N':
      PIN_NUMBER='(0,122,0,0)';
      BIDIRECTIONAL='TRUE';
      INPUT_LOAD='(-0.01,0.01)';
      OUTPUT_LOAD='(1.0,-1.0)';
      PINUSE='BI';
    'DQS15P':
      PIN_NUMBER='(0,121,0,0)';
      BIDIRECTIONAL='TRUE';
      INPUT_LOAD='(-0.01,0.01)';
      OUTPUT_LOAD='(1.0,-1.0)';
      PINUSE='BI';
    'DQS16N':
      PIN_NUMBER='(0,133,0,0)';
      BIDIRECTIONAL='TRUE';
      INPUT_LOAD='(-0.01,0.01)';
      OUTPUT_LOAD='(1.0,-1.0)';
      PINUSE='BI';
    'DQS16P':
      PIN_NUMBER='(0,132,0,0)';
      BIDIRECTIONAL='TRUE';
      INPUT_LOAD='(-0.01,0.01)';
      OUTPUT_LOAD='(1.0,-1.0)';
      PINUSE='BI';
    'DQS17N':
      PIN_NUMBER='(0,52,0,0)';
      BIDIRECTIONAL='TRUE';
      INPUT_LOAD='(-0.01,0.01)';
      OUTPUT_LOAD='(1.0,-1.0)';
      PINUSE='BI';
    'DQS17P':
      PIN_NUMBER='(0,51,0,0)';
      BIDIRECTIONAL='TRUE';
      INPUT_LOAD='(-0.01,0.01)';
      OUTPUT_LOAD='(1.0,-1.0)';
      PINUSE='BI';
    'DQS1N':
      PIN_NUMBER='(0,163,0,0)';
      BIDIRECTIONAL='TRUE';
      INPUT_LOAD='(-0.01,0.01)';
      OUTPUT_LOAD='(1.0,-1.0)';
      PINUSE='BI';
    'DQS1P':
      PIN_NUMBER='(0,164,0,0)';
      BIDIRECTIONAL='TRUE';
      INPUT_LOAD='(-0.01,0.01)';
      OUTPUT_LOAD='(1.0,-1.0)';
      PINUSE='BI';
    'DQS2N':
      PIN_NUMBER='(0,174,0,0)';
      BIDIRECTIONAL='TRUE';
      INPUT_LOAD='(-0.01,0.01)';
      OUTPUT_LOAD='(1.0,-1.0)';
      PINUSE='BI';
    'DQS2P':
      PIN_NUMBER='(0,175,0,0)';
      BIDIRECTIONAL='TRUE';
      INPUT_LOAD='(-0.01,0.01)';
      OUTPUT_LOAD='(1.0,-1.0)';
      PINUSE='BI';
    'DQS3N':
      PIN_NUMBER='(0,185,0,0)';
      BIDIRECTIONAL='TRUE';
      INPUT_LOAD='(-0.01,0.01)';
      OUTPUT_LOAD='(1.0,-1.0)';
      PINUSE='BI';
    'DQS3P':
      PIN_NUMBER='(0,186,0,0)';
      BIDIRECTIONAL='TRUE';
      INPUT_LOAD='(-0.01,0.01)';
      OUTPUT_LOAD='(1.0,-1.0)';
      PINUSE='BI';
    'DQS4N':
      PIN_NUMBER='(0,244,0,0)';
      BIDIRECTIONAL='TRUE';
      INPUT_LOAD='(-0.01,0.01)';
      OUTPUT_LOAD='(1.0,-1.0)';
      PINUSE='BI';
    'DQS4P':
      PIN_NUMBER='(0,245,0,0)';
      BIDIRECTIONAL='TRUE';
      INPUT_LOAD='(-0.01,0.01)';
      OUTPUT_LOAD='(1.0,-1.0)';
      PINUSE='BI';
    'DQS5N':
      PIN_NUMBER='(0,255,0,0)';
      BIDIRECTIONAL='TRUE';
      INPUT_LOAD='(-0.01,0.01)';
      OUTPUT_LOAD='(1.0,-1.0)';
      PINUSE='BI';
    'DQS5P':
      PIN_NUMBER='(0,256,0,0)';
      BIDIRECTIONAL='TRUE';
      INPUT_LOAD='(-0.01,0.01)';
      OUTPUT_LOAD='(1.0,-1.0)';
      PINUSE='BI';
    'DQS6N':
      PIN_NUMBER='(0,266,0,0)';
      BIDIRECTIONAL='TRUE';
      INPUT_LOAD='(-0.01,0.01)';
      OUTPUT_LOAD='(1.0,-1.0)';
      PINUSE='BI';
    'DQS6P':
      PIN_NUMBER='(0,267,0,0)';
      BIDIRECTIONAL='TRUE';
      INPUT_LOAD='(-0.01,0.01)';
      OUTPUT_LOAD='(1.0,-1.0)';
      PINUSE='BI';
    'DQS7N':
      PIN_NUMBER='(0,277,0,0)';
      BIDIRECTIONAL='TRUE';
      INPUT_LOAD='(-0.01,0.01)';
      OUTPUT_LOAD='(1.0,-1.0)';
      PINUSE='BI';
    'DQS7P':
      PIN_NUMBER='(0,278,0,0)';
      BIDIRECTIONAL='TRUE';
      INPUT_LOAD='(-0.01,0.01)';
      OUTPUT_LOAD='(1.0,-1.0)';
      PINUSE='BI';
    'DQS8N':
      PIN_NUMBER='(0,196,0,0)';
      BIDIRECTIONAL='TRUE';
      INPUT_LOAD='(-0.01,0.01)';
      OUTPUT_LOAD='(1.0,-1.0)';
      PINUSE='BI';
    'DQS8P':
      PIN_NUMBER='(0,197,0,0)';
      BIDIRECTIONAL='TRUE';
      INPUT_LOAD='(-0.01,0.01)';
      OUTPUT_LOAD='(1.0,-1.0)';
      PINUSE='BI';
    'DQS9N':
      PIN_NUMBER='(0,8,0,0)';
      BIDIRECTIONAL='TRUE';
      INPUT_LOAD='(-0.01,0.01)';
      OUTPUT_LOAD='(1.0,-1.0)';
      PINUSE='BI';
    'DQS9P':
      PIN_NUMBER='(0,7,0,0)';
      BIDIRECTIONAL='TRUE';
      INPUT_LOAD='(-0.01,0.01)';
      OUTPUT_LOAD='(1.0,-1.0)';
      PINUSE='BI';
    'EVENT_N':
      PIN_NUMBER='(78,0,0,0)';
      BIDIRECTIONAL='TRUE';
      INPUT_LOAD='(-0.01,0.01)';
      OUTPUT_LOAD='(1.0,-1.0)';
      PINUSE='BI';
    'ODT'<1>:
      PIN_NUMBER='(91,0,0,0)';
      BIDIRECTIONAL='TRUE';
      INPUT_LOAD='(-0.01,0.01)';
      OUTPUT_LOAD='(1.0,-1.0)';
      PINUSE='BI';
    'ODT'<0>:
      PIN_NUMBER='(87,0,0,0)';
      BIDIRECTIONAL='TRUE';
      INPUT_LOAD='(-0.01,0.01)';
      OUTPUT_LOAD='(1.0,-1.0)';
      PINUSE='BI';
    'PAR':
      PIN_NUMBER='(222,0,0,0)';
      BIDIRECTIONAL='TRUE';
      INPUT_LOAD='(-0.01,0.01)';
      OUTPUT_LOAD='(1.0,-1.0)';
      PINUSE='BI';
    'RESET_N':
      PIN_NUMBER='(58,0,0,0)';
      BIDIRECTIONAL='TRUE';
      INPUT_LOAD='(-0.01,0.01)';
      OUTPUT_LOAD='(1.0,-1.0)';
      PINUSE='BI';
    'RFU'<2>:
      PIN_NUMBER='(144,0,0,0)';
      BIDIRECTIONAL='TRUE';
      INPUT_LOAD='(-0.01,0.01)';
      OUTPUT_LOAD='(1.0,-1.0)';
      PINUSE='BI';
    'RFU'<1>:
      PIN_NUMBER='(227,0,0,0)';
      BIDIRECTIONAL='TRUE';
      INPUT_LOAD='(-0.01,0.01)';
      OUTPUT_LOAD='(1.0,-1.0)';
      PINUSE='BI';
    'RFU'<0>:
      PIN_NUMBER='(205,0,0,0)';
      BIDIRECTIONAL='TRUE';
      INPUT_LOAD='(-0.01,0.01)';
      OUTPUT_LOAD='(1.0,-1.0)';
      PINUSE='BI';
    'S0_N':
      PIN_NUMBER='(84,0,0,0)';
      BIDIRECTIONAL='TRUE';
      INPUT_LOAD='(-0.01,0.01)';
      OUTPUT_LOAD='(1.0,-1.0)';
      PINUSE='BI';
    'S1_N':
      PIN_NUMBER='(89,0,0,0)';
      BIDIRECTIONAL='TRUE';
      INPUT_LOAD='(-0.01,0.01)';
      OUTPUT_LOAD='(1.0,-1.0)';
      PINUSE='BI';
    'S2_N_C'<0>:
      PIN_NUMBER='(93,0,0,0)';
      BIDIRECTIONAL='TRUE';
      INPUT_LOAD='(-0.01,0.01)';
      OUTPUT_LOAD='(1.0,-1.0)';
      PINUSE='BI';
    'S3_N_C'<1>:
      PIN_NUMBER='(237,0,0,0)';
      BIDIRECTIONAL='TRUE';
      INPUT_LOAD='(-0.01,0.01)';
      OUTPUT_LOAD='(1.0,-1.0)';
      PINUSE='BI';
    'SA'<2>:
      PIN_NUMBER='(238,0,0,0)';
      BIDIRECTIONAL='TRUE';
      INPUT_LOAD='(-0.01,0.01)';
      OUTPUT_LOAD='(1.0,-1.0)';
      PINUSE='BI';
    'SA'<1>:
      PIN_NUMBER='(140,0,0,0)';
      BIDIRECTIONAL='TRUE';
      INPUT_LOAD='(-0.01,0.01)';
      OUTPUT_LOAD='(1.0,-1.0)';
      PINUSE='BI';
    'SA'<0>:
      PIN_NUMBER='(139,0,0,0)';
      BIDIRECTIONAL='TRUE';
      INPUT_LOAD='(-0.01,0.01)';
      OUTPUT_LOAD='(1.0,-1.0)';
      PINUSE='BI';
    'SAVE_N_NC':
      PIN_NUMBER='(230,0,0,0)';
      BIDIRECTIONAL='TRUE';
      INPUT_LOAD='(-0.01,0.01)';
      OUTPUT_LOAD='(1.0,-1.0)';
      PINUSE='BI';
    'SCL':
      PIN_NUMBER='(141,0,0,0)';
      BIDIRECTIONAL='TRUE';
      INPUT_LOAD='(-0.01,0.01)';
      OUTPUT_LOAD='(1.0,-1.0)';
      PINUSE='BI';
    'SDA':
      PIN_NUMBER='(285,0,0,0)';
      BIDIRECTIONAL='TRUE';
      INPUT_LOAD='(-0.01,0.01)';
      OUTPUT_LOAD='(1.0,-1.0)';
      PINUSE='BI';
    'VDD'<25>:
      PIN_NUMBER='(0,0,0,59)';
      PINUSE='POWER';
      NO_LOAD_CHECK='Both';
      NO_IO_CHECK='Both';
      NO_ASSERT_CHECK='TRUE';
      NO_DIR_CHECK='TRUE';
      ALLOW_CONNECT='TRUE';
    'VDD'<24>:
      PIN_NUMBER='(0,0,0,61)';
      PINUSE='POWER';
      NO_LOAD_CHECK='Both';
      NO_IO_CHECK='Both';
      NO_ASSERT_CHECK='TRUE';
      NO_DIR_CHECK='TRUE';
      ALLOW_CONNECT='TRUE';
    'VDD'<23>:
      PIN_NUMBER='(0,0,0,64)';
      PINUSE='POWER';
      NO_LOAD_CHECK='Both';
      NO_IO_CHECK='Both';
      NO_ASSERT_CHECK='TRUE';
      NO_DIR_CHECK='TRUE';
      ALLOW_CONNECT='TRUE';
    'VDD'<22>:
      PIN_NUMBER='(0,0,0,67)';
      PINUSE='POWER';
      NO_LOAD_CHECK='Both';
      NO_IO_CHECK='Both';
      NO_ASSERT_CHECK='TRUE';
      NO_DIR_CHECK='TRUE';
      ALLOW_CONNECT='TRUE';
    'VDD'<21>:
      PIN_NUMBER='(0,0,0,70)';
      PINUSE='POWER';
      NO_LOAD_CHECK='Both';
      NO_IO_CHECK='Both';
      NO_ASSERT_CHECK='TRUE';
      NO_DIR_CHECK='TRUE';
      ALLOW_CONNECT='TRUE';
    'VDD'<20>:
      PIN_NUMBER='(0,0,0,73)';
      PINUSE='POWER';
      NO_LOAD_CHECK='Both';
      NO_IO_CHECK='Both';
      NO_ASSERT_CHECK='TRUE';
      NO_DIR_CHECK='TRUE';
      ALLOW_CONNECT='TRUE';
    'VDD'<19>:
      PIN_NUMBER='(0,0,0,76)';
      PINUSE='POWER';
      NO_LOAD_CHECK='Both';
      NO_IO_CHECK='Both';
      NO_ASSERT_CHECK='TRUE';
      NO_DIR_CHECK='TRUE';
      ALLOW_CONNECT='TRUE';
    'VDD'<18>:
      PIN_NUMBER='(0,0,0,80)';
      PINUSE='POWER';
      NO_LOAD_CHECK='Both';
      NO_IO_CHECK='Both';
      NO_ASSERT_CHECK='TRUE';
      NO_DIR_CHECK='TRUE';
      ALLOW_CONNECT='TRUE';
    'VDD'<17>:
      PIN_NUMBER='(0,0,0,83)';
      PINUSE='POWER';
      NO_LOAD_CHECK='Both';
      NO_IO_CHECK='Both';
      NO_ASSERT_CHECK='TRUE';
      NO_DIR_CHECK='TRUE';
      ALLOW_CONNECT='TRUE';
    'VDD'<16>:
      PIN_NUMBER='(0,0,0,85)';
      PINUSE='POWER';
      NO_LOAD_CHECK='Both';
      NO_IO_CHECK='Both';
      NO_ASSERT_CHECK='TRUE';
      NO_DIR_CHECK='TRUE';
      ALLOW_CONNECT='TRUE';
    'VDD'<15>:
      PIN_NUMBER='(0,0,0,88)';
      PINUSE='POWER';
      NO_LOAD_CHECK='Both';
      NO_IO_CHECK='Both';
      NO_ASSERT_CHECK='TRUE';
      NO_DIR_CHECK='TRUE';
      ALLOW_CONNECT='TRUE';
    'VDD'<14>:
      PIN_NUMBER='(0,0,0,90)';
      PINUSE='POWER';
      NO_LOAD_CHECK='Both';
      NO_IO_CHECK='Both';
      NO_ASSERT_CHECK='TRUE';
      NO_DIR_CHECK='TRUE';
      ALLOW_CONNECT='TRUE';
    'VDD'<13>:
      PIN_NUMBER='(0,0,0,92)';
      PINUSE='POWER';
      NO_LOAD_CHECK='Both';
      NO_IO_CHECK='Both';
      NO_ASSERT_CHECK='TRUE';
      NO_DIR_CHECK='TRUE';
      ALLOW_CONNECT='TRUE';
    'VDD'<12>:
      PIN_NUMBER='(0,0,0,204)';
      PINUSE='POWER';
      NO_LOAD_CHECK='Both';
      NO_IO_CHECK='Both';
      NO_ASSERT_CHECK='TRUE';
      NO_DIR_CHECK='TRUE';
      ALLOW_CONNECT='TRUE';
    'VDD'<11>:
      PIN_NUMBER='(0,0,0,206)';
      PINUSE='POWER';
      NO_LOAD_CHECK='Both';
      NO_IO_CHECK='Both';
      NO_ASSERT_CHECK='TRUE';
      NO_DIR_CHECK='TRUE';
      ALLOW_CONNECT='TRUE';
    'VDD'<10>:
      PIN_NUMBER='(0,0,0,209)';
      PINUSE='POWER';
      NO_LOAD_CHECK='Both';
      NO_IO_CHECK='Both';
      NO_ASSERT_CHECK='TRUE';
      NO_DIR_CHECK='TRUE';
      ALLOW_CONNECT='TRUE';
    'VDD'<9>:
      PIN_NUMBER='(0,0,0,212)';
      PINUSE='POWER';
      NO_LOAD_CHECK='Both';
      NO_IO_CHECK='Both';
      NO_ASSERT_CHECK='TRUE';
      NO_DIR_CHECK='TRUE';
      ALLOW_CONNECT='TRUE';
    'VDD'<8>:
      PIN_NUMBER='(0,0,0,215)';
      PINUSE='POWER';
      NO_LOAD_CHECK='Both';
      NO_IO_CHECK='Both';
      NO_ASSERT_CHECK='TRUE';
      NO_DIR_CHECK='TRUE';
      ALLOW_CONNECT='TRUE';
    'VDD'<7>:
      PIN_NUMBER='(0,0,0,217)';
      PINUSE='POWER';
      NO_LOAD_CHECK='Both';
      NO_IO_CHECK='Both';
      NO_ASSERT_CHECK='TRUE';
      NO_DIR_CHECK='TRUE';
      ALLOW_CONNECT='TRUE';
    'VDD'<6>:
      PIN_NUMBER='(0,0,0,220)';
      PINUSE='POWER';
      NO_LOAD_CHECK='Both';
      NO_IO_CHECK='Both';
      NO_ASSERT_CHECK='TRUE';
      NO_DIR_CHECK='TRUE';
      ALLOW_CONNECT='TRUE';
    'VDD'<5>:
      PIN_NUMBER='(0,0,0,223)';
      PINUSE='POWER';
      NO_LOAD_CHECK='Both';
      NO_IO_CHECK='Both';
      NO_ASSERT_CHECK='TRUE';
      NO_DIR_CHECK='TRUE';
      ALLOW_CONNECT='TRUE';
    'VDD'<4>:
      PIN_NUMBER='(0,0,0,226)';
      PINUSE='POWER';
      NO_LOAD_CHECK='Both';
      NO_IO_CHECK='Both';
      NO_ASSERT_CHECK='TRUE';
      NO_DIR_CHECK='TRUE';
      ALLOW_CONNECT='TRUE';
    'VDD'<3>:
      PIN_NUMBER='(0,0,0,229)';
      PINUSE='POWER';
      NO_LOAD_CHECK='Both';
      NO_IO_CHECK='Both';
      NO_ASSERT_CHECK='TRUE';
      NO_DIR_CHECK='TRUE';
      ALLOW_CONNECT='TRUE';
    'VDD'<2>:
      PIN_NUMBER='(0,0,0,231)';
      PINUSE='POWER';
      NO_LOAD_CHECK='Both';
      NO_IO_CHECK='Both';
      NO_ASSERT_CHECK='TRUE';
      NO_DIR_CHECK='TRUE';
      ALLOW_CONNECT='TRUE';
    'VDD'<1>:
      PIN_NUMBER='(0,0,0,233)';
      PINUSE='POWER';
      NO_LOAD_CHECK='Both';
      NO_IO_CHECK='Both';
      NO_ASSERT_CHECK='TRUE';
      NO_DIR_CHECK='TRUE';
      ALLOW_CONNECT='TRUE';
    'VDD'<0>:
      PIN_NUMBER='(0,0,0,236)';
      PINUSE='POWER';
      NO_LOAD_CHECK='Both';
      NO_IO_CHECK='Both';
      NO_ASSERT_CHECK='TRUE';
      NO_DIR_CHECK='TRUE';
      ALLOW_CONNECT='TRUE';
    'VDDSPD':
      PIN_NUMBER='(284,0,0,0)';
      BIDIRECTIONAL='TRUE';
      INPUT_LOAD='(-0.01,0.01)';
      OUTPUT_LOAD='(1.0,-1.0)';
      PINUSE='BI';
    'VPP'<4>:
      PIN_NUMBER='(0,0,0,142)';
      PINUSE='POWER';
      NO_LOAD_CHECK='Both';
      NO_IO_CHECK='Both';
      NO_ASSERT_CHECK='TRUE';
      NO_DIR_CHECK='TRUE';
      ALLOW_CONNECT='TRUE';
    'VPP'<3>:
      PIN_NUMBER='(0,0,0,143)';
      PINUSE='POWER';
      NO_LOAD_CHECK='Both';
      NO_IO_CHECK='Both';
      NO_ASSERT_CHECK='TRUE';
      NO_DIR_CHECK='TRUE';
      ALLOW_CONNECT='TRUE';
    'VPP'<2>:
      PIN_NUMBER='(0,0,0,288)';
      PINUSE='POWER';
      NO_LOAD_CHECK='Both';
      NO_IO_CHECK='Both';
      NO_ASSERT_CHECK='TRUE';
      NO_DIR_CHECK='TRUE';
      ALLOW_CONNECT='TRUE';
    'VPP'<1>:
      PIN_NUMBER='(0,0,0,286)';
      PINUSE='POWER';
      NO_LOAD_CHECK='Both';
      NO_IO_CHECK='Both';
      NO_ASSERT_CHECK='TRUE';
      NO_DIR_CHECK='TRUE';
      ALLOW_CONNECT='TRUE';
    'VPP'<0>:
      PIN_NUMBER='(0,0,0,287)';
      PINUSE='POWER';
      NO_LOAD_CHECK='Both';
      NO_IO_CHECK='Both';
      NO_ASSERT_CHECK='TRUE';
      NO_DIR_CHECK='TRUE';
      ALLOW_CONNECT='TRUE';
    'VREFCA':
      PIN_NUMBER='(146,0,0,0)';
      BIDIRECTIONAL='TRUE';
      INPUT_LOAD='(-0.01,0.01)';
      OUTPUT_LOAD='(1.0,-1.0)';
      PINUSE='BI';
    'VSS'<93>:
      PIN_NUMBER='(0,0,2,0)';
      PINUSE='GROUND';
      NO_LOAD_CHECK='Both';
      NO_IO_CHECK='Both';
      NO_ASSERT_CHECK='TRUE';
      NO_DIR_CHECK='TRUE';
      ALLOW_CONNECT='TRUE';
    'VSS'<92>:
      PIN_NUMBER='(0,0,4,0)';
      PINUSE='GROUND';
      NO_LOAD_CHECK='Both';
      NO_IO_CHECK='Both';
      NO_ASSERT_CHECK='TRUE';
      NO_DIR_CHECK='TRUE';
      ALLOW_CONNECT='TRUE';
    'VSS'<91>:
      PIN_NUMBER='(0,0,6,0)';
      PINUSE='GROUND';
      NO_LOAD_CHECK='Both';
      NO_IO_CHECK='Both';
      NO_ASSERT_CHECK='TRUE';
      NO_DIR_CHECK='TRUE';
      ALLOW_CONNECT='TRUE';
    'VSS'<90>:
      PIN_NUMBER='(0,0,9,0)';
      PINUSE='GROUND';
      NO_LOAD_CHECK='Both';
      NO_IO_CHECK='Both';
      NO_ASSERT_CHECK='TRUE';
      NO_DIR_CHECK='TRUE';
      ALLOW_CONNECT='TRUE';
    'VSS'<89>:
      PIN_NUMBER='(0,0,11,0)';
      PINUSE='GROUND';
      NO_LOAD_CHECK='Both';
      NO_IO_CHECK='Both';
      NO_ASSERT_CHECK='TRUE';
      NO_DIR_CHECK='TRUE';
      ALLOW_CONNECT='TRUE';
    'VSS'<88>:
      PIN_NUMBER='(0,0,13,0)';
      PINUSE='GROUND';
      NO_LOAD_CHECK='Both';
      NO_IO_CHECK='Both';
      NO_ASSERT_CHECK='TRUE';
      NO_DIR_CHECK='TRUE';
      ALLOW_CONNECT='TRUE';
    'VSS'<87>:
      PIN_NUMBER='(0,0,15,0)';
      PINUSE='GROUND';
      NO_LOAD_CHECK='Both';
      NO_IO_CHECK='Both';
      NO_ASSERT_CHECK='TRUE';
      NO_DIR_CHECK='TRUE';
      ALLOW_CONNECT='TRUE';
    'VSS'<86>:
      PIN_NUMBER='(0,0,17,0)';
      PINUSE='GROUND';
      NO_LOAD_CHECK='Both';
      NO_IO_CHECK='Both';
      NO_ASSERT_CHECK='TRUE';
      NO_DIR_CHECK='TRUE';
      ALLOW_CONNECT='TRUE';
    'VSS'<85>:
      PIN_NUMBER='(0,0,20,0)';
      PINUSE='GROUND';
      NO_LOAD_CHECK='Both';
      NO_IO_CHECK='Both';
      NO_ASSERT_CHECK='TRUE';
      NO_DIR_CHECK='TRUE';
      ALLOW_CONNECT='TRUE';
    'VSS'<84>:
      PIN_NUMBER='(0,0,22,0)';
      PINUSE='GROUND';
      NO_LOAD_CHECK='Both';
      NO_IO_CHECK='Both';
      NO_ASSERT_CHECK='TRUE';
      NO_DIR_CHECK='TRUE';
      ALLOW_CONNECT='TRUE';
    'VSS'<83>:
      PIN_NUMBER='(0,0,24,0)';
      PINUSE='GROUND';
      NO_LOAD_CHECK='Both';
      NO_IO_CHECK='Both';
      NO_ASSERT_CHECK='TRUE';
      NO_DIR_CHECK='TRUE';
      ALLOW_CONNECT='TRUE';
    'VSS'<82>:
      PIN_NUMBER='(0,0,26,0)';
      PINUSE='GROUND';
      NO_LOAD_CHECK='Both';
      NO_IO_CHECK='Both';
      NO_ASSERT_CHECK='TRUE';
      NO_DIR_CHECK='TRUE';
      ALLOW_CONNECT='TRUE';
    'VSS'<81>:
      PIN_NUMBER='(0,0,28,0)';
      PINUSE='GROUND';
      NO_LOAD_CHECK='Both';
      NO_IO_CHECK='Both';
      NO_ASSERT_CHECK='TRUE';
      NO_DIR_CHECK='TRUE';
      ALLOW_CONNECT='TRUE';
    'VSS'<80>:
      PIN_NUMBER='(0,0,31,0)';
      PINUSE='GROUND';
      NO_LOAD_CHECK='Both';
      NO_IO_CHECK='Both';
      NO_ASSERT_CHECK='TRUE';
      NO_DIR_CHECK='TRUE';
      ALLOW_CONNECT='TRUE';
    'VSS'<79>:
      PIN_NUMBER='(0,0,33,0)';
      PINUSE='GROUND';
      NO_LOAD_CHECK='Both';
      NO_IO_CHECK='Both';
      NO_ASSERT_CHECK='TRUE';
      NO_DIR_CHECK='TRUE';
      ALLOW_CONNECT='TRUE';
    'VSS'<78>:
      PIN_NUMBER='(0,0,35,0)';
      PINUSE='GROUND';
      NO_LOAD_CHECK='Both';
      NO_IO_CHECK='Both';
      NO_ASSERT_CHECK='TRUE';
      NO_DIR_CHECK='TRUE';
      ALLOW_CONNECT='TRUE';
    'VSS'<77>:
      PIN_NUMBER='(0,0,37,0)';
      PINUSE='GROUND';
      NO_LOAD_CHECK='Both';
      NO_IO_CHECK='Both';
      NO_ASSERT_CHECK='TRUE';
      NO_DIR_CHECK='TRUE';
      ALLOW_CONNECT='TRUE';
    'VSS'<76>:
      PIN_NUMBER='(0,0,39,0)';
      PINUSE='GROUND';
      NO_LOAD_CHECK='Both';
      NO_IO_CHECK='Both';
      NO_ASSERT_CHECK='TRUE';
      NO_DIR_CHECK='TRUE';
      ALLOW_CONNECT='TRUE';
    'VSS'<75>:
      PIN_NUMBER='(0,0,42,0)';
      PINUSE='GROUND';
      NO_LOAD_CHECK='Both';
      NO_IO_CHECK='Both';
      NO_ASSERT_CHECK='TRUE';
      NO_DIR_CHECK='TRUE';
      ALLOW_CONNECT='TRUE';
    'VSS'<74>:
      PIN_NUMBER='(0,0,44,0)';
      PINUSE='GROUND';
      NO_LOAD_CHECK='Both';
      NO_IO_CHECK='Both';
      NO_ASSERT_CHECK='TRUE';
      NO_DIR_CHECK='TRUE';
      ALLOW_CONNECT='TRUE';
    'VSS'<73>:
      PIN_NUMBER='(0,0,46,0)';
      PINUSE='GROUND';
      NO_LOAD_CHECK='Both';
      NO_IO_CHECK='Both';
      NO_ASSERT_CHECK='TRUE';
      NO_DIR_CHECK='TRUE';
      ALLOW_CONNECT='TRUE';
    'VSS'<72>:
      PIN_NUMBER='(0,0,48,0)';
      PINUSE='GROUND';
      NO_LOAD_CHECK='Both';
      NO_IO_CHECK='Both';
      NO_ASSERT_CHECK='TRUE';
      NO_DIR_CHECK='TRUE';
      ALLOW_CONNECT='TRUE';
    'VSS'<71>:
      PIN_NUMBER='(0,0,50,0)';
      PINUSE='GROUND';
      NO_LOAD_CHECK='Both';
      NO_IO_CHECK='Both';
      NO_ASSERT_CHECK='TRUE';
      NO_DIR_CHECK='TRUE';
      ALLOW_CONNECT='TRUE';
    'VSS'<70>:
      PIN_NUMBER='(0,0,53,0)';
      PINUSE='GROUND';
      NO_LOAD_CHECK='Both';
      NO_IO_CHECK='Both';
      NO_ASSERT_CHECK='TRUE';
      NO_DIR_CHECK='TRUE';
      ALLOW_CONNECT='TRUE';
    'VSS'<69>:
      PIN_NUMBER='(0,0,55,0)';
      PINUSE='GROUND';
      NO_LOAD_CHECK='Both';
      NO_IO_CHECK='Both';
      NO_ASSERT_CHECK='TRUE';
      NO_DIR_CHECK='TRUE';
      ALLOW_CONNECT='TRUE';
    'VSS'<68>:
      PIN_NUMBER='(0,0,57,0)';
      PINUSE='GROUND';
      NO_LOAD_CHECK='Both';
      NO_IO_CHECK='Both';
      NO_ASSERT_CHECK='TRUE';
      NO_DIR_CHECK='TRUE';
      ALLOW_CONNECT='TRUE';
    'VSS'<67>:
      PIN_NUMBER='(0,0,94,0)';
      PINUSE='GROUND';
      NO_LOAD_CHECK='Both';
      NO_IO_CHECK='Both';
      NO_ASSERT_CHECK='TRUE';
      NO_DIR_CHECK='TRUE';
      ALLOW_CONNECT='TRUE';
    'VSS'<66>:
      PIN_NUMBER='(0,0,96,0)';
      PINUSE='GROUND';
      NO_LOAD_CHECK='Both';
      NO_IO_CHECK='Both';
      NO_ASSERT_CHECK='TRUE';
      NO_DIR_CHECK='TRUE';
      ALLOW_CONNECT='TRUE';
    'VSS'<65>:
      PIN_NUMBER='(0,0,98,0)';
      PINUSE='GROUND';
      NO_LOAD_CHECK='Both';
      NO_IO_CHECK='Both';
      NO_ASSERT_CHECK='TRUE';
      NO_DIR_CHECK='TRUE';
      ALLOW_CONNECT='TRUE';
    'VSS'<64>:
      PIN_NUMBER='(0,0,101,0)';
      PINUSE='GROUND';
      NO_LOAD_CHECK='Both';
      NO_IO_CHECK='Both';
      NO_ASSERT_CHECK='TRUE';
      NO_DIR_CHECK='TRUE';
      ALLOW_CONNECT='TRUE';
    'VSS'<63>:
      PIN_NUMBER='(0,0,103,0)';
      PINUSE='GROUND';
      NO_LOAD_CHECK='Both';
      NO_IO_CHECK='Both';
      NO_ASSERT_CHECK='TRUE';
      NO_DIR_CHECK='TRUE';
      ALLOW_CONNECT='TRUE';
    'VSS'<62>:
      PIN_NUMBER='(0,0,105,0)';
      PINUSE='GROUND';
      NO_LOAD_CHECK='Both';
      NO_IO_CHECK='Both';
      NO_ASSERT_CHECK='TRUE';
      NO_DIR_CHECK='TRUE';
      ALLOW_CONNECT='TRUE';
    'VSS'<61>:
      PIN_NUMBER='(0,0,107,0)';
      PINUSE='GROUND';
      NO_LOAD_CHECK='Both';
      NO_IO_CHECK='Both';
      NO_ASSERT_CHECK='TRUE';
      NO_DIR_CHECK='TRUE';
      ALLOW_CONNECT='TRUE';
    'VSS'<60>:
      PIN_NUMBER='(0,0,109,0)';
      PINUSE='GROUND';
      NO_LOAD_CHECK='Both';
      NO_IO_CHECK='Both';
      NO_ASSERT_CHECK='TRUE';
      NO_DIR_CHECK='TRUE';
      ALLOW_CONNECT='TRUE';
    'VSS'<59>:
      PIN_NUMBER='(0,0,112,0)';
      PINUSE='GROUND';
      NO_LOAD_CHECK='Both';
      NO_IO_CHECK='Both';
      NO_ASSERT_CHECK='TRUE';
      NO_DIR_CHECK='TRUE';
      ALLOW_CONNECT='TRUE';
    'VSS'<58>:
      PIN_NUMBER='(0,0,114,0)';
      PINUSE='GROUND';
      NO_LOAD_CHECK='Both';
      NO_IO_CHECK='Both';
      NO_ASSERT_CHECK='TRUE';
      NO_DIR_CHECK='TRUE';
      ALLOW_CONNECT='TRUE';
    'VSS'<57>:
      PIN_NUMBER='(0,0,116,0)';
      PINUSE='GROUND';
      NO_LOAD_CHECK='Both';
      NO_IO_CHECK='Both';
      NO_ASSERT_CHECK='TRUE';
      NO_DIR_CHECK='TRUE';
      ALLOW_CONNECT='TRUE';
    'VSS'<56>:
      PIN_NUMBER='(0,0,118,0)';
      PINUSE='GROUND';
      NO_LOAD_CHECK='Both';
      NO_IO_CHECK='Both';
      NO_ASSERT_CHECK='TRUE';
      NO_DIR_CHECK='TRUE';
      ALLOW_CONNECT='TRUE';
    'VSS'<55>:
      PIN_NUMBER='(0,0,120,0)';
      PINUSE='GROUND';
      NO_LOAD_CHECK='Both';
      NO_IO_CHECK='Both';
      NO_ASSERT_CHECK='TRUE';
      NO_DIR_CHECK='TRUE';
      ALLOW_CONNECT='TRUE';
    'VSS'<54>:
      PIN_NUMBER='(0,0,123,0)';
      PINUSE='GROUND';
      NO_LOAD_CHECK='Both';
      NO_IO_CHECK='Both';
      NO_ASSERT_CHECK='TRUE';
      NO_DIR_CHECK='TRUE';
      ALLOW_CONNECT='TRUE';
    'VSS'<53>:
      PIN_NUMBER='(0,0,125,0)';
      PINUSE='GROUND';
      NO_LOAD_CHECK='Both';
      NO_IO_CHECK='Both';
      NO_ASSERT_CHECK='TRUE';
      NO_DIR_CHECK='TRUE';
      ALLOW_CONNECT='TRUE';
    'VSS'<52>:
      PIN_NUMBER='(0,0,127,0)';
      PINUSE='GROUND';
      NO_LOAD_CHECK='Both';
      NO_IO_CHECK='Both';
      NO_ASSERT_CHECK='TRUE';
      NO_DIR_CHECK='TRUE';
      ALLOW_CONNECT='TRUE';
    'VSS'<51>:
      PIN_NUMBER='(0,0,129,0)';
      PINUSE='GROUND';
      NO_LOAD_CHECK='Both';
      NO_IO_CHECK='Both';
      NO_ASSERT_CHECK='TRUE';
      NO_DIR_CHECK='TRUE';
      ALLOW_CONNECT='TRUE';
    'VSS'<50>:
      PIN_NUMBER='(0,0,131,0)';
      PINUSE='GROUND';
      NO_LOAD_CHECK='Both';
      NO_IO_CHECK='Both';
      NO_ASSERT_CHECK='TRUE';
      NO_DIR_CHECK='TRUE';
      ALLOW_CONNECT='TRUE';
    'VSS'<49>:
      PIN_NUMBER='(0,0,134,0)';
      PINUSE='GROUND';
      NO_LOAD_CHECK='Both';
      NO_IO_CHECK='Both';
      NO_ASSERT_CHECK='TRUE';
      NO_DIR_CHECK='TRUE';
      ALLOW_CONNECT='TRUE';
    'VSS'<48>:
      PIN_NUMBER='(0,0,136,0)';
      PINUSE='GROUND';
      NO_LOAD_CHECK='Both';
      NO_IO_CHECK='Both';
      NO_ASSERT_CHECK='TRUE';
      NO_DIR_CHECK='TRUE';
      ALLOW_CONNECT='TRUE';
    'VSS'<47>:
      PIN_NUMBER='(0,0,138,0)';
      PINUSE='GROUND';
      NO_LOAD_CHECK='Both';
      NO_IO_CHECK='Both';
      NO_ASSERT_CHECK='TRUE';
      NO_DIR_CHECK='TRUE';
      ALLOW_CONNECT='TRUE';
    'VSS'<46>:
      PIN_NUMBER='(0,0,147,0)';
      PINUSE='GROUND';
      NO_LOAD_CHECK='Both';
      NO_IO_CHECK='Both';
      NO_ASSERT_CHECK='TRUE';
      NO_DIR_CHECK='TRUE';
      ALLOW_CONNECT='TRUE';
    'VSS'<45>:
      PIN_NUMBER='(0,0,149,0)';
      PINUSE='GROUND';
      NO_LOAD_CHECK='Both';
      NO_IO_CHECK='Both';
      NO_ASSERT_CHECK='TRUE';
      NO_DIR_CHECK='TRUE';
      ALLOW_CONNECT='TRUE';
    'VSS'<44>:
      PIN_NUMBER='(0,0,151,0)';
      PINUSE='GROUND';
      NO_LOAD_CHECK='Both';
      NO_IO_CHECK='Both';
      NO_ASSERT_CHECK='TRUE';
      NO_DIR_CHECK='TRUE';
      ALLOW_CONNECT='TRUE';
    'VSS'<43>:
      PIN_NUMBER='(0,0,154,0)';
      PINUSE='GROUND';
      NO_LOAD_CHECK='Both';
      NO_IO_CHECK='Both';
      NO_ASSERT_CHECK='TRUE';
      NO_DIR_CHECK='TRUE';
      ALLOW_CONNECT='TRUE';
    'VSS'<42>:
      PIN_NUMBER='(0,0,156,0)';
      PINUSE='GROUND';
      NO_LOAD_CHECK='Both';
      NO_IO_CHECK='Both';
      NO_ASSERT_CHECK='TRUE';
      NO_DIR_CHECK='TRUE';
      ALLOW_CONNECT='TRUE';
    'VSS'<41>:
      PIN_NUMBER='(0,0,158,0)';
      PINUSE='GROUND';
      NO_LOAD_CHECK='Both';
      NO_IO_CHECK='Both';
      NO_ASSERT_CHECK='TRUE';
      NO_DIR_CHECK='TRUE';
      ALLOW_CONNECT='TRUE';
    'VSS'<40>:
      PIN_NUMBER='(0,0,160,0)';
      PINUSE='GROUND';
      NO_LOAD_CHECK='Both';
      NO_IO_CHECK='Both';
      NO_ASSERT_CHECK='TRUE';
      NO_DIR_CHECK='TRUE';
      ALLOW_CONNECT='TRUE';
    'VSS'<39>:
      PIN_NUMBER='(0,0,162,0)';
      PINUSE='GROUND';
      NO_LOAD_CHECK='Both';
      NO_IO_CHECK='Both';
      NO_ASSERT_CHECK='TRUE';
      NO_DIR_CHECK='TRUE';
      ALLOW_CONNECT='TRUE';
    'VSS'<38>:
      PIN_NUMBER='(0,0,165,0)';
      PINUSE='GROUND';
      NO_LOAD_CHECK='Both';
      NO_IO_CHECK='Both';
      NO_ASSERT_CHECK='TRUE';
      NO_DIR_CHECK='TRUE';
      ALLOW_CONNECT='TRUE';
    'VSS'<37>:
      PIN_NUMBER='(0,0,167,0)';
      PINUSE='GROUND';
      NO_LOAD_CHECK='Both';
      NO_IO_CHECK='Both';
      NO_ASSERT_CHECK='TRUE';
      NO_DIR_CHECK='TRUE';
      ALLOW_CONNECT='TRUE';
    'VSS'<36>:
      PIN_NUMBER='(0,0,169,0)';
      PINUSE='GROUND';
      NO_LOAD_CHECK='Both';
      NO_IO_CHECK='Both';
      NO_ASSERT_CHECK='TRUE';
      NO_DIR_CHECK='TRUE';
      ALLOW_CONNECT='TRUE';
    'VSS'<35>:
      PIN_NUMBER='(0,0,171,0)';
      PINUSE='GROUND';
      NO_LOAD_CHECK='Both';
      NO_IO_CHECK='Both';
      NO_ASSERT_CHECK='TRUE';
      NO_DIR_CHECK='TRUE';
      ALLOW_CONNECT='TRUE';
    'VSS'<34>:
      PIN_NUMBER='(0,0,173,0)';
      PINUSE='GROUND';
      NO_LOAD_CHECK='Both';
      NO_IO_CHECK='Both';
      NO_ASSERT_CHECK='TRUE';
      NO_DIR_CHECK='TRUE';
      ALLOW_CONNECT='TRUE';
    'VSS'<33>:
      PIN_NUMBER='(0,0,176,0)';
      PINUSE='GROUND';
      NO_LOAD_CHECK='Both';
      NO_IO_CHECK='Both';
      NO_ASSERT_CHECK='TRUE';
      NO_DIR_CHECK='TRUE';
      ALLOW_CONNECT='TRUE';
    'VSS'<32>:
      PIN_NUMBER='(0,0,178,0)';
      PINUSE='GROUND';
      NO_LOAD_CHECK='Both';
      NO_IO_CHECK='Both';
      NO_ASSERT_CHECK='TRUE';
      NO_DIR_CHECK='TRUE';
      ALLOW_CONNECT='TRUE';
    'VSS'<31>:
      PIN_NUMBER='(0,0,180,0)';
      PINUSE='GROUND';
      NO_LOAD_CHECK='Both';
      NO_IO_CHECK='Both';
      NO_ASSERT_CHECK='TRUE';
      NO_DIR_CHECK='TRUE';
      ALLOW_CONNECT='TRUE';
    'VSS'<30>:
      PIN_NUMBER='(0,0,182,0)';
      PINUSE='GROUND';
      NO_LOAD_CHECK='Both';
      NO_IO_CHECK='Both';
      NO_ASSERT_CHECK='TRUE';
      NO_DIR_CHECK='TRUE';
      ALLOW_CONNECT='TRUE';
    'VSS'<29>:
      PIN_NUMBER='(0,0,184,0)';
      PINUSE='GROUND';
      NO_LOAD_CHECK='Both';
      NO_IO_CHECK='Both';
      NO_ASSERT_CHECK='TRUE';
      NO_DIR_CHECK='TRUE';
      ALLOW_CONNECT='TRUE';
    'VSS'<28>:
      PIN_NUMBER='(0,0,187,0)';
      PINUSE='GROUND';
      NO_LOAD_CHECK='Both';
      NO_IO_CHECK='Both';
      NO_ASSERT_CHECK='TRUE';
      NO_DIR_CHECK='TRUE';
      ALLOW_CONNECT='TRUE';
    'VSS'<27>:
      PIN_NUMBER='(0,0,189,0)';
      PINUSE='GROUND';
      NO_LOAD_CHECK='Both';
      NO_IO_CHECK='Both';
      NO_ASSERT_CHECK='TRUE';
      NO_DIR_CHECK='TRUE';
      ALLOW_CONNECT='TRUE';
    'VSS'<26>:
      PIN_NUMBER='(0,0,191,0)';
      PINUSE='GROUND';
      NO_LOAD_CHECK='Both';
      NO_IO_CHECK='Both';
      NO_ASSERT_CHECK='TRUE';
      NO_DIR_CHECK='TRUE';
      ALLOW_CONNECT='TRUE';
    'VSS'<25>:
      PIN_NUMBER='(0,0,193,0)';
      PINUSE='GROUND';
      NO_LOAD_CHECK='Both';
      NO_IO_CHECK='Both';
      NO_ASSERT_CHECK='TRUE';
      NO_DIR_CHECK='TRUE';
      ALLOW_CONNECT='TRUE';
    'VSS'<24>:
      PIN_NUMBER='(0,0,195,0)';
      PINUSE='GROUND';
      NO_LOAD_CHECK='Both';
      NO_IO_CHECK='Both';
      NO_ASSERT_CHECK='TRUE';
      NO_DIR_CHECK='TRUE';
      ALLOW_CONNECT='TRUE';
    'VSS'<23>:
      PIN_NUMBER='(0,0,198,0)';
      PINUSE='GROUND';
      NO_LOAD_CHECK='Both';
      NO_IO_CHECK='Both';
      NO_ASSERT_CHECK='TRUE';
      NO_DIR_CHECK='TRUE';
      ALLOW_CONNECT='TRUE';
    'VSS'<22>:
      PIN_NUMBER='(0,0,200,0)';
      PINUSE='GROUND';
      NO_LOAD_CHECK='Both';
      NO_IO_CHECK='Both';
      NO_ASSERT_CHECK='TRUE';
      NO_DIR_CHECK='TRUE';
      ALLOW_CONNECT='TRUE';
    'VSS'<21>:
      PIN_NUMBER='(0,0,202,0)';
      PINUSE='GROUND';
      NO_LOAD_CHECK='Both';
      NO_IO_CHECK='Both';
      NO_ASSERT_CHECK='TRUE';
      NO_DIR_CHECK='TRUE';
      ALLOW_CONNECT='TRUE';
    'VSS'<20>:
      PIN_NUMBER='(0,0,239,0)';
      PINUSE='GROUND';
      NO_LOAD_CHECK='Both';
      NO_IO_CHECK='Both';
      NO_ASSERT_CHECK='TRUE';
      NO_DIR_CHECK='TRUE';
      ALLOW_CONNECT='TRUE';
    'VSS'<19>:
      PIN_NUMBER='(0,0,241,0)';
      PINUSE='GROUND';
      NO_LOAD_CHECK='Both';
      NO_IO_CHECK='Both';
      NO_ASSERT_CHECK='TRUE';
      NO_DIR_CHECK='TRUE';
      ALLOW_CONNECT='TRUE';
    'VSS'<18>:
      PIN_NUMBER='(0,0,243,0)';
      PINUSE='GROUND';
      NO_LOAD_CHECK='Both';
      NO_IO_CHECK='Both';
      NO_ASSERT_CHECK='TRUE';
      NO_DIR_CHECK='TRUE';
      ALLOW_CONNECT='TRUE';
    'VSS'<17>:
      PIN_NUMBER='(0,0,246,0)';
      PINUSE='GROUND';
      NO_LOAD_CHECK='Both';
      NO_IO_CHECK='Both';
      NO_ASSERT_CHECK='TRUE';
      NO_DIR_CHECK='TRUE';
      ALLOW_CONNECT='TRUE';
    'VSS'<16>:
      PIN_NUMBER='(0,0,248,0)';
      PINUSE='GROUND';
      NO_LOAD_CHECK='Both';
      NO_IO_CHECK='Both';
      NO_ASSERT_CHECK='TRUE';
      NO_DIR_CHECK='TRUE';
      ALLOW_CONNECT='TRUE';
    'VSS'<15>:
      PIN_NUMBER='(0,0,250,0)';
      PINUSE='GROUND';
      NO_LOAD_CHECK='Both';
      NO_IO_CHECK='Both';
      NO_ASSERT_CHECK='TRUE';
      NO_DIR_CHECK='TRUE';
      ALLOW_CONNECT='TRUE';
    'VSS'<14>:
      PIN_NUMBER='(0,0,252,0)';
      PINUSE='GROUND';
      NO_LOAD_CHECK='Both';
      NO_IO_CHECK='Both';
      NO_ASSERT_CHECK='TRUE';
      NO_DIR_CHECK='TRUE';
      ALLOW_CONNECT='TRUE';
    'VSS'<13>:
      PIN_NUMBER='(0,0,254,0)';
      PINUSE='GROUND';
      NO_LOAD_CHECK='Both';
      NO_IO_CHECK='Both';
      NO_ASSERT_CHECK='TRUE';
      NO_DIR_CHECK='TRUE';
      ALLOW_CONNECT='TRUE';
    'VSS'<12>:
      PIN_NUMBER='(0,0,257,0)';
      PINUSE='GROUND';
      NO_LOAD_CHECK='Both';
      NO_IO_CHECK='Both';
      NO_ASSERT_CHECK='TRUE';
      NO_DIR_CHECK='TRUE';
      ALLOW_CONNECT='TRUE';
    'VSS'<11>:
      PIN_NUMBER='(0,0,259,0)';
      PINUSE='GROUND';
      NO_LOAD_CHECK='Both';
      NO_IO_CHECK='Both';
      NO_ASSERT_CHECK='TRUE';
      NO_DIR_CHECK='TRUE';
      ALLOW_CONNECT='TRUE';
    'VSS'<10>:
      PIN_NUMBER='(0,0,261,0)';
      PINUSE='GROUND';
      NO_LOAD_CHECK='Both';
      NO_IO_CHECK='Both';
      NO_ASSERT_CHECK='TRUE';
      NO_DIR_CHECK='TRUE';
      ALLOW_CONNECT='TRUE';
    'VSS'<9>:
      PIN_NUMBER='(0,0,263,0)';
      PINUSE='GROUND';
      NO_LOAD_CHECK='Both';
      NO_IO_CHECK='Both';
      NO_ASSERT_CHECK='TRUE';
      NO_DIR_CHECK='TRUE';
      ALLOW_CONNECT='TRUE';
    'VSS'<8>:
      PIN_NUMBER='(0,0,265,0)';
      PINUSE='GROUND';
      NO_LOAD_CHECK='Both';
      NO_IO_CHECK='Both';
      NO_ASSERT_CHECK='TRUE';
      NO_DIR_CHECK='TRUE';
      ALLOW_CONNECT='TRUE';
    'VSS'<7>:
      PIN_NUMBER='(0,0,268,0)';
      PINUSE='GROUND';
      NO_LOAD_CHECK='Both';
      NO_IO_CHECK='Both';
      NO_ASSERT_CHECK='TRUE';
      NO_DIR_CHECK='TRUE';
      ALLOW_CONNECT='TRUE';
    'VSS'<6>:
      PIN_NUMBER='(0,0,270,0)';
      PINUSE='GROUND';
      NO_LOAD_CHECK='Both';
      NO_IO_CHECK='Both';
      NO_ASSERT_CHECK='TRUE';
      NO_DIR_CHECK='TRUE';
      ALLOW_CONNECT='TRUE';
    'VSS'<5>:
      PIN_NUMBER='(0,0,272,0)';
      PINUSE='GROUND';
      NO_LOAD_CHECK='Both';
      NO_IO_CHECK='Both';
      NO_ASSERT_CHECK='TRUE';
      NO_DIR_CHECK='TRUE';
      ALLOW_CONNECT='TRUE';
    'VSS'<4>:
      PIN_NUMBER='(0,0,274,0)';
      PINUSE='GROUND';
      NO_LOAD_CHECK='Both';
      NO_IO_CHECK='Both';
      NO_ASSERT_CHECK='TRUE';
      NO_DIR_CHECK='TRUE';
      ALLOW_CONNECT='TRUE';
    'VSS'<3>:
      PIN_NUMBER='(0,0,276,0)';
      PINUSE='GROUND';
      NO_LOAD_CHECK='Both';
      NO_IO_CHECK='Both';
      NO_ASSERT_CHECK='TRUE';
      NO_DIR_CHECK='TRUE';
      ALLOW_CONNECT='TRUE';
    'VSS'<2>:
      PIN_NUMBER='(0,0,279,0)';
      PINUSE='GROUND';
      NO_LOAD_CHECK='Both';
      NO_IO_CHECK='Both';
      NO_ASSERT_CHECK='TRUE';
      NO_DIR_CHECK='TRUE';
      ALLOW_CONNECT='TRUE';
    'VSS'<1>:
      PIN_NUMBER='(0,0,281,0)';
      PINUSE='GROUND';
      NO_LOAD_CHECK='Both';
      NO_IO_CHECK='Both';
      NO_ASSERT_CHECK='TRUE';
      NO_DIR_CHECK='TRUE';
      ALLOW_CONNECT='TRUE';
    'VSS'<0>:
      PIN_NUMBER='(0,0,283,0)';
      PINUSE='GROUND';
      NO_LOAD_CHECK='Both';
      NO_IO_CHECK='Both';
      NO_ASSERT_CHECK='TRUE';
      NO_DIR_CHECK='TRUE';
      ALLOW_CONNECT='TRUE';
    'VTT'<1>:
      PIN_NUMBER='(0,0,0,77)';
      PINUSE='POWER';
      NO_LOAD_CHECK='Both';
      NO_IO_CHECK='Both';
      NO_ASSERT_CHECK='TRUE';
      NO_DIR_CHECK='TRUE';
      ALLOW_CONNECT='TRUE';
    'VTT'<0>:
      PIN_NUMBER='(0,0,0,221)';
      PINUSE='POWER';
      NO_LOAD_CHECK='Both';
      NO_IO_CHECK='Both';
      NO_ASSERT_CHECK='TRUE';
      NO_DIR_CHECK='TRUE';
      ALLOW_CONNECT='TRUE';
  end_pin;
  body
      PART_NAME='SCONN288_H44441003';
      PHYS_DES_PREFIX='J';
      ENVCOMP='';
      PART_NUMBER='H44441-003';
      JEDEC_TYPE='SCONN288_H44441003_PIP';
      DESCRIPTION='(USE SYM 1-4)CONN,CEDG,288P,DDR4,VT,0.85mm,SMT,BK';
      CLASS='IO';
      COMPONENT_TYPE='SMTCONN';
      HEIGHT='0.839 IN';
      LPID='3551';
      SPEED_URL='http://speed.intel.com:8081/speed/module/pdm/item/pdm_item_deta~
il_direct.asp?item_cde=H44441-003&item_rev=01&url_param=unused';
      STATUS='';
      RPL='';
      AML='';
      BUS_UNIT='';
      DAYS='';
      PARENT_PART_TYPE='SCONN288_H44441003_PIP';
      PARENT_PPT='SCONN288_H44441003';
      PARENT_PPT_PART='SCONN288_H44441003_PIP-SCONN,H44441-003';
  end_body;
end_primitive;
primitive 'SCONN288_H44441004_PIP-SCONN,HA';
  pin
    '12V'<1>:
      PIN_NUMBER='(0,0,0,1)';
      PINUSE='POWER';
      NO_LOAD_CHECK='Both';
      NO_IO_CHECK='Both';
      NO_ASSERT_CHECK='TRUE';
      NO_DIR_CHECK='TRUE';
      ALLOW_CONNECT='TRUE';
    '12V'<0>:
      PIN_NUMBER='(0,0,0,145)';
      PINUSE='POWER';
      NO_LOAD_CHECK='Both';
      NO_IO_CHECK='Both';
      NO_ASSERT_CHECK='TRUE';
      NO_DIR_CHECK='TRUE';
      ALLOW_CONNECT='TRUE';
    'A0':
      PIN_NUMBER='(79,0,0,0)';
      BIDIRECTIONAL='TRUE';
      INPUT_LOAD='(-0.01,0.01)';
      OUTPUT_LOAD='(1.0,-1.0)';
      PINUSE='BI';
    'A1':
      PIN_NUMBER='(72,0,0,0)';
      BIDIRECTIONAL='TRUE';
      INPUT_LOAD='(-0.01,0.01)';
      OUTPUT_LOAD='(1.0,-1.0)';
      PINUSE='BI';
    'A10':
      PIN_NUMBER='(225,0,0,0)';
      BIDIRECTIONAL='TRUE';
      INPUT_LOAD='(-0.01,0.01)';
      OUTPUT_LOAD='(1.0,-1.0)';
      PINUSE='BI';
    'A11':
      PIN_NUMBER='(210,0,0,0)';
      BIDIRECTIONAL='TRUE';
      INPUT_LOAD='(-0.01,0.01)';
      OUTPUT_LOAD='(1.0,-1.0)';
      PINUSE='BI';
    'A12':
      PIN_NUMBER='(65,0,0,0)';
      BIDIRECTIONAL='TRUE';
      INPUT_LOAD='(-0.01,0.01)';
      OUTPUT_LOAD='(1.0,-1.0)';
      PINUSE='BI';
    'A13':
      PIN_NUMBER='(232,0,0,0)';
      BIDIRECTIONAL='TRUE';
      INPUT_LOAD='(-0.01,0.01)';
      OUTPUT_LOAD='(1.0,-1.0)';
      PINUSE='BI';
    'A14_WE_N':
      PIN_NUMBER='(228,0,0,0)';
      BIDIRECTIONAL='TRUE';
      INPUT_LOAD='(-0.01,0.01)';
      OUTPUT_LOAD='(1.0,-1.0)';
      PINUSE='BI';
    'A15_CAS_N':
      PIN_NUMBER='(86,0,0,0)';
      BIDIRECTIONAL='TRUE';
      INPUT_LOAD='(-0.01,0.01)';
      OUTPUT_LOAD='(1.0,-1.0)';
      PINUSE='BI';
    'A16_RAS_N':
      PIN_NUMBER='(82,0,0,0)';
      BIDIRECTIONAL='TRUE';
      INPUT_LOAD='(-0.01,0.01)';
      OUTPUT_LOAD='(1.0,-1.0)';
      PINUSE='BI';
    'A17':
      PIN_NUMBER='(234,0,0,0)';
      BIDIRECTIONAL='TRUE';
      INPUT_LOAD='(-0.01,0.01)';
      OUTPUT_LOAD='(1.0,-1.0)';
      PINUSE='BI';
    'A2':
      PIN_NUMBER='(216,0,0,0)';
      BIDIRECTIONAL='TRUE';
      INPUT_LOAD='(-0.01,0.01)';
      OUTPUT_LOAD='(1.0,-1.0)';
      PINUSE='BI';
    'A3':
      PIN_NUMBER='(71,0,0,0)';
      BIDIRECTIONAL='TRUE';
      INPUT_LOAD='(-0.01,0.01)';
      OUTPUT_LOAD='(1.0,-1.0)';
      PINUSE='BI';
    'A4':
      PIN_NUMBER='(214,0,0,0)';
      BIDIRECTIONAL='TRUE';
      INPUT_LOAD='(-0.01,0.01)';
      OUTPUT_LOAD='(1.0,-1.0)';
      PINUSE='BI';
    'A5':
      PIN_NUMBER='(213,0,0,0)';
      BIDIRECTIONAL='TRUE';
      INPUT_LOAD='(-0.01,0.01)';
      OUTPUT_LOAD='(1.0,-1.0)';
      PINUSE='BI';
    'A6':
      PIN_NUMBER='(69,0,0,0)';
      BIDIRECTIONAL='TRUE';
      INPUT_LOAD='(-0.01,0.01)';
      OUTPUT_LOAD='(1.0,-1.0)';
      PINUSE='BI';
    'A7':
      PIN_NUMBER='(211,0,0,0)';
      BIDIRECTIONAL='TRUE';
      INPUT_LOAD='(-0.01,0.01)';
      OUTPUT_LOAD='(1.0,-1.0)';
      PINUSE='BI';
    'A8':
      PIN_NUMBER='(68,0,0,0)';
      BIDIRECTIONAL='TRUE';
      INPUT_LOAD='(-0.01,0.01)';
      OUTPUT_LOAD='(1.0,-1.0)';
      PINUSE='BI';
    'A9':
      PIN_NUMBER='(66,0,0,0)';
      BIDIRECTIONAL='TRUE';
      INPUT_LOAD='(-0.01,0.01)';
      OUTPUT_LOAD='(1.0,-1.0)';
      PINUSE='BI';
    'ACT_N':
      PIN_NUMBER='(62,0,0,0)';
      BIDIRECTIONAL='TRUE';
      INPUT_LOAD='(-0.01,0.01)';
      OUTPUT_LOAD='(1.0,-1.0)';
      PINUSE='BI';
    'ALERT_N':
      PIN_NUMBER='(208,0,0,0)';
      BIDIRECTIONAL='TRUE';
      INPUT_LOAD='(-0.01,0.01)';
      OUTPUT_LOAD='(1.0,-1.0)';
      PINUSE='BI';
    'BA'<1>:
      PIN_NUMBER='(224,0,0,0)';
      BIDIRECTIONAL='TRUE';
      INPUT_LOAD='(-0.01,0.01)';
      OUTPUT_LOAD='(1.0,-1.0)';
      PINUSE='BI';
    'BA'<0>:
      PIN_NUMBER='(81,0,0,0)';
      BIDIRECTIONAL='TRUE';
      INPUT_LOAD='(-0.01,0.01)';
      OUTPUT_LOAD='(1.0,-1.0)';
      PINUSE='BI';
    'BG'<1>:
      PIN_NUMBER='(207,0,0,0)';
      BIDIRECTIONAL='TRUE';
      INPUT_LOAD='(-0.01,0.01)';
      OUTPUT_LOAD='(1.0,-1.0)';
      PINUSE='BI';
    'BG'<0>:
      PIN_NUMBER='(63,0,0,0)';
      BIDIRECTIONAL='TRUE';
      INPUT_LOAD='(-0.01,0.01)';
      OUTPUT_LOAD='(1.0,-1.0)';
      PINUSE='BI';
    'C'<2>:
      PIN_NUMBER='(235,0,0,0)';
      BIDIRECTIONAL='TRUE';
      INPUT_LOAD='(-0.01,0.01)';
      OUTPUT_LOAD='(1.0,-1.0)';
      PINUSE='BI';
    'CB'<7>:
      PIN_NUMBER='(199,0,0,0)';
      BIDIRECTIONAL='TRUE';
      INPUT_LOAD='(-0.01,0.01)';
      OUTPUT_LOAD='(1.0,-1.0)';
      PINUSE='BI';
    'CB'<6>:
      PIN_NUMBER='(54,0,0,0)';
      BIDIRECTIONAL='TRUE';
      INPUT_LOAD='(-0.01,0.01)';
      OUTPUT_LOAD='(1.0,-1.0)';
      PINUSE='BI';
    'CB'<5>:
      PIN_NUMBER='(192,0,0,0)';
      BIDIRECTIONAL='TRUE';
      INPUT_LOAD='(-0.01,0.01)';
      OUTPUT_LOAD='(1.0,-1.0)';
      PINUSE='BI';
    'CB'<4>:
      PIN_NUMBER='(47,0,0,0)';
      BIDIRECTIONAL='TRUE';
      INPUT_LOAD='(-0.01,0.01)';
      OUTPUT_LOAD='(1.0,-1.0)';
      PINUSE='BI';
    'CB'<3>:
      PIN_NUMBER='(201,0,0,0)';
      BIDIRECTIONAL='TRUE';
      INPUT_LOAD='(-0.01,0.01)';
      OUTPUT_LOAD='(1.0,-1.0)';
      PINUSE='BI';
    'CB'<2>:
      PIN_NUMBER='(56,0,0,0)';
      BIDIRECTIONAL='TRUE';
      INPUT_LOAD='(-0.01,0.01)';
      OUTPUT_LOAD='(1.0,-1.0)';
      PINUSE='BI';
    'CB'<1>:
      PIN_NUMBER='(194,0,0,0)';
      BIDIRECTIONAL='TRUE';
      INPUT_LOAD='(-0.01,0.01)';
      OUTPUT_LOAD='(1.0,-1.0)';
      PINUSE='BI';
    'CB'<0>:
      PIN_NUMBER='(49,0,0,0)';
      BIDIRECTIONAL='TRUE';
      INPUT_LOAD='(-0.01,0.01)';
      OUTPUT_LOAD='(1.0,-1.0)';
      PINUSE='BI';
    'CK0N':
      PIN_NUMBER='(75,0,0,0)';
      BIDIRECTIONAL='TRUE';
      INPUT_LOAD='(-0.01,0.01)';
      OUTPUT_LOAD='(1.0,-1.0)';
      PINUSE='BI';
    'CK0P':
      PIN_NUMBER='(74,0,0,0)';
      BIDIRECTIONAL='TRUE';
      INPUT_LOAD='(-0.01,0.01)';
      OUTPUT_LOAD='(1.0,-1.0)';
      PINUSE='BI';
    'CK1N':
      PIN_NUMBER='(219,0,0,0)';
      BIDIRECTIONAL='TRUE';
      INPUT_LOAD='(-0.01,0.01)';
      OUTPUT_LOAD='(1.0,-1.0)';
      PINUSE='BI';
    'CK1P':
      PIN_NUMBER='(218,0,0,0)';
      BIDIRECTIONAL='TRUE';
      INPUT_LOAD='(-0.01,0.01)';
      OUTPUT_LOAD='(1.0,-1.0)';
      PINUSE='BI';
    'CKE'<1>:
      PIN_NUMBER='(203,0,0,0)';
      BIDIRECTIONAL='TRUE';
      INPUT_LOAD='(-0.01,0.01)';
      OUTPUT_LOAD='(1.0,-1.0)';
      PINUSE='BI';
    'CKE'<0>:
      PIN_NUMBER='(60,0,0,0)';
      BIDIRECTIONAL='TRUE';
      INPUT_LOAD='(-0.01,0.01)';
      OUTPUT_LOAD='(1.0,-1.0)';
      PINUSE='BI';
    'DQ'<63>:
      PIN_NUMBER='(280,0,0,0)';
      BIDIRECTIONAL='TRUE';
      INPUT_LOAD='(-0.01,0.01)';
      OUTPUT_LOAD='(1.0,-1.0)';
      PINUSE='BI';
    'DQ'<62>:
      PIN_NUMBER='(135,0,0,0)';
      BIDIRECTIONAL='TRUE';
      INPUT_LOAD='(-0.01,0.01)';
      OUTPUT_LOAD='(1.0,-1.0)';
      PINUSE='BI';
    'DQ'<61>:
      PIN_NUMBER='(273,0,0,0)';
      BIDIRECTIONAL='TRUE';
      INPUT_LOAD='(-0.01,0.01)';
      OUTPUT_LOAD='(1.0,-1.0)';
      PINUSE='BI';
    'DQ'<60>:
      PIN_NUMBER='(128,0,0,0)';
      BIDIRECTIONAL='TRUE';
      INPUT_LOAD='(-0.01,0.01)';
      OUTPUT_LOAD='(1.0,-1.0)';
      PINUSE='BI';
    'DQ'<59>:
      PIN_NUMBER='(282,0,0,0)';
      BIDIRECTIONAL='TRUE';
      INPUT_LOAD='(-0.01,0.01)';
      OUTPUT_LOAD='(1.0,-1.0)';
      PINUSE='BI';
    'DQ'<58>:
      PIN_NUMBER='(137,0,0,0)';
      BIDIRECTIONAL='TRUE';
      INPUT_LOAD='(-0.01,0.01)';
      OUTPUT_LOAD='(1.0,-1.0)';
      PINUSE='BI';
    'DQ'<57>:
      PIN_NUMBER='(275,0,0,0)';
      BIDIRECTIONAL='TRUE';
      INPUT_LOAD='(-0.01,0.01)';
      OUTPUT_LOAD='(1.0,-1.0)';
      PINUSE='BI';
    'DQ'<56>:
      PIN_NUMBER='(130,0,0,0)';
      BIDIRECTIONAL='TRUE';
      INPUT_LOAD='(-0.01,0.01)';
      OUTPUT_LOAD='(1.0,-1.0)';
      PINUSE='BI';
    'DQ'<55>:
      PIN_NUMBER='(269,0,0,0)';
      BIDIRECTIONAL='TRUE';
      INPUT_LOAD='(-0.01,0.01)';
      OUTPUT_LOAD='(1.0,-1.0)';
      PINUSE='BI';
    'DQ'<54>:
      PIN_NUMBER='(124,0,0,0)';
      BIDIRECTIONAL='TRUE';
      INPUT_LOAD='(-0.01,0.01)';
      OUTPUT_LOAD='(1.0,-1.0)';
      PINUSE='BI';
    'DQ'<53>:
      PIN_NUMBER='(262,0,0,0)';
      BIDIRECTIONAL='TRUE';
      INPUT_LOAD='(-0.01,0.01)';
      OUTPUT_LOAD='(1.0,-1.0)';
      PINUSE='BI';
    'DQ'<52>:
      PIN_NUMBER='(117,0,0,0)';
      BIDIRECTIONAL='TRUE';
      INPUT_LOAD='(-0.01,0.01)';
      OUTPUT_LOAD='(1.0,-1.0)';
      PINUSE='BI';
    'DQ'<51>:
      PIN_NUMBER='(271,0,0,0)';
      BIDIRECTIONAL='TRUE';
      INPUT_LOAD='(-0.01,0.01)';
      OUTPUT_LOAD='(1.0,-1.0)';
      PINUSE='BI';
    'DQ'<50>:
      PIN_NUMBER='(126,0,0,0)';
      BIDIRECTIONAL='TRUE';
      INPUT_LOAD='(-0.01,0.01)';
      OUTPUT_LOAD='(1.0,-1.0)';
      PINUSE='BI';
    'DQ'<49>:
      PIN_NUMBER='(264,0,0,0)';
      BIDIRECTIONAL='TRUE';
      INPUT_LOAD='(-0.01,0.01)';
      OUTPUT_LOAD='(1.0,-1.0)';
      PINUSE='BI';
    'DQ'<48>:
      PIN_NUMBER='(119,0,0,0)';
      BIDIRECTIONAL='TRUE';
      INPUT_LOAD='(-0.01,0.01)';
      OUTPUT_LOAD='(1.0,-1.0)';
      PINUSE='BI';
    'DQ'<47>:
      PIN_NUMBER='(258,0,0,0)';
      BIDIRECTIONAL='TRUE';
      INPUT_LOAD='(-0.01,0.01)';
      OUTPUT_LOAD='(1.0,-1.0)';
      PINUSE='BI';
    'DQ'<46>:
      PIN_NUMBER='(113,0,0,0)';
      BIDIRECTIONAL='TRUE';
      INPUT_LOAD='(-0.01,0.01)';
      OUTPUT_LOAD='(1.0,-1.0)';
      PINUSE='BI';
    'DQ'<45>:
      PIN_NUMBER='(251,0,0,0)';
      BIDIRECTIONAL='TRUE';
      INPUT_LOAD='(-0.01,0.01)';
      OUTPUT_LOAD='(1.0,-1.0)';
      PINUSE='BI';
    'DQ'<44>:
      PIN_NUMBER='(106,0,0,0)';
      BIDIRECTIONAL='TRUE';
      INPUT_LOAD='(-0.01,0.01)';
      OUTPUT_LOAD='(1.0,-1.0)';
      PINUSE='BI';
    'DQ'<43>:
      PIN_NUMBER='(260,0,0,0)';
      BIDIRECTIONAL='TRUE';
      INPUT_LOAD='(-0.01,0.01)';
      OUTPUT_LOAD='(1.0,-1.0)';
      PINUSE='BI';
    'DQ'<42>:
      PIN_NUMBER='(115,0,0,0)';
      BIDIRECTIONAL='TRUE';
      INPUT_LOAD='(-0.01,0.01)';
      OUTPUT_LOAD='(1.0,-1.0)';
      PINUSE='BI';
    'DQ'<41>:
      PIN_NUMBER='(253,0,0,0)';
      BIDIRECTIONAL='TRUE';
      INPUT_LOAD='(-0.01,0.01)';
      OUTPUT_LOAD='(1.0,-1.0)';
      PINUSE='BI';
    'DQ'<40>:
      PIN_NUMBER='(108,0,0,0)';
      BIDIRECTIONAL='TRUE';
      INPUT_LOAD='(-0.01,0.01)';
      OUTPUT_LOAD='(1.0,-1.0)';
      PINUSE='BI';
    'DQ'<39>:
      PIN_NUMBER='(247,0,0,0)';
      BIDIRECTIONAL='TRUE';
      INPUT_LOAD='(-0.01,0.01)';
      OUTPUT_LOAD='(1.0,-1.0)';
      PINUSE='BI';
    'DQ'<38>:
      PIN_NUMBER='(102,0,0,0)';
      BIDIRECTIONAL='TRUE';
      INPUT_LOAD='(-0.01,0.01)';
      OUTPUT_LOAD='(1.0,-1.0)';
      PINUSE='BI';
    'DQ'<37>:
      PIN_NUMBER='(240,0,0,0)';
      BIDIRECTIONAL='TRUE';
      INPUT_LOAD='(-0.01,0.01)';
      OUTPUT_LOAD='(1.0,-1.0)';
      PINUSE='BI';
    'DQ'<36>:
      PIN_NUMBER='(95,0,0,0)';
      BIDIRECTIONAL='TRUE';
      INPUT_LOAD='(-0.01,0.01)';
      OUTPUT_LOAD='(1.0,-1.0)';
      PINUSE='BI';
    'DQ'<35>:
      PIN_NUMBER='(249,0,0,0)';
      BIDIRECTIONAL='TRUE';
      INPUT_LOAD='(-0.01,0.01)';
      OUTPUT_LOAD='(1.0,-1.0)';
      PINUSE='BI';
    'DQ'<34>:
      PIN_NUMBER='(104,0,0,0)';
      BIDIRECTIONAL='TRUE';
      INPUT_LOAD='(-0.01,0.01)';
      OUTPUT_LOAD='(1.0,-1.0)';
      PINUSE='BI';
    'DQ'<33>:
      PIN_NUMBER='(242,0,0,0)';
      BIDIRECTIONAL='TRUE';
      INPUT_LOAD='(-0.01,0.01)';
      OUTPUT_LOAD='(1.0,-1.0)';
      PINUSE='BI';
    'DQ'<32>:
      PIN_NUMBER='(97,0,0,0)';
      BIDIRECTIONAL='TRUE';
      INPUT_LOAD='(-0.01,0.01)';
      OUTPUT_LOAD='(1.0,-1.0)';
      PINUSE='BI';
    'DQ'<31>:
      PIN_NUMBER='(188,0,0,0)';
      BIDIRECTIONAL='TRUE';
      INPUT_LOAD='(-0.01,0.01)';
      OUTPUT_LOAD='(1.0,-1.0)';
      PINUSE='BI';
    'DQ'<30>:
      PIN_NUMBER='(43,0,0,0)';
      BIDIRECTIONAL='TRUE';
      INPUT_LOAD='(-0.01,0.01)';
      OUTPUT_LOAD='(1.0,-1.0)';
      PINUSE='BI';
    'DQ'<29>:
      PIN_NUMBER='(181,0,0,0)';
      BIDIRECTIONAL='TRUE';
      INPUT_LOAD='(-0.01,0.01)';
      OUTPUT_LOAD='(1.0,-1.0)';
      PINUSE='BI';
    'DQ'<28>:
      PIN_NUMBER='(36,0,0,0)';
      BIDIRECTIONAL='TRUE';
      INPUT_LOAD='(-0.01,0.01)';
      OUTPUT_LOAD='(1.0,-1.0)';
      PINUSE='BI';
    'DQ'<27>:
      PIN_NUMBER='(190,0,0,0)';
      BIDIRECTIONAL='TRUE';
      INPUT_LOAD='(-0.01,0.01)';
      OUTPUT_LOAD='(1.0,-1.0)';
      PINUSE='BI';
    'DQ'<26>:
      PIN_NUMBER='(45,0,0,0)';
      BIDIRECTIONAL='TRUE';
      INPUT_LOAD='(-0.01,0.01)';
      OUTPUT_LOAD='(1.0,-1.0)';
      PINUSE='BI';
    'DQ'<25>:
      PIN_NUMBER='(183,0,0,0)';
      BIDIRECTIONAL='TRUE';
      INPUT_LOAD='(-0.01,0.01)';
      OUTPUT_LOAD='(1.0,-1.0)';
      PINUSE='BI';
    'DQ'<24>:
      PIN_NUMBER='(38,0,0,0)';
      BIDIRECTIONAL='TRUE';
      INPUT_LOAD='(-0.01,0.01)';
      OUTPUT_LOAD='(1.0,-1.0)';
      PINUSE='BI';
    'DQ'<23>:
      PIN_NUMBER='(177,0,0,0)';
      BIDIRECTIONAL='TRUE';
      INPUT_LOAD='(-0.01,0.01)';
      OUTPUT_LOAD='(1.0,-1.0)';
      PINUSE='BI';
    'DQ'<22>:
      PIN_NUMBER='(32,0,0,0)';
      BIDIRECTIONAL='TRUE';
      INPUT_LOAD='(-0.01,0.01)';
      OUTPUT_LOAD='(1.0,-1.0)';
      PINUSE='BI';
    'DQ'<21>:
      PIN_NUMBER='(170,0,0,0)';
      BIDIRECTIONAL='TRUE';
      INPUT_LOAD='(-0.01,0.01)';
      OUTPUT_LOAD='(1.0,-1.0)';
      PINUSE='BI';
    'DQ'<20>:
      PIN_NUMBER='(25,0,0,0)';
      BIDIRECTIONAL='TRUE';
      INPUT_LOAD='(-0.01,0.01)';
      OUTPUT_LOAD='(1.0,-1.0)';
      PINUSE='BI';
    'DQ'<19>:
      PIN_NUMBER='(179,0,0,0)';
      BIDIRECTIONAL='TRUE';
      INPUT_LOAD='(-0.01,0.01)';
      OUTPUT_LOAD='(1.0,-1.0)';
      PINUSE='BI';
    'DQ'<18>:
      PIN_NUMBER='(34,0,0,0)';
      BIDIRECTIONAL='TRUE';
      INPUT_LOAD='(-0.01,0.01)';
      OUTPUT_LOAD='(1.0,-1.0)';
      PINUSE='BI';
    'DQ'<17>:
      PIN_NUMBER='(172,0,0,0)';
      BIDIRECTIONAL='TRUE';
      INPUT_LOAD='(-0.01,0.01)';
      OUTPUT_LOAD='(1.0,-1.0)';
      PINUSE='BI';
    'DQ'<16>:
      PIN_NUMBER='(27,0,0,0)';
      BIDIRECTIONAL='TRUE';
      INPUT_LOAD='(-0.01,0.01)';
      OUTPUT_LOAD='(1.0,-1.0)';
      PINUSE='BI';
    'DQ'<15>:
      PIN_NUMBER='(166,0,0,0)';
      BIDIRECTIONAL='TRUE';
      INPUT_LOAD='(-0.01,0.01)';
      OUTPUT_LOAD='(1.0,-1.0)';
      PINUSE='BI';
    'DQ'<14>:
      PIN_NUMBER='(21,0,0,0)';
      BIDIRECTIONAL='TRUE';
      INPUT_LOAD='(-0.01,0.01)';
      OUTPUT_LOAD='(1.0,-1.0)';
      PINUSE='BI';
    'DQ'<13>:
      PIN_NUMBER='(159,0,0,0)';
      BIDIRECTIONAL='TRUE';
      INPUT_LOAD='(-0.01,0.01)';
      OUTPUT_LOAD='(1.0,-1.0)';
      PINUSE='BI';
    'DQ'<12>:
      PIN_NUMBER='(14,0,0,0)';
      BIDIRECTIONAL='TRUE';
      INPUT_LOAD='(-0.01,0.01)';
      OUTPUT_LOAD='(1.0,-1.0)';
      PINUSE='BI';
    'DQ'<11>:
      PIN_NUMBER='(168,0,0,0)';
      BIDIRECTIONAL='TRUE';
      INPUT_LOAD='(-0.01,0.01)';
      OUTPUT_LOAD='(1.0,-1.0)';
      PINUSE='BI';
    'DQ'<10>:
      PIN_NUMBER='(23,0,0,0)';
      BIDIRECTIONAL='TRUE';
      INPUT_LOAD='(-0.01,0.01)';
      OUTPUT_LOAD='(1.0,-1.0)';
      PINUSE='BI';
    'DQ'<9>:
      PIN_NUMBER='(161,0,0,0)';
      BIDIRECTIONAL='TRUE';
      INPUT_LOAD='(-0.01,0.01)';
      OUTPUT_LOAD='(1.0,-1.0)';
      PINUSE='BI';
    'DQ'<8>:
      PIN_NUMBER='(16,0,0,0)';
      BIDIRECTIONAL='TRUE';
      INPUT_LOAD='(-0.01,0.01)';
      OUTPUT_LOAD='(1.0,-1.0)';
      PINUSE='BI';
    'DQ'<7>:
      PIN_NUMBER='(155,0,0,0)';
      BIDIRECTIONAL='TRUE';
      INPUT_LOAD='(-0.01,0.01)';
      OUTPUT_LOAD='(1.0,-1.0)';
      PINUSE='BI';
    'DQ'<6>:
      PIN_NUMBER='(10,0,0,0)';
      BIDIRECTIONAL='TRUE';
      INPUT_LOAD='(-0.01,0.01)';
      OUTPUT_LOAD='(1.0,-1.0)';
      PINUSE='BI';
    'DQ'<5>:
      PIN_NUMBER='(148,0,0,0)';
      BIDIRECTIONAL='TRUE';
      INPUT_LOAD='(-0.01,0.01)';
      OUTPUT_LOAD='(1.0,-1.0)';
      PINUSE='BI';
    'DQ'<4>:
      PIN_NUMBER='(3,0,0,0)';
      BIDIRECTIONAL='TRUE';
      INPUT_LOAD='(-0.01,0.01)';
      OUTPUT_LOAD='(1.0,-1.0)';
      PINUSE='BI';
    'DQ'<3>:
      PIN_NUMBER='(157,0,0,0)';
      BIDIRECTIONAL='TRUE';
      INPUT_LOAD='(-0.01,0.01)';
      OUTPUT_LOAD='(1.0,-1.0)';
      PINUSE='BI';
    'DQ'<2>:
      PIN_NUMBER='(12,0,0,0)';
      BIDIRECTIONAL='TRUE';
      INPUT_LOAD='(-0.01,0.01)';
      OUTPUT_LOAD='(1.0,-1.0)';
      PINUSE='BI';
    'DQ'<1>:
      PIN_NUMBER='(150,0,0,0)';
      BIDIRECTIONAL='TRUE';
      INPUT_LOAD='(-0.01,0.01)';
      OUTPUT_LOAD='(1.0,-1.0)';
      PINUSE='BI';
    'DQ'<0>:
      PIN_NUMBER='(5,0,0,0)';
      BIDIRECTIONAL='TRUE';
      INPUT_LOAD='(-0.01,0.01)';
      OUTPUT_LOAD='(1.0,-1.0)';
      PINUSE='BI';
    'DQS0N':
      PIN_NUMBER='(0,152,0,0)';
      BIDIRECTIONAL='TRUE';
      INPUT_LOAD='(-0.01,0.01)';
      OUTPUT_LOAD='(1.0,-1.0)';
      PINUSE='BI';
    'DQS0P':
      PIN_NUMBER='(0,153,0,0)';
      BIDIRECTIONAL='TRUE';
      INPUT_LOAD='(-0.01,0.01)';
      OUTPUT_LOAD='(1.0,-1.0)';
      PINUSE='BI';
    'DQS10N':
      PIN_NUMBER='(0,19,0,0)';
      BIDIRECTIONAL='TRUE';
      INPUT_LOAD='(-0.01,0.01)';
      OUTPUT_LOAD='(1.0,-1.0)';
      PINUSE='BI';
    'DQS10P':
      PIN_NUMBER='(0,18,0,0)';
      BIDIRECTIONAL='TRUE';
      INPUT_LOAD='(-0.01,0.01)';
      OUTPUT_LOAD='(1.0,-1.0)';
      PINUSE='BI';
    'DQS11N':
      PIN_NUMBER='(0,30,0,0)';
      BIDIRECTIONAL='TRUE';
      INPUT_LOAD='(-0.01,0.01)';
      OUTPUT_LOAD='(1.0,-1.0)';
      PINUSE='BI';
    'DQS11P':
      PIN_NUMBER='(0,29,0,0)';
      BIDIRECTIONAL='TRUE';
      INPUT_LOAD='(-0.01,0.01)';
      OUTPUT_LOAD='(1.0,-1.0)';
      PINUSE='BI';
    'DQS12N':
      PIN_NUMBER='(0,41,0,0)';
      BIDIRECTIONAL='TRUE';
      INPUT_LOAD='(-0.01,0.01)';
      OUTPUT_LOAD='(1.0,-1.0)';
      PINUSE='BI';
    'DQS12P':
      PIN_NUMBER='(0,40,0,0)';
      BIDIRECTIONAL='TRUE';
      INPUT_LOAD='(-0.01,0.01)';
      OUTPUT_LOAD='(1.0,-1.0)';
      PINUSE='BI';
    'DQS13N':
      PIN_NUMBER='(0,100,0,0)';
      BIDIRECTIONAL='TRUE';
      INPUT_LOAD='(-0.01,0.01)';
      OUTPUT_LOAD='(1.0,-1.0)';
      PINUSE='BI';
    'DQS13P':
      PIN_NUMBER='(0,99,0,0)';
      BIDIRECTIONAL='TRUE';
      INPUT_LOAD='(-0.01,0.01)';
      OUTPUT_LOAD='(1.0,-1.0)';
      PINUSE='BI';
    'DQS14N':
      PIN_NUMBER='(0,111,0,0)';
      BIDIRECTIONAL='TRUE';
      INPUT_LOAD='(-0.01,0.01)';
      OUTPUT_LOAD='(1.0,-1.0)';
      PINUSE='BI';
    'DQS14P':
      PIN_NUMBER='(0,110,0,0)';
      BIDIRECTIONAL='TRUE';
      INPUT_LOAD='(-0.01,0.01)';
      OUTPUT_LOAD='(1.0,-1.0)';
      PINUSE='BI';
    'DQS15N':
      PIN_NUMBER='(0,122,0,0)';
      BIDIRECTIONAL='TRUE';
      INPUT_LOAD='(-0.01,0.01)';
      OUTPUT_LOAD='(1.0,-1.0)';
      PINUSE='BI';
    'DQS15P':
      PIN_NUMBER='(0,121,0,0)';
      BIDIRECTIONAL='TRUE';
      INPUT_LOAD='(-0.01,0.01)';
      OUTPUT_LOAD='(1.0,-1.0)';
      PINUSE='BI';
    'DQS16N':
      PIN_NUMBER='(0,133,0,0)';
      BIDIRECTIONAL='TRUE';
      INPUT_LOAD='(-0.01,0.01)';
      OUTPUT_LOAD='(1.0,-1.0)';
      PINUSE='BI';
    'DQS16P':
      PIN_NUMBER='(0,132,0,0)';
      BIDIRECTIONAL='TRUE';
      INPUT_LOAD='(-0.01,0.01)';
      OUTPUT_LOAD='(1.0,-1.0)';
      PINUSE='BI';
    'DQS17N':
      PIN_NUMBER='(0,52,0,0)';
      BIDIRECTIONAL='TRUE';
      INPUT_LOAD='(-0.01,0.01)';
      OUTPUT_LOAD='(1.0,-1.0)';
      PINUSE='BI';
    'DQS17P':
      PIN_NUMBER='(0,51,0,0)';
      BIDIRECTIONAL='TRUE';
      INPUT_LOAD='(-0.01,0.01)';
      OUTPUT_LOAD='(1.0,-1.0)';
      PINUSE='BI';
    'DQS1N':
      PIN_NUMBER='(0,163,0,0)';
      BIDIRECTIONAL='TRUE';
      INPUT_LOAD='(-0.01,0.01)';
      OUTPUT_LOAD='(1.0,-1.0)';
      PINUSE='BI';
    'DQS1P':
      PIN_NUMBER='(0,164,0,0)';
      BIDIRECTIONAL='TRUE';
      INPUT_LOAD='(-0.01,0.01)';
      OUTPUT_LOAD='(1.0,-1.0)';
      PINUSE='BI';
    'DQS2N':
      PIN_NUMBER='(0,174,0,0)';
      BIDIRECTIONAL='TRUE';
      INPUT_LOAD='(-0.01,0.01)';
      OUTPUT_LOAD='(1.0,-1.0)';
      PINUSE='BI';
    'DQS2P':
      PIN_NUMBER='(0,175,0,0)';
      BIDIRECTIONAL='TRUE';
      INPUT_LOAD='(-0.01,0.01)';
      OUTPUT_LOAD='(1.0,-1.0)';
      PINUSE='BI';
    'DQS3N':
      PIN_NUMBER='(0,185,0,0)';
      BIDIRECTIONAL='TRUE';
      INPUT_LOAD='(-0.01,0.01)';
      OUTPUT_LOAD='(1.0,-1.0)';
      PINUSE='BI';
    'DQS3P':
      PIN_NUMBER='(0,186,0,0)';
      BIDIRECTIONAL='TRUE';
      INPUT_LOAD='(-0.01,0.01)';
      OUTPUT_LOAD='(1.0,-1.0)';
      PINUSE='BI';
    'DQS4N':
      PIN_NUMBER='(0,244,0,0)';
      BIDIRECTIONAL='TRUE';
      INPUT_LOAD='(-0.01,0.01)';
      OUTPUT_LOAD='(1.0,-1.0)';
      PINUSE='BI';
    'DQS4P':
      PIN_NUMBER='(0,245,0,0)';
      BIDIRECTIONAL='TRUE';
      INPUT_LOAD='(-0.01,0.01)';
      OUTPUT_LOAD='(1.0,-1.0)';
      PINUSE='BI';
    'DQS5N':
      PIN_NUMBER='(0,255,0,0)';
      BIDIRECTIONAL='TRUE';
      INPUT_LOAD='(-0.01,0.01)';
      OUTPUT_LOAD='(1.0,-1.0)';
      PINUSE='BI';
    'DQS5P':
      PIN_NUMBER='(0,256,0,0)';
      BIDIRECTIONAL='TRUE';
      INPUT_LOAD='(-0.01,0.01)';
      OUTPUT_LOAD='(1.0,-1.0)';
      PINUSE='BI';
    'DQS6N':
      PIN_NUMBER='(0,266,0,0)';
      BIDIRECTIONAL='TRUE';
      INPUT_LOAD='(-0.01,0.01)';
      OUTPUT_LOAD='(1.0,-1.0)';
      PINUSE='BI';
    'DQS6P':
      PIN_NUMBER='(0,267,0,0)';
      BIDIRECTIONAL='TRUE';
      INPUT_LOAD='(-0.01,0.01)';
      OUTPUT_LOAD='(1.0,-1.0)';
      PINUSE='BI';
    'DQS7N':
      PIN_NUMBER='(0,277,0,0)';
      BIDIRECTIONAL='TRUE';
      INPUT_LOAD='(-0.01,0.01)';
      OUTPUT_LOAD='(1.0,-1.0)';
      PINUSE='BI';
    'DQS7P':
      PIN_NUMBER='(0,278,0,0)';
      BIDIRECTIONAL='TRUE';
      INPUT_LOAD='(-0.01,0.01)';
      OUTPUT_LOAD='(1.0,-1.0)';
      PINUSE='BI';
    'DQS8N':
      PIN_NUMBER='(0,196,0,0)';
      BIDIRECTIONAL='TRUE';
      INPUT_LOAD='(-0.01,0.01)';
      OUTPUT_LOAD='(1.0,-1.0)';
      PINUSE='BI';
    'DQS8P':
      PIN_NUMBER='(0,197,0,0)';
      BIDIRECTIONAL='TRUE';
      INPUT_LOAD='(-0.01,0.01)';
      OUTPUT_LOAD='(1.0,-1.0)';
      PINUSE='BI';
    'DQS9N':
      PIN_NUMBER='(0,8,0,0)';
      BIDIRECTIONAL='TRUE';
      INPUT_LOAD='(-0.01,0.01)';
      OUTPUT_LOAD='(1.0,-1.0)';
      PINUSE='BI';
    'DQS9P':
      PIN_NUMBER='(0,7,0,0)';
      BIDIRECTIONAL='TRUE';
      INPUT_LOAD='(-0.01,0.01)';
      OUTPUT_LOAD='(1.0,-1.0)';
      PINUSE='BI';
    'EVENT_N':
      PIN_NUMBER='(78,0,0,0)';
      BIDIRECTIONAL='TRUE';
      INPUT_LOAD='(-0.01,0.01)';
      OUTPUT_LOAD='(1.0,-1.0)';
      PINUSE='BI';
    'ODT'<1>:
      PIN_NUMBER='(91,0,0,0)';
      BIDIRECTIONAL='TRUE';
      INPUT_LOAD='(-0.01,0.01)';
      OUTPUT_LOAD='(1.0,-1.0)';
      PINUSE='BI';
    'ODT'<0>:
      PIN_NUMBER='(87,0,0,0)';
      BIDIRECTIONAL='TRUE';
      INPUT_LOAD='(-0.01,0.01)';
      OUTPUT_LOAD='(1.0,-1.0)';
      PINUSE='BI';
    'PAR':
      PIN_NUMBER='(222,0,0,0)';
      BIDIRECTIONAL='TRUE';
      INPUT_LOAD='(-0.01,0.01)';
      OUTPUT_LOAD='(1.0,-1.0)';
      PINUSE='BI';
    'RESET_N':
      PIN_NUMBER='(58,0,0,0)';
      BIDIRECTIONAL='TRUE';
      INPUT_LOAD='(-0.01,0.01)';
      OUTPUT_LOAD='(1.0,-1.0)';
      PINUSE='BI';
    'RFU'<2>:
      PIN_NUMBER='(144,0,0,0)';
      BIDIRECTIONAL='TRUE';
      INPUT_LOAD='(-0.01,0.01)';
      OUTPUT_LOAD='(1.0,-1.0)';
      PINUSE='BI';
    'RFU'<1>:
      PIN_NUMBER='(227,0,0,0)';
      BIDIRECTIONAL='TRUE';
      INPUT_LOAD='(-0.01,0.01)';
      OUTPUT_LOAD='(1.0,-1.0)';
      PINUSE='BI';
    'RFU'<0>:
      PIN_NUMBER='(205,0,0,0)';
      BIDIRECTIONAL='TRUE';
      INPUT_LOAD='(-0.01,0.01)';
      OUTPUT_LOAD='(1.0,-1.0)';
      PINUSE='BI';
    'S0_N':
      PIN_NUMBER='(84,0,0,0)';
      BIDIRECTIONAL='TRUE';
      INPUT_LOAD='(-0.01,0.01)';
      OUTPUT_LOAD='(1.0,-1.0)';
      PINUSE='BI';
    'S1_N':
      PIN_NUMBER='(89,0,0,0)';
      BIDIRECTIONAL='TRUE';
      INPUT_LOAD='(-0.01,0.01)';
      OUTPUT_LOAD='(1.0,-1.0)';
      PINUSE='BI';
    'S2_N_C'<0>:
      PIN_NUMBER='(93,0,0,0)';
      BIDIRECTIONAL='TRUE';
      INPUT_LOAD='(-0.01,0.01)';
      OUTPUT_LOAD='(1.0,-1.0)';
      PINUSE='BI';
    'S3_N_C'<1>:
      PIN_NUMBER='(237,0,0,0)';
      BIDIRECTIONAL='TRUE';
      INPUT_LOAD='(-0.01,0.01)';
      OUTPUT_LOAD='(1.0,-1.0)';
      PINUSE='BI';
    'SA'<2>:
      PIN_NUMBER='(238,0,0,0)';
      BIDIRECTIONAL='TRUE';
      INPUT_LOAD='(-0.01,0.01)';
      OUTPUT_LOAD='(1.0,-1.0)';
      PINUSE='BI';
    'SA'<1>:
      PIN_NUMBER='(140,0,0,0)';
      BIDIRECTIONAL='TRUE';
      INPUT_LOAD='(-0.01,0.01)';
      OUTPUT_LOAD='(1.0,-1.0)';
      PINUSE='BI';
    'SA'<0>:
      PIN_NUMBER='(139,0,0,0)';
      BIDIRECTIONAL='TRUE';
      INPUT_LOAD='(-0.01,0.01)';
      OUTPUT_LOAD='(1.0,-1.0)';
      PINUSE='BI';
    'SAVE_N_NC':
      PIN_NUMBER='(230,0,0,0)';
      BIDIRECTIONAL='TRUE';
      INPUT_LOAD='(-0.01,0.01)';
      OUTPUT_LOAD='(1.0,-1.0)';
      PINUSE='BI';
    'SCL':
      PIN_NUMBER='(141,0,0,0)';
      BIDIRECTIONAL='TRUE';
      INPUT_LOAD='(-0.01,0.01)';
      OUTPUT_LOAD='(1.0,-1.0)';
      PINUSE='BI';
    'SDA':
      PIN_NUMBER='(285,0,0,0)';
      BIDIRECTIONAL='TRUE';
      INPUT_LOAD='(-0.01,0.01)';
      OUTPUT_LOAD='(1.0,-1.0)';
      PINUSE='BI';
    'VDD'<25>:
      PIN_NUMBER='(0,0,0,59)';
      PINUSE='POWER';
      NO_LOAD_CHECK='Both';
      NO_IO_CHECK='Both';
      NO_ASSERT_CHECK='TRUE';
      NO_DIR_CHECK='TRUE';
      ALLOW_CONNECT='TRUE';
    'VDD'<24>:
      PIN_NUMBER='(0,0,0,61)';
      PINUSE='POWER';
      NO_LOAD_CHECK='Both';
      NO_IO_CHECK='Both';
      NO_ASSERT_CHECK='TRUE';
      NO_DIR_CHECK='TRUE';
      ALLOW_CONNECT='TRUE';
    'VDD'<23>:
      PIN_NUMBER='(0,0,0,64)';
      PINUSE='POWER';
      NO_LOAD_CHECK='Both';
      NO_IO_CHECK='Both';
      NO_ASSERT_CHECK='TRUE';
      NO_DIR_CHECK='TRUE';
      ALLOW_CONNECT='TRUE';
    'VDD'<22>:
      PIN_NUMBER='(0,0,0,67)';
      PINUSE='POWER';
      NO_LOAD_CHECK='Both';
      NO_IO_CHECK='Both';
      NO_ASSERT_CHECK='TRUE';
      NO_DIR_CHECK='TRUE';
      ALLOW_CONNECT='TRUE';
    'VDD'<21>:
      PIN_NUMBER='(0,0,0,70)';
      PINUSE='POWER';
      NO_LOAD_CHECK='Both';
      NO_IO_CHECK='Both';
      NO_ASSERT_CHECK='TRUE';
      NO_DIR_CHECK='TRUE';
      ALLOW_CONNECT='TRUE';
    'VDD'<20>:
      PIN_NUMBER='(0,0,0,73)';
      PINUSE='POWER';
      NO_LOAD_CHECK='Both';
      NO_IO_CHECK='Both';
      NO_ASSERT_CHECK='TRUE';
      NO_DIR_CHECK='TRUE';
      ALLOW_CONNECT='TRUE';
    'VDD'<19>:
      PIN_NUMBER='(0,0,0,76)';
      PINUSE='POWER';
      NO_LOAD_CHECK='Both';
      NO_IO_CHECK='Both';
      NO_ASSERT_CHECK='TRUE';
      NO_DIR_CHECK='TRUE';
      ALLOW_CONNECT='TRUE';
    'VDD'<18>:
      PIN_NUMBER='(0,0,0,80)';
      PINUSE='POWER';
      NO_LOAD_CHECK='Both';
      NO_IO_CHECK='Both';
      NO_ASSERT_CHECK='TRUE';
      NO_DIR_CHECK='TRUE';
      ALLOW_CONNECT='TRUE';
    'VDD'<17>:
      PIN_NUMBER='(0,0,0,83)';
      PINUSE='POWER';
      NO_LOAD_CHECK='Both';
      NO_IO_CHECK='Both';
      NO_ASSERT_CHECK='TRUE';
      NO_DIR_CHECK='TRUE';
      ALLOW_CONNECT='TRUE';
    'VDD'<16>:
      PIN_NUMBER='(0,0,0,85)';
      PINUSE='POWER';
      NO_LOAD_CHECK='Both';
      NO_IO_CHECK='Both';
      NO_ASSERT_CHECK='TRUE';
      NO_DIR_CHECK='TRUE';
      ALLOW_CONNECT='TRUE';
    'VDD'<15>:
      PIN_NUMBER='(0,0,0,88)';
      PINUSE='POWER';
      NO_LOAD_CHECK='Both';
      NO_IO_CHECK='Both';
      NO_ASSERT_CHECK='TRUE';
      NO_DIR_CHECK='TRUE';
      ALLOW_CONNECT='TRUE';
    'VDD'<14>:
      PIN_NUMBER='(0,0,0,90)';
      PINUSE='POWER';
      NO_LOAD_CHECK='Both';
      NO_IO_CHECK='Both';
      NO_ASSERT_CHECK='TRUE';
      NO_DIR_CHECK='TRUE';
      ALLOW_CONNECT='TRUE';
    'VDD'<13>:
      PIN_NUMBER='(0,0,0,92)';
      PINUSE='POWER';
      NO_LOAD_CHECK='Both';
      NO_IO_CHECK='Both';
      NO_ASSERT_CHECK='TRUE';
      NO_DIR_CHECK='TRUE';
      ALLOW_CONNECT='TRUE';
    'VDD'<12>:
      PIN_NUMBER='(0,0,0,204)';
      PINUSE='POWER';
      NO_LOAD_CHECK='Both';
      NO_IO_CHECK='Both';
      NO_ASSERT_CHECK='TRUE';
      NO_DIR_CHECK='TRUE';
      ALLOW_CONNECT='TRUE';
    'VDD'<11>:
      PIN_NUMBER='(0,0,0,206)';
      PINUSE='POWER';
      NO_LOAD_CHECK='Both';
      NO_IO_CHECK='Both';
      NO_ASSERT_CHECK='TRUE';
      NO_DIR_CHECK='TRUE';
      ALLOW_CONNECT='TRUE';
    'VDD'<10>:
      PIN_NUMBER='(0,0,0,209)';
      PINUSE='POWER';
      NO_LOAD_CHECK='Both';
      NO_IO_CHECK='Both';
      NO_ASSERT_CHECK='TRUE';
      NO_DIR_CHECK='TRUE';
      ALLOW_CONNECT='TRUE';
    'VDD'<9>:
      PIN_NUMBER='(0,0,0,212)';
      PINUSE='POWER';
      NO_LOAD_CHECK='Both';
      NO_IO_CHECK='Both';
      NO_ASSERT_CHECK='TRUE';
      NO_DIR_CHECK='TRUE';
      ALLOW_CONNECT='TRUE';
    'VDD'<8>:
      PIN_NUMBER='(0,0,0,215)';
      PINUSE='POWER';
      NO_LOAD_CHECK='Both';
      NO_IO_CHECK='Both';
      NO_ASSERT_CHECK='TRUE';
      NO_DIR_CHECK='TRUE';
      ALLOW_CONNECT='TRUE';
    'VDD'<7>:
      PIN_NUMBER='(0,0,0,217)';
      PINUSE='POWER';
      NO_LOAD_CHECK='Both';
      NO_IO_CHECK='Both';
      NO_ASSERT_CHECK='TRUE';
      NO_DIR_CHECK='TRUE';
      ALLOW_CONNECT='TRUE';
    'VDD'<6>:
      PIN_NUMBER='(0,0,0,220)';
      PINUSE='POWER';
      NO_LOAD_CHECK='Both';
      NO_IO_CHECK='Both';
      NO_ASSERT_CHECK='TRUE';
      NO_DIR_CHECK='TRUE';
      ALLOW_CONNECT='TRUE';
    'VDD'<5>:
      PIN_NUMBER='(0,0,0,223)';
      PINUSE='POWER';
      NO_LOAD_CHECK='Both';
      NO_IO_CHECK='Both';
      NO_ASSERT_CHECK='TRUE';
      NO_DIR_CHECK='TRUE';
      ALLOW_CONNECT='TRUE';
    'VDD'<4>:
      PIN_NUMBER='(0,0,0,226)';
      PINUSE='POWER';
      NO_LOAD_CHECK='Both';
      NO_IO_CHECK='Both';
      NO_ASSERT_CHECK='TRUE';
      NO_DIR_CHECK='TRUE';
      ALLOW_CONNECT='TRUE';
    'VDD'<3>:
      PIN_NUMBER='(0,0,0,229)';
      PINUSE='POWER';
      NO_LOAD_CHECK='Both';
      NO_IO_CHECK='Both';
      NO_ASSERT_CHECK='TRUE';
      NO_DIR_CHECK='TRUE';
      ALLOW_CONNECT='TRUE';
    'VDD'<2>:
      PIN_NUMBER='(0,0,0,231)';
      PINUSE='POWER';
      NO_LOAD_CHECK='Both';
      NO_IO_CHECK='Both';
      NO_ASSERT_CHECK='TRUE';
      NO_DIR_CHECK='TRUE';
      ALLOW_CONNECT='TRUE';
    'VDD'<1>:
      PIN_NUMBER='(0,0,0,233)';
      PINUSE='POWER';
      NO_LOAD_CHECK='Both';
      NO_IO_CHECK='Both';
      NO_ASSERT_CHECK='TRUE';
      NO_DIR_CHECK='TRUE';
      ALLOW_CONNECT='TRUE';
    'VDD'<0>:
      PIN_NUMBER='(0,0,0,236)';
      PINUSE='POWER';
      NO_LOAD_CHECK='Both';
      NO_IO_CHECK='Both';
      NO_ASSERT_CHECK='TRUE';
      NO_DIR_CHECK='TRUE';
      ALLOW_CONNECT='TRUE';
    'VDDSPD':
      PIN_NUMBER='(284,0,0,0)';
      BIDIRECTIONAL='TRUE';
      INPUT_LOAD='(-0.01,0.01)';
      OUTPUT_LOAD='(1.0,-1.0)';
      PINUSE='BI';
    'VPP'<4>:
      PIN_NUMBER='(0,0,0,142)';
      PINUSE='POWER';
      NO_LOAD_CHECK='Both';
      NO_IO_CHECK='Both';
      NO_ASSERT_CHECK='TRUE';
      NO_DIR_CHECK='TRUE';
      ALLOW_CONNECT='TRUE';
    'VPP'<3>:
      PIN_NUMBER='(0,0,0,143)';
      PINUSE='POWER';
      NO_LOAD_CHECK='Both';
      NO_IO_CHECK='Both';
      NO_ASSERT_CHECK='TRUE';
      NO_DIR_CHECK='TRUE';
      ALLOW_CONNECT='TRUE';
    'VPP'<2>:
      PIN_NUMBER='(0,0,0,288)';
      PINUSE='POWER';
      NO_LOAD_CHECK='Both';
      NO_IO_CHECK='Both';
      NO_ASSERT_CHECK='TRUE';
      NO_DIR_CHECK='TRUE';
      ALLOW_CONNECT='TRUE';
    'VPP'<1>:
      PIN_NUMBER='(0,0,0,286)';
      PINUSE='POWER';
      NO_LOAD_CHECK='Both';
      NO_IO_CHECK='Both';
      NO_ASSERT_CHECK='TRUE';
      NO_DIR_CHECK='TRUE';
      ALLOW_CONNECT='TRUE';
    'VPP'<0>:
      PIN_NUMBER='(0,0,0,287)';
      PINUSE='POWER';
      NO_LOAD_CHECK='Both';
      NO_IO_CHECK='Both';
      NO_ASSERT_CHECK='TRUE';
      NO_DIR_CHECK='TRUE';
      ALLOW_CONNECT='TRUE';
    'VREFCA':
      PIN_NUMBER='(146,0,0,0)';
      BIDIRECTIONAL='TRUE';
      INPUT_LOAD='(-0.01,0.01)';
      OUTPUT_LOAD='(1.0,-1.0)';
      PINUSE='BI';
    'VSS'<93>:
      PIN_NUMBER='(0,0,2,0)';
      PINUSE='GROUND';
      NO_LOAD_CHECK='Both';
      NO_IO_CHECK='Both';
      NO_ASSERT_CHECK='TRUE';
      NO_DIR_CHECK='TRUE';
      ALLOW_CONNECT='TRUE';
    'VSS'<92>:
      PIN_NUMBER='(0,0,4,0)';
      PINUSE='GROUND';
      NO_LOAD_CHECK='Both';
      NO_IO_CHECK='Both';
      NO_ASSERT_CHECK='TRUE';
      NO_DIR_CHECK='TRUE';
      ALLOW_CONNECT='TRUE';
    'VSS'<91>:
      PIN_NUMBER='(0,0,6,0)';
      PINUSE='GROUND';
      NO_LOAD_CHECK='Both';
      NO_IO_CHECK='Both';
      NO_ASSERT_CHECK='TRUE';
      NO_DIR_CHECK='TRUE';
      ALLOW_CONNECT='TRUE';
    'VSS'<90>:
      PIN_NUMBER='(0,0,9,0)';
      PINUSE='GROUND';
      NO_LOAD_CHECK='Both';
      NO_IO_CHECK='Both';
      NO_ASSERT_CHECK='TRUE';
      NO_DIR_CHECK='TRUE';
      ALLOW_CONNECT='TRUE';
    'VSS'<89>:
      PIN_NUMBER='(0,0,11,0)';
      PINUSE='GROUND';
      NO_LOAD_CHECK='Both';
      NO_IO_CHECK='Both';
      NO_ASSERT_CHECK='TRUE';
      NO_DIR_CHECK='TRUE';
      ALLOW_CONNECT='TRUE';
    'VSS'<88>:
      PIN_NUMBER='(0,0,13,0)';
      PINUSE='GROUND';
      NO_LOAD_CHECK='Both';
      NO_IO_CHECK='Both';
      NO_ASSERT_CHECK='TRUE';
      NO_DIR_CHECK='TRUE';
      ALLOW_CONNECT='TRUE';
    'VSS'<87>:
      PIN_NUMBER='(0,0,15,0)';
      PINUSE='GROUND';
      NO_LOAD_CHECK='Both';
      NO_IO_CHECK='Both';
      NO_ASSERT_CHECK='TRUE';
      NO_DIR_CHECK='TRUE';
      ALLOW_CONNECT='TRUE';
    'VSS'<86>:
      PIN_NUMBER='(0,0,17,0)';
      PINUSE='GROUND';
      NO_LOAD_CHECK='Both';
      NO_IO_CHECK='Both';
      NO_ASSERT_CHECK='TRUE';
      NO_DIR_CHECK='TRUE';
      ALLOW_CONNECT='TRUE';
    'VSS'<85>:
      PIN_NUMBER='(0,0,20,0)';
      PINUSE='GROUND';
      NO_LOAD_CHECK='Both';
      NO_IO_CHECK='Both';
      NO_ASSERT_CHECK='TRUE';
      NO_DIR_CHECK='TRUE';
      ALLOW_CONNECT='TRUE';
    'VSS'<84>:
      PIN_NUMBER='(0,0,22,0)';
      PINUSE='GROUND';
      NO_LOAD_CHECK='Both';
      NO_IO_CHECK='Both';
      NO_ASSERT_CHECK='TRUE';
      NO_DIR_CHECK='TRUE';
      ALLOW_CONNECT='TRUE';
    'VSS'<83>:
      PIN_NUMBER='(0,0,24,0)';
      PINUSE='GROUND';
      NO_LOAD_CHECK='Both';
      NO_IO_CHECK='Both';
      NO_ASSERT_CHECK='TRUE';
      NO_DIR_CHECK='TRUE';
      ALLOW_CONNECT='TRUE';
    'VSS'<82>:
      PIN_NUMBER='(0,0,26,0)';
      PINUSE='GROUND';
      NO_LOAD_CHECK='Both';
      NO_IO_CHECK='Both';
      NO_ASSERT_CHECK='TRUE';
      NO_DIR_CHECK='TRUE';
      ALLOW_CONNECT='TRUE';
    'VSS'<81>:
      PIN_NUMBER='(0,0,28,0)';
      PINUSE='GROUND';
      NO_LOAD_CHECK='Both';
      NO_IO_CHECK='Both';
      NO_ASSERT_CHECK='TRUE';
      NO_DIR_CHECK='TRUE';
      ALLOW_CONNECT='TRUE';
    'VSS'<80>:
      PIN_NUMBER='(0,0,31,0)';
      PINUSE='GROUND';
      NO_LOAD_CHECK='Both';
      NO_IO_CHECK='Both';
      NO_ASSERT_CHECK='TRUE';
      NO_DIR_CHECK='TRUE';
      ALLOW_CONNECT='TRUE';
    'VSS'<79>:
      PIN_NUMBER='(0,0,33,0)';
      PINUSE='GROUND';
      NO_LOAD_CHECK='Both';
      NO_IO_CHECK='Both';
      NO_ASSERT_CHECK='TRUE';
      NO_DIR_CHECK='TRUE';
      ALLOW_CONNECT='TRUE';
    'VSS'<78>:
      PIN_NUMBER='(0,0,35,0)';
      PINUSE='GROUND';
      NO_LOAD_CHECK='Both';
      NO_IO_CHECK='Both';
      NO_ASSERT_CHECK='TRUE';
      NO_DIR_CHECK='TRUE';
      ALLOW_CONNECT='TRUE';
    'VSS'<77>:
      PIN_NUMBER='(0,0,37,0)';
      PINUSE='GROUND';
      NO_LOAD_CHECK='Both';
      NO_IO_CHECK='Both';
      NO_ASSERT_CHECK='TRUE';
      NO_DIR_CHECK='TRUE';
      ALLOW_CONNECT='TRUE';
    'VSS'<76>:
      PIN_NUMBER='(0,0,39,0)';
      PINUSE='GROUND';
      NO_LOAD_CHECK='Both';
      NO_IO_CHECK='Both';
      NO_ASSERT_CHECK='TRUE';
      NO_DIR_CHECK='TRUE';
      ALLOW_CONNECT='TRUE';
    'VSS'<75>:
      PIN_NUMBER='(0,0,42,0)';
      PINUSE='GROUND';
      NO_LOAD_CHECK='Both';
      NO_IO_CHECK='Both';
      NO_ASSERT_CHECK='TRUE';
      NO_DIR_CHECK='TRUE';
      ALLOW_CONNECT='TRUE';
    'VSS'<74>:
      PIN_NUMBER='(0,0,44,0)';
      PINUSE='GROUND';
      NO_LOAD_CHECK='Both';
      NO_IO_CHECK='Both';
      NO_ASSERT_CHECK='TRUE';
      NO_DIR_CHECK='TRUE';
      ALLOW_CONNECT='TRUE';
    'VSS'<73>:
      PIN_NUMBER='(0,0,46,0)';
      PINUSE='GROUND';
      NO_LOAD_CHECK='Both';
      NO_IO_CHECK='Both';
      NO_ASSERT_CHECK='TRUE';
      NO_DIR_CHECK='TRUE';
      ALLOW_CONNECT='TRUE';
    'VSS'<72>:
      PIN_NUMBER='(0,0,48,0)';
      PINUSE='GROUND';
      NO_LOAD_CHECK='Both';
      NO_IO_CHECK='Both';
      NO_ASSERT_CHECK='TRUE';
      NO_DIR_CHECK='TRUE';
      ALLOW_CONNECT='TRUE';
    'VSS'<71>:
      PIN_NUMBER='(0,0,50,0)';
      PINUSE='GROUND';
      NO_LOAD_CHECK='Both';
      NO_IO_CHECK='Both';
      NO_ASSERT_CHECK='TRUE';
      NO_DIR_CHECK='TRUE';
      ALLOW_CONNECT='TRUE';
    'VSS'<70>:
      PIN_NUMBER='(0,0,53,0)';
      PINUSE='GROUND';
      NO_LOAD_CHECK='Both';
      NO_IO_CHECK='Both';
      NO_ASSERT_CHECK='TRUE';
      NO_DIR_CHECK='TRUE';
      ALLOW_CONNECT='TRUE';
    'VSS'<69>:
      PIN_NUMBER='(0,0,55,0)';
      PINUSE='GROUND';
      NO_LOAD_CHECK='Both';
      NO_IO_CHECK='Both';
      NO_ASSERT_CHECK='TRUE';
      NO_DIR_CHECK='TRUE';
      ALLOW_CONNECT='TRUE';
    'VSS'<68>:
      PIN_NUMBER='(0,0,57,0)';
      PINUSE='GROUND';
      NO_LOAD_CHECK='Both';
      NO_IO_CHECK='Both';
      NO_ASSERT_CHECK='TRUE';
      NO_DIR_CHECK='TRUE';
      ALLOW_CONNECT='TRUE';
    'VSS'<67>:
      PIN_NUMBER='(0,0,94,0)';
      PINUSE='GROUND';
      NO_LOAD_CHECK='Both';
      NO_IO_CHECK='Both';
      NO_ASSERT_CHECK='TRUE';
      NO_DIR_CHECK='TRUE';
      ALLOW_CONNECT='TRUE';
    'VSS'<66>:
      PIN_NUMBER='(0,0,96,0)';
      PINUSE='GROUND';
      NO_LOAD_CHECK='Both';
      NO_IO_CHECK='Both';
      NO_ASSERT_CHECK='TRUE';
      NO_DIR_CHECK='TRUE';
      ALLOW_CONNECT='TRUE';
    'VSS'<65>:
      PIN_NUMBER='(0,0,98,0)';
      PINUSE='GROUND';
      NO_LOAD_CHECK='Both';
      NO_IO_CHECK='Both';
      NO_ASSERT_CHECK='TRUE';
      NO_DIR_CHECK='TRUE';
      ALLOW_CONNECT='TRUE';
    'VSS'<64>:
      PIN_NUMBER='(0,0,101,0)';
      PINUSE='GROUND';
      NO_LOAD_CHECK='Both';
      NO_IO_CHECK='Both';
      NO_ASSERT_CHECK='TRUE';
      NO_DIR_CHECK='TRUE';
      ALLOW_CONNECT='TRUE';
    'VSS'<63>:
      PIN_NUMBER='(0,0,103,0)';
      PINUSE='GROUND';
      NO_LOAD_CHECK='Both';
      NO_IO_CHECK='Both';
      NO_ASSERT_CHECK='TRUE';
      NO_DIR_CHECK='TRUE';
      ALLOW_CONNECT='TRUE';
    'VSS'<62>:
      PIN_NUMBER='(0,0,105,0)';
      PINUSE='GROUND';
      NO_LOAD_CHECK='Both';
      NO_IO_CHECK='Both';
      NO_ASSERT_CHECK='TRUE';
      NO_DIR_CHECK='TRUE';
      ALLOW_CONNECT='TRUE';
    'VSS'<61>:
      PIN_NUMBER='(0,0,107,0)';
      PINUSE='GROUND';
      NO_LOAD_CHECK='Both';
      NO_IO_CHECK='Both';
      NO_ASSERT_CHECK='TRUE';
      NO_DIR_CHECK='TRUE';
      ALLOW_CONNECT='TRUE';
    'VSS'<60>:
      PIN_NUMBER='(0,0,109,0)';
      PINUSE='GROUND';
      NO_LOAD_CHECK='Both';
      NO_IO_CHECK='Both';
      NO_ASSERT_CHECK='TRUE';
      NO_DIR_CHECK='TRUE';
      ALLOW_CONNECT='TRUE';
    'VSS'<59>:
      PIN_NUMBER='(0,0,112,0)';
      PINUSE='GROUND';
      NO_LOAD_CHECK='Both';
      NO_IO_CHECK='Both';
      NO_ASSERT_CHECK='TRUE';
      NO_DIR_CHECK='TRUE';
      ALLOW_CONNECT='TRUE';
    'VSS'<58>:
      PIN_NUMBER='(0,0,114,0)';
      PINUSE='GROUND';
      NO_LOAD_CHECK='Both';
      NO_IO_CHECK='Both';
      NO_ASSERT_CHECK='TRUE';
      NO_DIR_CHECK='TRUE';
      ALLOW_CONNECT='TRUE';
    'VSS'<57>:
      PIN_NUMBER='(0,0,116,0)';
      PINUSE='GROUND';
      NO_LOAD_CHECK='Both';
      NO_IO_CHECK='Both';
      NO_ASSERT_CHECK='TRUE';
      NO_DIR_CHECK='TRUE';
      ALLOW_CONNECT='TRUE';
    'VSS'<56>:
      PIN_NUMBER='(0,0,118,0)';
      PINUSE='GROUND';
      NO_LOAD_CHECK='Both';
      NO_IO_CHECK='Both';
      NO_ASSERT_CHECK='TRUE';
      NO_DIR_CHECK='TRUE';
      ALLOW_CONNECT='TRUE';
    'VSS'<55>:
      PIN_NUMBER='(0,0,120,0)';
      PINUSE='GROUND';
      NO_LOAD_CHECK='Both';
      NO_IO_CHECK='Both';
      NO_ASSERT_CHECK='TRUE';
      NO_DIR_CHECK='TRUE';
      ALLOW_CONNECT='TRUE';
    'VSS'<54>:
      PIN_NUMBER='(0,0,123,0)';
      PINUSE='GROUND';
      NO_LOAD_CHECK='Both';
      NO_IO_CHECK='Both';
      NO_ASSERT_CHECK='TRUE';
      NO_DIR_CHECK='TRUE';
      ALLOW_CONNECT='TRUE';
    'VSS'<53>:
      PIN_NUMBER='(0,0,125,0)';
      PINUSE='GROUND';
      NO_LOAD_CHECK='Both';
      NO_IO_CHECK='Both';
      NO_ASSERT_CHECK='TRUE';
      NO_DIR_CHECK='TRUE';
      ALLOW_CONNECT='TRUE';
    'VSS'<52>:
      PIN_NUMBER='(0,0,127,0)';
      PINUSE='GROUND';
      NO_LOAD_CHECK='Both';
      NO_IO_CHECK='Both';
      NO_ASSERT_CHECK='TRUE';
      NO_DIR_CHECK='TRUE';
      ALLOW_CONNECT='TRUE';
    'VSS'<51>:
      PIN_NUMBER='(0,0,129,0)';
      PINUSE='GROUND';
      NO_LOAD_CHECK='Both';
      NO_IO_CHECK='Both';
      NO_ASSERT_CHECK='TRUE';
      NO_DIR_CHECK='TRUE';
      ALLOW_CONNECT='TRUE';
    'VSS'<50>:
      PIN_NUMBER='(0,0,131,0)';
      PINUSE='GROUND';
      NO_LOAD_CHECK='Both';
      NO_IO_CHECK='Both';
      NO_ASSERT_CHECK='TRUE';
      NO_DIR_CHECK='TRUE';
      ALLOW_CONNECT='TRUE';
    'VSS'<49>:
      PIN_NUMBER='(0,0,134,0)';
      PINUSE='GROUND';
      NO_LOAD_CHECK='Both';
      NO_IO_CHECK='Both';
      NO_ASSERT_CHECK='TRUE';
      NO_DIR_CHECK='TRUE';
      ALLOW_CONNECT='TRUE';
    'VSS'<48>:
      PIN_NUMBER='(0,0,136,0)';
      PINUSE='GROUND';
      NO_LOAD_CHECK='Both';
      NO_IO_CHECK='Both';
      NO_ASSERT_CHECK='TRUE';
      NO_DIR_CHECK='TRUE';
      ALLOW_CONNECT='TRUE';
    'VSS'<47>:
      PIN_NUMBER='(0,0,138,0)';
      PINUSE='GROUND';
      NO_LOAD_CHECK='Both';
      NO_IO_CHECK='Both';
      NO_ASSERT_CHECK='TRUE';
      NO_DIR_CHECK='TRUE';
      ALLOW_CONNECT='TRUE';
    'VSS'<46>:
      PIN_NUMBER='(0,0,147,0)';
      PINUSE='GROUND';
      NO_LOAD_CHECK='Both';
      NO_IO_CHECK='Both';
      NO_ASSERT_CHECK='TRUE';
      NO_DIR_CHECK='TRUE';
      ALLOW_CONNECT='TRUE';
    'VSS'<45>:
      PIN_NUMBER='(0,0,149,0)';
      PINUSE='GROUND';
      NO_LOAD_CHECK='Both';
      NO_IO_CHECK='Both';
      NO_ASSERT_CHECK='TRUE';
      NO_DIR_CHECK='TRUE';
      ALLOW_CONNECT='TRUE';
    'VSS'<44>:
      PIN_NUMBER='(0,0,151,0)';
      PINUSE='GROUND';
      NO_LOAD_CHECK='Both';
      NO_IO_CHECK='Both';
      NO_ASSERT_CHECK='TRUE';
      NO_DIR_CHECK='TRUE';
      ALLOW_CONNECT='TRUE';
    'VSS'<43>:
      PIN_NUMBER='(0,0,154,0)';
      PINUSE='GROUND';
      NO_LOAD_CHECK='Both';
      NO_IO_CHECK='Both';
      NO_ASSERT_CHECK='TRUE';
      NO_DIR_CHECK='TRUE';
      ALLOW_CONNECT='TRUE';
    'VSS'<42>:
      PIN_NUMBER='(0,0,156,0)';
      PINUSE='GROUND';
      NO_LOAD_CHECK='Both';
      NO_IO_CHECK='Both';
      NO_ASSERT_CHECK='TRUE';
      NO_DIR_CHECK='TRUE';
      ALLOW_CONNECT='TRUE';
    'VSS'<41>:
      PIN_NUMBER='(0,0,158,0)';
      PINUSE='GROUND';
      NO_LOAD_CHECK='Both';
      NO_IO_CHECK='Both';
      NO_ASSERT_CHECK='TRUE';
      NO_DIR_CHECK='TRUE';
      ALLOW_CONNECT='TRUE';
    'VSS'<40>:
      PIN_NUMBER='(0,0,160,0)';
      PINUSE='GROUND';
      NO_LOAD_CHECK='Both';
      NO_IO_CHECK='Both';
      NO_ASSERT_CHECK='TRUE';
      NO_DIR_CHECK='TRUE';
      ALLOW_CONNECT='TRUE';
    'VSS'<39>:
      PIN_NUMBER='(0,0,162,0)';
      PINUSE='GROUND';
      NO_LOAD_CHECK='Both';
      NO_IO_CHECK='Both';
      NO_ASSERT_CHECK='TRUE';
      NO_DIR_CHECK='TRUE';
      ALLOW_CONNECT='TRUE';
    'VSS'<38>:
      PIN_NUMBER='(0,0,165,0)';
      PINUSE='GROUND';
      NO_LOAD_CHECK='Both';
      NO_IO_CHECK='Both';
      NO_ASSERT_CHECK='TRUE';
      NO_DIR_CHECK='TRUE';
      ALLOW_CONNECT='TRUE';
    'VSS'<37>:
      PIN_NUMBER='(0,0,167,0)';
      PINUSE='GROUND';
      NO_LOAD_CHECK='Both';
      NO_IO_CHECK='Both';
      NO_ASSERT_CHECK='TRUE';
      NO_DIR_CHECK='TRUE';
      ALLOW_CONNECT='TRUE';
    'VSS'<36>:
      PIN_NUMBER='(0,0,169,0)';
      PINUSE='GROUND';
      NO_LOAD_CHECK='Both';
      NO_IO_CHECK='Both';
      NO_ASSERT_CHECK='TRUE';
      NO_DIR_CHECK='TRUE';
      ALLOW_CONNECT='TRUE';
    'VSS'<35>:
      PIN_NUMBER='(0,0,171,0)';
      PINUSE='GROUND';
      NO_LOAD_CHECK='Both';
      NO_IO_CHECK='Both';
      NO_ASSERT_CHECK='TRUE';
      NO_DIR_CHECK='TRUE';
      ALLOW_CONNECT='TRUE';
    'VSS'<34>:
      PIN_NUMBER='(0,0,173,0)';
      PINUSE='GROUND';
      NO_LOAD_CHECK='Both';
      NO_IO_CHECK='Both';
      NO_ASSERT_CHECK='TRUE';
      NO_DIR_CHECK='TRUE';
      ALLOW_CONNECT='TRUE';
    'VSS'<33>:
      PIN_NUMBER='(0,0,176,0)';
      PINUSE='GROUND';
      NO_LOAD_CHECK='Both';
      NO_IO_CHECK='Both';
      NO_ASSERT_CHECK='TRUE';
      NO_DIR_CHECK='TRUE';
      ALLOW_CONNECT='TRUE';
    'VSS'<32>:
      PIN_NUMBER='(0,0,178,0)';
      PINUSE='GROUND';
      NO_LOAD_CHECK='Both';
      NO_IO_CHECK='Both';
      NO_ASSERT_CHECK='TRUE';
      NO_DIR_CHECK='TRUE';
      ALLOW_CONNECT='TRUE';
    'VSS'<31>:
      PIN_NUMBER='(0,0,180,0)';
      PINUSE='GROUND';
      NO_LOAD_CHECK='Both';
      NO_IO_CHECK='Both';
      NO_ASSERT_CHECK='TRUE';
      NO_DIR_CHECK='TRUE';
      ALLOW_CONNECT='TRUE';
    'VSS'<30>:
      PIN_NUMBER='(0,0,182,0)';
      PINUSE='GROUND';
      NO_LOAD_CHECK='Both';
      NO_IO_CHECK='Both';
      NO_ASSERT_CHECK='TRUE';
      NO_DIR_CHECK='TRUE';
      ALLOW_CONNECT='TRUE';
    'VSS'<29>:
      PIN_NUMBER='(0,0,184,0)';
      PINUSE='GROUND';
      NO_LOAD_CHECK='Both';
      NO_IO_CHECK='Both';
      NO_ASSERT_CHECK='TRUE';
      NO_DIR_CHECK='TRUE';
      ALLOW_CONNECT='TRUE';
    'VSS'<28>:
      PIN_NUMBER='(0,0,187,0)';
      PINUSE='GROUND';
      NO_LOAD_CHECK='Both';
      NO_IO_CHECK='Both';
      NO_ASSERT_CHECK='TRUE';
      NO_DIR_CHECK='TRUE';
      ALLOW_CONNECT='TRUE';
    'VSS'<27>:
      PIN_NUMBER='(0,0,189,0)';
      PINUSE='GROUND';
      NO_LOAD_CHECK='Both';
      NO_IO_CHECK='Both';
      NO_ASSERT_CHECK='TRUE';
      NO_DIR_CHECK='TRUE';
      ALLOW_CONNECT='TRUE';
    'VSS'<26>:
      PIN_NUMBER='(0,0,191,0)';
      PINUSE='GROUND';
      NO_LOAD_CHECK='Both';
      NO_IO_CHECK='Both';
      NO_ASSERT_CHECK='TRUE';
      NO_DIR_CHECK='TRUE';
      ALLOW_CONNECT='TRUE';
    'VSS'<25>:
      PIN_NUMBER='(0,0,193,0)';
      PINUSE='GROUND';
      NO_LOAD_CHECK='Both';
      NO_IO_CHECK='Both';
      NO_ASSERT_CHECK='TRUE';
      NO_DIR_CHECK='TRUE';
      ALLOW_CONNECT='TRUE';
    'VSS'<24>:
      PIN_NUMBER='(0,0,195,0)';
      PINUSE='GROUND';
      NO_LOAD_CHECK='Both';
      NO_IO_CHECK='Both';
      NO_ASSERT_CHECK='TRUE';
      NO_DIR_CHECK='TRUE';
      ALLOW_CONNECT='TRUE';
    'VSS'<23>:
      PIN_NUMBER='(0,0,198,0)';
      PINUSE='GROUND';
      NO_LOAD_CHECK='Both';
      NO_IO_CHECK='Both';
      NO_ASSERT_CHECK='TRUE';
      NO_DIR_CHECK='TRUE';
      ALLOW_CONNECT='TRUE';
    'VSS'<22>:
      PIN_NUMBER='(0,0,200,0)';
      PINUSE='GROUND';
      NO_LOAD_CHECK='Both';
      NO_IO_CHECK='Both';
      NO_ASSERT_CHECK='TRUE';
      NO_DIR_CHECK='TRUE';
      ALLOW_CONNECT='TRUE';
    'VSS'<21>:
      PIN_NUMBER='(0,0,202,0)';
      PINUSE='GROUND';
      NO_LOAD_CHECK='Both';
      NO_IO_CHECK='Both';
      NO_ASSERT_CHECK='TRUE';
      NO_DIR_CHECK='TRUE';
      ALLOW_CONNECT='TRUE';
    'VSS'<20>:
      PIN_NUMBER='(0,0,239,0)';
      PINUSE='GROUND';
      NO_LOAD_CHECK='Both';
      NO_IO_CHECK='Both';
      NO_ASSERT_CHECK='TRUE';
      NO_DIR_CHECK='TRUE';
      ALLOW_CONNECT='TRUE';
    'VSS'<19>:
      PIN_NUMBER='(0,0,241,0)';
      PINUSE='GROUND';
      NO_LOAD_CHECK='Both';
      NO_IO_CHECK='Both';
      NO_ASSERT_CHECK='TRUE';
      NO_DIR_CHECK='TRUE';
      ALLOW_CONNECT='TRUE';
    'VSS'<18>:
      PIN_NUMBER='(0,0,243,0)';
      PINUSE='GROUND';
      NO_LOAD_CHECK='Both';
      NO_IO_CHECK='Both';
      NO_ASSERT_CHECK='TRUE';
      NO_DIR_CHECK='TRUE';
      ALLOW_CONNECT='TRUE';
    'VSS'<17>:
      PIN_NUMBER='(0,0,246,0)';
      PINUSE='GROUND';
      NO_LOAD_CHECK='Both';
      NO_IO_CHECK='Both';
      NO_ASSERT_CHECK='TRUE';
      NO_DIR_CHECK='TRUE';
      ALLOW_CONNECT='TRUE';
    'VSS'<16>:
      PIN_NUMBER='(0,0,248,0)';
      PINUSE='GROUND';
      NO_LOAD_CHECK='Both';
      NO_IO_CHECK='Both';
      NO_ASSERT_CHECK='TRUE';
      NO_DIR_CHECK='TRUE';
      ALLOW_CONNECT='TRUE';
    'VSS'<15>:
      PIN_NUMBER='(0,0,250,0)';
      PINUSE='GROUND';
      NO_LOAD_CHECK='Both';
      NO_IO_CHECK='Both';
      NO_ASSERT_CHECK='TRUE';
      NO_DIR_CHECK='TRUE';
      ALLOW_CONNECT='TRUE';
    'VSS'<14>:
      PIN_NUMBER='(0,0,252,0)';
      PINUSE='GROUND';
      NO_LOAD_CHECK='Both';
      NO_IO_CHECK='Both';
      NO_ASSERT_CHECK='TRUE';
      NO_DIR_CHECK='TRUE';
      ALLOW_CONNECT='TRUE';
    'VSS'<13>:
      PIN_NUMBER='(0,0,254,0)';
      PINUSE='GROUND';
      NO_LOAD_CHECK='Both';
      NO_IO_CHECK='Both';
      NO_ASSERT_CHECK='TRUE';
      NO_DIR_CHECK='TRUE';
      ALLOW_CONNECT='TRUE';
    'VSS'<12>:
      PIN_NUMBER='(0,0,257,0)';
      PINUSE='GROUND';
      NO_LOAD_CHECK='Both';
      NO_IO_CHECK='Both';
      NO_ASSERT_CHECK='TRUE';
      NO_DIR_CHECK='TRUE';
      ALLOW_CONNECT='TRUE';
    'VSS'<11>:
      PIN_NUMBER='(0,0,259,0)';
      PINUSE='GROUND';
      NO_LOAD_CHECK='Both';
      NO_IO_CHECK='Both';
      NO_ASSERT_CHECK='TRUE';
      NO_DIR_CHECK='TRUE';
      ALLOW_CONNECT='TRUE';
    'VSS'<10>:
      PIN_NUMBER='(0,0,261,0)';
      PINUSE='GROUND';
      NO_LOAD_CHECK='Both';
      NO_IO_CHECK='Both';
      NO_ASSERT_CHECK='TRUE';
      NO_DIR_CHECK='TRUE';
      ALLOW_CONNECT='TRUE';
    'VSS'<9>:
      PIN_NUMBER='(0,0,263,0)';
      PINUSE='GROUND';
      NO_LOAD_CHECK='Both';
      NO_IO_CHECK='Both';
      NO_ASSERT_CHECK='TRUE';
      NO_DIR_CHECK='TRUE';
      ALLOW_CONNECT='TRUE';
    'VSS'<8>:
      PIN_NUMBER='(0,0,265,0)';
      PINUSE='GROUND';
      NO_LOAD_CHECK='Both';
      NO_IO_CHECK='Both';
      NO_ASSERT_CHECK='TRUE';
      NO_DIR_CHECK='TRUE';
      ALLOW_CONNECT='TRUE';
    'VSS'<7>:
      PIN_NUMBER='(0,0,268,0)';
      PINUSE='GROUND';
      NO_LOAD_CHECK='Both';
      NO_IO_CHECK='Both';
      NO_ASSERT_CHECK='TRUE';
      NO_DIR_CHECK='TRUE';
      ALLOW_CONNECT='TRUE';
    'VSS'<6>:
      PIN_NUMBER='(0,0,270,0)';
      PINUSE='GROUND';
      NO_LOAD_CHECK='Both';
      NO_IO_CHECK='Both';
      NO_ASSERT_CHECK='TRUE';
      NO_DIR_CHECK='TRUE';
      ALLOW_CONNECT='TRUE';
    'VSS'<5>:
      PIN_NUMBER='(0,0,272,0)';
      PINUSE='GROUND';
      NO_LOAD_CHECK='Both';
      NO_IO_CHECK='Both';
      NO_ASSERT_CHECK='TRUE';
      NO_DIR_CHECK='TRUE';
      ALLOW_CONNECT='TRUE';
    'VSS'<4>:
      PIN_NUMBER='(0,0,274,0)';
      PINUSE='GROUND';
      NO_LOAD_CHECK='Both';
      NO_IO_CHECK='Both';
      NO_ASSERT_CHECK='TRUE';
      NO_DIR_CHECK='TRUE';
      ALLOW_CONNECT='TRUE';
    'VSS'<3>:
      PIN_NUMBER='(0,0,276,0)';
      PINUSE='GROUND';
      NO_LOAD_CHECK='Both';
      NO_IO_CHECK='Both';
      NO_ASSERT_CHECK='TRUE';
      NO_DIR_CHECK='TRUE';
      ALLOW_CONNECT='TRUE';
    'VSS'<2>:
      PIN_NUMBER='(0,0,279,0)';
      PINUSE='GROUND';
      NO_LOAD_CHECK='Both';
      NO_IO_CHECK='Both';
      NO_ASSERT_CHECK='TRUE';
      NO_DIR_CHECK='TRUE';
      ALLOW_CONNECT='TRUE';
    'VSS'<1>:
      PIN_NUMBER='(0,0,281,0)';
      PINUSE='GROUND';
      NO_LOAD_CHECK='Both';
      NO_IO_CHECK='Both';
      NO_ASSERT_CHECK='TRUE';
      NO_DIR_CHECK='TRUE';
      ALLOW_CONNECT='TRUE';
    'VSS'<0>:
      PIN_NUMBER='(0,0,283,0)';
      PINUSE='GROUND';
      NO_LOAD_CHECK='Both';
      NO_IO_CHECK='Both';
      NO_ASSERT_CHECK='TRUE';
      NO_DIR_CHECK='TRUE';
      ALLOW_CONNECT='TRUE';
    'VTT'<1>:
      PIN_NUMBER='(0,0,0,77)';
      PINUSE='POWER';
      NO_LOAD_CHECK='Both';
      NO_IO_CHECK='Both';
      NO_ASSERT_CHECK='TRUE';
      NO_DIR_CHECK='TRUE';
      ALLOW_CONNECT='TRUE';
    'VTT'<0>:
      PIN_NUMBER='(0,0,0,221)';
      PINUSE='POWER';
      NO_LOAD_CHECK='Both';
      NO_IO_CHECK='Both';
      NO_ASSERT_CHECK='TRUE';
      NO_DIR_CHECK='TRUE';
      ALLOW_CONNECT='TRUE';
  end_pin;
  body
      PART_NAME='SCONN288_H44441004';
      PHYS_DES_PREFIX='J';
      ENVCOMP='';
      PART_NUMBER='H44441-004';
      JEDEC_TYPE='SCONN288_H44441004_PIP';
      DESCRIPTION='(USE SYM 1-4)CONN,CEDG,288P,DDR4,VT,0.85mm,SMT,BU';
      CLASS='IO';
      COMPONENT_TYPE='SMTCONN';
      HEIGHT='0.839 IN';
      LPID='3551';
      SPEED_URL='http://speed.intel.com:8081/speed/module/pdm/item/pdm_item_deta~
il_direct.asp?item_cde=H44441-004&item_rev=01&url_param=unused';
      STATUS='';
      RPL='';
      AML='';
      BUS_UNIT='';
      DAYS='';
      PARENT_PART_TYPE='SCONN288_H44441004_PIP';
      PARENT_PPT='SCONN288_H44441004';
      PARENT_PPT_PART='SCONN288_H44441004_PIP-SCONN,H44441-004';
  end_body;
end_primitive;
primitive 'SCONN60_C21100002_SMLF-CONN,C2A';
  pin
    'IO1':
      PIN_NUMBER='(1)';
      PIN_TYPE='UNSPEC';
      PINUSE='UNSPEC';
    'IO3':
      PIN_NUMBER='(3)';
      PIN_TYPE='UNSPEC';
      PINUSE='UNSPEC';
    'IO5':
      PIN_NUMBER='(5)';
      PIN_TYPE='UNSPEC';
      PINUSE='UNSPEC';
    'IO7':
      PIN_NUMBER='(7)';
      PIN_TYPE='UNSPEC';
      PINUSE='UNSPEC';
    'IO9':
      PIN_NUMBER='(9)';
      PIN_TYPE='UNSPEC';
      PINUSE='UNSPEC';
    'IO11':
      PIN_NUMBER='(11)';
      PIN_TYPE='UNSPEC';
      PINUSE='UNSPEC';
    'IO13':
      PIN_NUMBER='(13)';
      PIN_TYPE='UNSPEC';
      PINUSE='UNSPEC';
    'IO15':
      PIN_NUMBER='(15)';
      PIN_TYPE='UNSPEC';
      PINUSE='UNSPEC';
    'IO17':
      PIN_NUMBER='(17)';
      PIN_TYPE='UNSPEC';
      PINUSE='UNSPEC';
    'IO19':
      PIN_NUMBER='(19)';
      PIN_TYPE='UNSPEC';
      PINUSE='UNSPEC';
    'IO21':
      PIN_NUMBER='(21)';
      PIN_TYPE='UNSPEC';
      PINUSE='UNSPEC';
    'IO23':
      PIN_NUMBER='(23)';
      PIN_TYPE='UNSPEC';
      PINUSE='UNSPEC';
    'IO25':
      PIN_NUMBER='(25)';
      PIN_TYPE='UNSPEC';
      PINUSE='UNSPEC';
    'IO27':
      PIN_NUMBER='(27)';
      PIN_TYPE='UNSPEC';
      PINUSE='UNSPEC';
    'IO29':
      PIN_NUMBER='(29)';
      PIN_TYPE='UNSPEC';
      PINUSE='UNSPEC';
    'IO31':
      PIN_NUMBER='(31)';
      PIN_TYPE='UNSPEC';
      PINUSE='UNSPEC';
    'IO33':
      PIN_NUMBER='(33)';
      PIN_TYPE='UNSPEC';
      PINUSE='UNSPEC';
    'IO35':
      PIN_NUMBER='(35)';
      PIN_TYPE='UNSPEC';
      PINUSE='UNSPEC';
    'IO37':
      PIN_NUMBER='(37)';
      PIN_TYPE='UNSPEC';
      PINUSE='UNSPEC';
    'IO39':
      PIN_NUMBER='(39)';
      PIN_TYPE='UNSPEC';
      PINUSE='UNSPEC';
    'IO41':
      PIN_NUMBER='(41)';
      PIN_TYPE='UNSPEC';
      PINUSE='UNSPEC';
    'IO43':
      PIN_NUMBER='(43)';
      PIN_TYPE='UNSPEC';
      PINUSE='UNSPEC';
    'IO45':
      PIN_NUMBER='(45)';
      PIN_TYPE='UNSPEC';
      PINUSE='UNSPEC';
    'IO47':
      PIN_NUMBER='(47)';
      PIN_TYPE='UNSPEC';
      PINUSE='UNSPEC';
    'IO49':
      PIN_NUMBER='(49)';
      PIN_TYPE='UNSPEC';
      PINUSE='UNSPEC';
    'IO2':
      PIN_NUMBER='(2)';
      PIN_TYPE='UNSPEC';
      PINUSE='UNSPEC';
    'IO4':
      PIN_NUMBER='(4)';
      PIN_TYPE='UNSPEC';
      PINUSE='UNSPEC';
    'IO6':
      PIN_NUMBER='(6)';
      PIN_TYPE='UNSPEC';
      PINUSE='UNSPEC';
    'IO8':
      PIN_NUMBER='(8)';
      PIN_TYPE='UNSPEC';
      PINUSE='UNSPEC';
    'IO10':
      PIN_NUMBER='(10)';
      PIN_TYPE='UNSPEC';
      PINUSE='UNSPEC';
    'IO12':
      PIN_NUMBER='(12)';
      PIN_TYPE='UNSPEC';
      PINUSE='UNSPEC';
    'IO14':
      PIN_NUMBER='(14)';
      PIN_TYPE='UNSPEC';
      PINUSE='UNSPEC';
    'IO16':
      PIN_NUMBER='(16)';
      PIN_TYPE='UNSPEC';
      PINUSE='UNSPEC';
    'IO18':
      PIN_NUMBER='(18)';
      PIN_TYPE='UNSPEC';
      PINUSE='UNSPEC';
    'IO20':
      PIN_NUMBER='(20)';
      PIN_TYPE='UNSPEC';
      PINUSE='UNSPEC';
    'IO22':
      PIN_NUMBER='(22)';
      PIN_TYPE='UNSPEC';
      PINUSE='UNSPEC';
    'IO24':
      PIN_NUMBER='(24)';
      PIN_TYPE='UNSPEC';
      PINUSE='UNSPEC';
    'IO26':
      PIN_NUMBER='(26)';
      PIN_TYPE='UNSPEC';
      PINUSE='UNSPEC';
    'IO28':
      PIN_NUMBER='(28)';
      PIN_TYPE='UNSPEC';
      PINUSE='UNSPEC';
    'IO30':
      PIN_NUMBER='(30)';
      PIN_TYPE='UNSPEC';
      PINUSE='UNSPEC';
    'IO32':
      PIN_NUMBER='(32)';
      PIN_TYPE='UNSPEC';
      PINUSE='UNSPEC';
    'IO34':
      PIN_NUMBER='(34)';
      PIN_TYPE='UNSPEC';
      PINUSE='UNSPEC';
    'IO36':
      PIN_NUMBER='(36)';
      PIN_TYPE='UNSPEC';
      PINUSE='UNSPEC';
    'IO38':
      PIN_NUMBER='(38)';
      PIN_TYPE='UNSPEC';
      PINUSE='UNSPEC';
    'IO40':
      PIN_NUMBER='(40)';
      PIN_TYPE='UNSPEC';
      PINUSE='UNSPEC';
    'IO42':
      PIN_NUMBER='(42)';
      PIN_TYPE='UNSPEC';
      PINUSE='UNSPEC';
    'IO44':
      PIN_NUMBER='(44)';
      PIN_TYPE='UNSPEC';
      PINUSE='UNSPEC';
    'IO46':
      PIN_NUMBER='(46)';
      PIN_TYPE='UNSPEC';
      PINUSE='UNSPEC';
    'IO48':
      PIN_NUMBER='(48)';
      PIN_TYPE='UNSPEC';
      PINUSE='UNSPEC';
    'IO50':
      PIN_NUMBER='(50)';
      PIN_TYPE='UNSPEC';
      PINUSE='UNSPEC';
    'IO51':
      PIN_NUMBER='(51)';
      PIN_TYPE='UNSPEC';
      PINUSE='UNSPEC';
    'IO52':
      PIN_NUMBER='(52)';
      PIN_TYPE='UNSPEC';
      PINUSE='UNSPEC';
    'IO53':
      PIN_NUMBER='(53)';
      PIN_TYPE='UNSPEC';
      PINUSE='UNSPEC';
    'IO54':
      PIN_NUMBER='(54)';
      PIN_TYPE='UNSPEC';
      PINUSE='UNSPEC';
    'IO55':
      PIN_NUMBER='(55)';
      PIN_TYPE='UNSPEC';
      PINUSE='UNSPEC';
    'IO56':
      PIN_NUMBER='(56)';
      PIN_TYPE='UNSPEC';
      PINUSE='UNSPEC';
    'IO57':
      PIN_NUMBER='(57)';
      PIN_TYPE='UNSPEC';
      PINUSE='UNSPEC';
    'IO58':
      PIN_NUMBER='(58)';
      PIN_TYPE='UNSPEC';
      PINUSE='UNSPEC';
    'IO59':
      PIN_NUMBER='(59)';
      PIN_TYPE='UNSPEC';
      PINUSE='UNSPEC';
    'IO60':
      PIN_NUMBER='(60)';
      PIN_TYPE='UNSPEC';
      PINUSE='UNSPEC';
  end_pin;
  body
      BODY_NAME='SCONN60_C21100002';
      PART_NAME='SCONN60_C21100002';
      PHYS_DES_PREFIX='J';
      ENVCOMP='YES;YES;YES;UNK;ok;CIP';
      PART_NUMBER='C21100-002';
      JEDEC_TYPE='SCONN60_C21100002';
      CLASS='IO';
      DESCRIPTION='SAMTEC 60';
      HEIGHT='.120 IN';
      COMPONENT_TYPE='SMTCONN';
      LPID='';
      SPEED_URL='http://speed.intel.com:8081/speed/module/pdm/item/pdm_item_deta~
il_direct.asp?item_cde=C21100-002&item_rev=01&url_param=unused';
      STATUS='Unqual';
      RPL='NO';
      AML='1';
      BUS_UNIT='SMO_BOARDS';
      DAYS='56';
      PARENT_PART_TYPE='SCONN60_C21100002';
      PARENT_PPT='SCONN60_C21100002';
      PARENT_PPT_PART='SCONN60_C21100002_SMLF-CONN,C21100-002';
  end_body;
end_primitive;
primitive 'SCONN64_H87568002_A_SMT-CONN,HA';
  pin
    'IO1':
      PIN_NUMBER='(1)';
      BIDIRECTIONAL='TRUE';
      INPUT_LOAD='(-0.01,0.01)';
      OUTPUT_LOAD='(1.0,-1.0)';
      PINUSE='BI';
    'IO10':
      PIN_NUMBER='(10)';
      BIDIRECTIONAL='TRUE';
      INPUT_LOAD='(-0.01,0.01)';
      OUTPUT_LOAD='(1.0,-1.0)';
      PINUSE='BI';
    'IO11':
      PIN_NUMBER='(11)';
      BIDIRECTIONAL='TRUE';
      INPUT_LOAD='(-0.01,0.01)';
      OUTPUT_LOAD='(1.0,-1.0)';
      PINUSE='BI';
    'IO12':
      PIN_NUMBER='(12)';
      BIDIRECTIONAL='TRUE';
      INPUT_LOAD='(-0.01,0.01)';
      OUTPUT_LOAD='(1.0,-1.0)';
      PINUSE='BI';
    'IO13':
      PIN_NUMBER='(13)';
      BIDIRECTIONAL='TRUE';
      INPUT_LOAD='(-0.01,0.01)';
      OUTPUT_LOAD='(1.0,-1.0)';
      PINUSE='BI';
    'IO14':
      PIN_NUMBER='(14)';
      BIDIRECTIONAL='TRUE';
      INPUT_LOAD='(-0.01,0.01)';
      OUTPUT_LOAD='(1.0,-1.0)';
      PINUSE='BI';
    'IO15':
      PIN_NUMBER='(15)';
      BIDIRECTIONAL='TRUE';
      INPUT_LOAD='(-0.01,0.01)';
      OUTPUT_LOAD='(1.0,-1.0)';
      PINUSE='BI';
    'IO16':
      PIN_NUMBER='(16)';
      BIDIRECTIONAL='TRUE';
      INPUT_LOAD='(-0.01,0.01)';
      OUTPUT_LOAD='(1.0,-1.0)';
      PINUSE='BI';
    'IO17':
      PIN_NUMBER='(17)';
      BIDIRECTIONAL='TRUE';
      INPUT_LOAD='(-0.01,0.01)';
      OUTPUT_LOAD='(1.0,-1.0)';
      PINUSE='BI';
    'IO18':
      PIN_NUMBER='(18)';
      BIDIRECTIONAL='TRUE';
      INPUT_LOAD='(-0.01,0.01)';
      OUTPUT_LOAD='(1.0,-1.0)';
      PINUSE='BI';
    'IO19':
      PIN_NUMBER='(19)';
      BIDIRECTIONAL='TRUE';
      INPUT_LOAD='(-0.01,0.01)';
      OUTPUT_LOAD='(1.0,-1.0)';
      PINUSE='BI';
    'IO2':
      PIN_NUMBER='(2)';
      BIDIRECTIONAL='TRUE';
      INPUT_LOAD='(-0.01,0.01)';
      OUTPUT_LOAD='(1.0,-1.0)';
      PINUSE='BI';
    'IO20':
      PIN_NUMBER='(20)';
      BIDIRECTIONAL='TRUE';
      INPUT_LOAD='(-0.01,0.01)';
      OUTPUT_LOAD='(1.0,-1.0)';
      PINUSE='BI';
    'IO21':
      PIN_NUMBER='(21)';
      BIDIRECTIONAL='TRUE';
      INPUT_LOAD='(-0.01,0.01)';
      OUTPUT_LOAD='(1.0,-1.0)';
      PINUSE='BI';
    'IO22':
      PIN_NUMBER='(22)';
      BIDIRECTIONAL='TRUE';
      INPUT_LOAD='(-0.01,0.01)';
      OUTPUT_LOAD='(1.0,-1.0)';
      PINUSE='BI';
    'IO23':
      PIN_NUMBER='(23)';
      BIDIRECTIONAL='TRUE';
      INPUT_LOAD='(-0.01,0.01)';
      OUTPUT_LOAD='(1.0,-1.0)';
      PINUSE='BI';
    'IO24':
      PIN_NUMBER='(24)';
      BIDIRECTIONAL='TRUE';
      INPUT_LOAD='(-0.01,0.01)';
      OUTPUT_LOAD='(1.0,-1.0)';
      PINUSE='BI';
    'IO25':
      PIN_NUMBER='(25)';
      BIDIRECTIONAL='TRUE';
      INPUT_LOAD='(-0.01,0.01)';
      OUTPUT_LOAD='(1.0,-1.0)';
      PINUSE='BI';
    'IO26':
      PIN_NUMBER='(26)';
      BIDIRECTIONAL='TRUE';
      INPUT_LOAD='(-0.01,0.01)';
      OUTPUT_LOAD='(1.0,-1.0)';
      PINUSE='BI';
    'IO27':
      PIN_NUMBER='(27)';
      BIDIRECTIONAL='TRUE';
      INPUT_LOAD='(-0.01,0.01)';
      OUTPUT_LOAD='(1.0,-1.0)';
      PINUSE='BI';
    'IO28':
      PIN_NUMBER='(28)';
      BIDIRECTIONAL='TRUE';
      INPUT_LOAD='(-0.01,0.01)';
      OUTPUT_LOAD='(1.0,-1.0)';
      PINUSE='BI';
    'IO29':
      PIN_NUMBER='(29)';
      BIDIRECTIONAL='TRUE';
      INPUT_LOAD='(-0.01,0.01)';
      OUTPUT_LOAD='(1.0,-1.0)';
      PINUSE='BI';
    'IO3':
      PIN_NUMBER='(3)';
      BIDIRECTIONAL='TRUE';
      INPUT_LOAD='(-0.01,0.01)';
      OUTPUT_LOAD='(1.0,-1.0)';
      PINUSE='BI';
    'IO30':
      PIN_NUMBER='(30)';
      BIDIRECTIONAL='TRUE';
      INPUT_LOAD='(-0.01,0.01)';
      OUTPUT_LOAD='(1.0,-1.0)';
      PINUSE='BI';
    'IO31':
      PIN_NUMBER='(31)';
      BIDIRECTIONAL='TRUE';
      INPUT_LOAD='(-0.01,0.01)';
      OUTPUT_LOAD='(1.0,-1.0)';
      PINUSE='BI';
    'IO32':
      PIN_NUMBER='(32)';
      BIDIRECTIONAL='TRUE';
      INPUT_LOAD='(-0.01,0.01)';
      OUTPUT_LOAD='(1.0,-1.0)';
      PINUSE='BI';
    'IO33':
      PIN_NUMBER='(33)';
      BIDIRECTIONAL='TRUE';
      INPUT_LOAD='(-0.01,0.01)';
      OUTPUT_LOAD='(1.0,-1.0)';
      PINUSE='BI';
    'IO34':
      PIN_NUMBER='(34)';
      BIDIRECTIONAL='TRUE';
      INPUT_LOAD='(-0.01,0.01)';
      OUTPUT_LOAD='(1.0,-1.0)';
      PINUSE='BI';
    'IO35':
      PIN_NUMBER='(35)';
      BIDIRECTIONAL='TRUE';
      INPUT_LOAD='(-0.01,0.01)';
      OUTPUT_LOAD='(1.0,-1.0)';
      PINUSE='BI';
    'IO36':
      PIN_NUMBER='(36)';
      BIDIRECTIONAL='TRUE';
      INPUT_LOAD='(-0.01,0.01)';
      OUTPUT_LOAD='(1.0,-1.0)';
      PINUSE='BI';
    'IO37':
      PIN_NUMBER='(37)';
      BIDIRECTIONAL='TRUE';
      INPUT_LOAD='(-0.01,0.01)';
      OUTPUT_LOAD='(1.0,-1.0)';
      PINUSE='BI';
    'IO38':
      PIN_NUMBER='(38)';
      BIDIRECTIONAL='TRUE';
      INPUT_LOAD='(-0.01,0.01)';
      OUTPUT_LOAD='(1.0,-1.0)';
      PINUSE='BI';
    'IO39':
      PIN_NUMBER='(39)';
      BIDIRECTIONAL='TRUE';
      INPUT_LOAD='(-0.01,0.01)';
      OUTPUT_LOAD='(1.0,-1.0)';
      PINUSE='BI';
    'IO4':
      PIN_NUMBER='(4)';
      BIDIRECTIONAL='TRUE';
      INPUT_LOAD='(-0.01,0.01)';
      OUTPUT_LOAD='(1.0,-1.0)';
      PINUSE='BI';
    'IO40':
      PIN_NUMBER='(40)';
      BIDIRECTIONAL='TRUE';
      INPUT_LOAD='(-0.01,0.01)';
      OUTPUT_LOAD='(1.0,-1.0)';
      PINUSE='BI';
    'IO41':
      PIN_NUMBER='(41)';
      BIDIRECTIONAL='TRUE';
      INPUT_LOAD='(-0.01,0.01)';
      OUTPUT_LOAD='(1.0,-1.0)';
      PINUSE='BI';
    'IO42':
      PIN_NUMBER='(42)';
      BIDIRECTIONAL='TRUE';
      INPUT_LOAD='(-0.01,0.01)';
      OUTPUT_LOAD='(1.0,-1.0)';
      PINUSE='BI';
    'IO43':
      PIN_NUMBER='(43)';
      BIDIRECTIONAL='TRUE';
      INPUT_LOAD='(-0.01,0.01)';
      OUTPUT_LOAD='(1.0,-1.0)';
      PINUSE='BI';
    'IO44':
      PIN_NUMBER='(44)';
      BIDIRECTIONAL='TRUE';
      INPUT_LOAD='(-0.01,0.01)';
      OUTPUT_LOAD='(1.0,-1.0)';
      PINUSE='BI';
    'IO45':
      PIN_NUMBER='(45)';
      BIDIRECTIONAL='TRUE';
      INPUT_LOAD='(-0.01,0.01)';
      OUTPUT_LOAD='(1.0,-1.0)';
      PINUSE='BI';
    'IO46':
      PIN_NUMBER='(46)';
      BIDIRECTIONAL='TRUE';
      INPUT_LOAD='(-0.01,0.01)';
      OUTPUT_LOAD='(1.0,-1.0)';
      PINUSE='BI';
    'IO47':
      PIN_NUMBER='(47)';
      BIDIRECTIONAL='TRUE';
      INPUT_LOAD='(-0.01,0.01)';
      OUTPUT_LOAD='(1.0,-1.0)';
      PINUSE='BI';
    'IO48':
      PIN_NUMBER='(48)';
      BIDIRECTIONAL='TRUE';
      INPUT_LOAD='(-0.01,0.01)';
      OUTPUT_LOAD='(1.0,-1.0)';
      PINUSE='BI';
    'IO49':
      PIN_NUMBER='(49)';
      BIDIRECTIONAL='TRUE';
      INPUT_LOAD='(-0.01,0.01)';
      OUTPUT_LOAD='(1.0,-1.0)';
      PINUSE='BI';
    'IO5':
      PIN_NUMBER='(5)';
      BIDIRECTIONAL='TRUE';
      INPUT_LOAD='(-0.01,0.01)';
      OUTPUT_LOAD='(1.0,-1.0)';
      PINUSE='BI';
    'IO50':
      PIN_NUMBER='(50)';
      BIDIRECTIONAL='TRUE';
      INPUT_LOAD='(-0.01,0.01)';
      OUTPUT_LOAD='(1.0,-1.0)';
      PINUSE='BI';
    'IO51':
      PIN_NUMBER='(51)';
      BIDIRECTIONAL='TRUE';
      INPUT_LOAD='(-0.01,0.01)';
      OUTPUT_LOAD='(1.0,-1.0)';
      PINUSE='BI';
    'IO52':
      PIN_NUMBER='(52)';
      BIDIRECTIONAL='TRUE';
      INPUT_LOAD='(-0.01,0.01)';
      OUTPUT_LOAD='(1.0,-1.0)';
      PINUSE='BI';
    'IO53':
      PIN_NUMBER='(53)';
      BIDIRECTIONAL='TRUE';
      INPUT_LOAD='(-0.01,0.01)';
      OUTPUT_LOAD='(1.0,-1.0)';
      PINUSE='BI';
    'IO54':
      PIN_NUMBER='(54)';
      BIDIRECTIONAL='TRUE';
      INPUT_LOAD='(-0.01,0.01)';
      OUTPUT_LOAD='(1.0,-1.0)';
      PINUSE='BI';
    'IO55':
      PIN_NUMBER='(55)';
      BIDIRECTIONAL='TRUE';
      INPUT_LOAD='(-0.01,0.01)';
      OUTPUT_LOAD='(1.0,-1.0)';
      PINUSE='BI';
    'IO56':
      PIN_NUMBER='(56)';
      BIDIRECTIONAL='TRUE';
      INPUT_LOAD='(-0.01,0.01)';
      OUTPUT_LOAD='(1.0,-1.0)';
      PINUSE='BI';
    'IO57':
      PIN_NUMBER='(57)';
      BIDIRECTIONAL='TRUE';
      INPUT_LOAD='(-0.01,0.01)';
      OUTPUT_LOAD='(1.0,-1.0)';
      PINUSE='BI';
    'IO58':
      PIN_NUMBER='(58)';
      BIDIRECTIONAL='TRUE';
      INPUT_LOAD='(-0.01,0.01)';
      OUTPUT_LOAD='(1.0,-1.0)';
      PINUSE='BI';
    'IO59':
      PIN_NUMBER='(59)';
      BIDIRECTIONAL='TRUE';
      INPUT_LOAD='(-0.01,0.01)';
      OUTPUT_LOAD='(1.0,-1.0)';
      PINUSE='BI';
    'IO6':
      PIN_NUMBER='(6)';
      BIDIRECTIONAL='TRUE';
      INPUT_LOAD='(-0.01,0.01)';
      OUTPUT_LOAD='(1.0,-1.0)';
      PINUSE='BI';
    'IO60':
      PIN_NUMBER='(60)';
      BIDIRECTIONAL='TRUE';
      INPUT_LOAD='(-0.01,0.01)';
      OUTPUT_LOAD='(1.0,-1.0)';
      PINUSE='BI';
    'IO61':
      PIN_NUMBER='(61)';
      BIDIRECTIONAL='TRUE';
      INPUT_LOAD='(-0.01,0.01)';
      OUTPUT_LOAD='(1.0,-1.0)';
      PINUSE='BI';
    'IO62':
      PIN_NUMBER='(62)';
      BIDIRECTIONAL='TRUE';
      INPUT_LOAD='(-0.01,0.01)';
      OUTPUT_LOAD='(1.0,-1.0)';
      PINUSE='BI';
    'IO63':
      PIN_NUMBER='(63)';
      BIDIRECTIONAL='TRUE';
      INPUT_LOAD='(-0.01,0.01)';
      OUTPUT_LOAD='(1.0,-1.0)';
      PINUSE='BI';
    'IO64':
      PIN_NUMBER='(64)';
      BIDIRECTIONAL='TRUE';
      INPUT_LOAD='(-0.01,0.01)';
      OUTPUT_LOAD='(1.0,-1.0)';
      PINUSE='BI';
    'IO7':
      PIN_NUMBER='(7)';
      BIDIRECTIONAL='TRUE';
      INPUT_LOAD='(-0.01,0.01)';
      OUTPUT_LOAD='(1.0,-1.0)';
      PINUSE='BI';
    'IO8':
      PIN_NUMBER='(8)';
      BIDIRECTIONAL='TRUE';
      INPUT_LOAD='(-0.01,0.01)';
      OUTPUT_LOAD='(1.0,-1.0)';
      PINUSE='BI';
    'IO9':
      PIN_NUMBER='(9)';
      BIDIRECTIONAL='TRUE';
      INPUT_LOAD='(-0.01,0.01)';
      OUTPUT_LOAD='(1.0,-1.0)';
      PINUSE='BI';
  end_pin;
  body
      PART_NAME='SCONN64_H87568002_A';
      PHYS_DES_PREFIX='J';
      ENVCOMP='';
      PART_NUMBER='H87568-002';
      JEDEC_TYPE='SCONN64_H87568002_A';
      CLASS='IO';
      DESCRIPTION='(GENERIC IO USE SYM_1)CONN,MISC,7.7MM,64P,BERG,RCPT,0.8,VT,SM~
T';
      HEIGHT='0.315 IN';
      COMPONENT_TYPE='SMTCONN';
      LPID='4203';
      SPEED_URL='http://speed.intel.com:8081/speed/module/pdm/item/pdm_item_deta~
il_direct.asp?item_cde=H87568-002&item_rev=01&url_param=unused';
      STATUS='';
      RPL='';
      AML='';
      BUS_UNIT='';
      DAYS='';
      PARENT_PART_TYPE='SCONN64_H87568002_A_SMT';
      PARENT_PPT='SCONN64_H87568002_A';
      PARENT_PPT_PART='SCONN64_H87568002_A_SMT-CONN,H87568-002';
  end_body;
end_primitive;
primitive 'SCONN80_E67482007_SM-CONN,E674A';
  pin
    'IO1':
      PIN_NUMBER='(1)';
      BIDIRECTIONAL='TRUE';
      INPUT_LOAD='(-0.01,0.01)';
      OUTPUT_LOAD='(1.0,-1.0)';
      PINUSE='BI';
    'IO10':
      PIN_NUMBER='(10)';
      BIDIRECTIONAL='TRUE';
      INPUT_LOAD='(-0.01,0.01)';
      OUTPUT_LOAD='(1.0,-1.0)';
      PINUSE='BI';
    'IO11':
      PIN_NUMBER='(11)';
      BIDIRECTIONAL='TRUE';
      INPUT_LOAD='(-0.01,0.01)';
      OUTPUT_LOAD='(1.0,-1.0)';
      PINUSE='BI';
    'IO12':
      PIN_NUMBER='(12)';
      BIDIRECTIONAL='TRUE';
      INPUT_LOAD='(-0.01,0.01)';
      OUTPUT_LOAD='(1.0,-1.0)';
      PINUSE='BI';
    'IO13':
      PIN_NUMBER='(13)';
      BIDIRECTIONAL='TRUE';
      INPUT_LOAD='(-0.01,0.01)';
      OUTPUT_LOAD='(1.0,-1.0)';
      PINUSE='BI';
    'IO14':
      PIN_NUMBER='(14)';
      BIDIRECTIONAL='TRUE';
      INPUT_LOAD='(-0.01,0.01)';
      OUTPUT_LOAD='(1.0,-1.0)';
      PINUSE='BI';
    'IO15':
      PIN_NUMBER='(15)';
      BIDIRECTIONAL='TRUE';
      INPUT_LOAD='(-0.01,0.01)';
      OUTPUT_LOAD='(1.0,-1.0)';
      PINUSE='BI';
    'IO16':
      PIN_NUMBER='(16)';
      BIDIRECTIONAL='TRUE';
      INPUT_LOAD='(-0.01,0.01)';
      OUTPUT_LOAD='(1.0,-1.0)';
      PINUSE='BI';
    'IO17':
      PIN_NUMBER='(17)';
      BIDIRECTIONAL='TRUE';
      INPUT_LOAD='(-0.01,0.01)';
      OUTPUT_LOAD='(1.0,-1.0)';
      PINUSE='BI';
    'IO18':
      PIN_NUMBER='(18)';
      BIDIRECTIONAL='TRUE';
      INPUT_LOAD='(-0.01,0.01)';
      OUTPUT_LOAD='(1.0,-1.0)';
      PINUSE='BI';
    'IO19':
      PIN_NUMBER='(19)';
      BIDIRECTIONAL='TRUE';
      INPUT_LOAD='(-0.01,0.01)';
      OUTPUT_LOAD='(1.0,-1.0)';
      PINUSE='BI';
    'IO2':
      PIN_NUMBER='(2)';
      BIDIRECTIONAL='TRUE';
      INPUT_LOAD='(-0.01,0.01)';
      OUTPUT_LOAD='(1.0,-1.0)';
      PINUSE='BI';
    'IO20':
      PIN_NUMBER='(20)';
      BIDIRECTIONAL='TRUE';
      INPUT_LOAD='(-0.01,0.01)';
      OUTPUT_LOAD='(1.0,-1.0)';
      PINUSE='BI';
    'IO21':
      PIN_NUMBER='(21)';
      BIDIRECTIONAL='TRUE';
      INPUT_LOAD='(-0.01,0.01)';
      OUTPUT_LOAD='(1.0,-1.0)';
      PINUSE='BI';
    'IO22':
      PIN_NUMBER='(22)';
      BIDIRECTIONAL='TRUE';
      INPUT_LOAD='(-0.01,0.01)';
      OUTPUT_LOAD='(1.0,-1.0)';
      PINUSE='BI';
    'IO23':
      PIN_NUMBER='(23)';
      BIDIRECTIONAL='TRUE';
      INPUT_LOAD='(-0.01,0.01)';
      OUTPUT_LOAD='(1.0,-1.0)';
      PINUSE='BI';
    'IO24':
      PIN_NUMBER='(24)';
      BIDIRECTIONAL='TRUE';
      INPUT_LOAD='(-0.01,0.01)';
      OUTPUT_LOAD='(1.0,-1.0)';
      PINUSE='BI';
    'IO25':
      PIN_NUMBER='(25)';
      BIDIRECTIONAL='TRUE';
      INPUT_LOAD='(-0.01,0.01)';
      OUTPUT_LOAD='(1.0,-1.0)';
      PINUSE='BI';
    'IO26':
      PIN_NUMBER='(26)';
      BIDIRECTIONAL='TRUE';
      INPUT_LOAD='(-0.01,0.01)';
      OUTPUT_LOAD='(1.0,-1.0)';
      PINUSE='BI';
    'IO27':
      PIN_NUMBER='(27)';
      BIDIRECTIONAL='TRUE';
      INPUT_LOAD='(-0.01,0.01)';
      OUTPUT_LOAD='(1.0,-1.0)';
      PINUSE='BI';
    'IO28':
      PIN_NUMBER='(28)';
      BIDIRECTIONAL='TRUE';
      INPUT_LOAD='(-0.01,0.01)';
      OUTPUT_LOAD='(1.0,-1.0)';
      PINUSE='BI';
    'IO29':
      PIN_NUMBER='(29)';
      BIDIRECTIONAL='TRUE';
      INPUT_LOAD='(-0.01,0.01)';
      OUTPUT_LOAD='(1.0,-1.0)';
      PINUSE='BI';
    'IO3':
      PIN_NUMBER='(3)';
      BIDIRECTIONAL='TRUE';
      INPUT_LOAD='(-0.01,0.01)';
      OUTPUT_LOAD='(1.0,-1.0)';
      PINUSE='BI';
    'IO30':
      PIN_NUMBER='(30)';
      BIDIRECTIONAL='TRUE';
      INPUT_LOAD='(-0.01,0.01)';
      OUTPUT_LOAD='(1.0,-1.0)';
      PINUSE='BI';
    'IO31':
      PIN_NUMBER='(31)';
      BIDIRECTIONAL='TRUE';
      INPUT_LOAD='(-0.01,0.01)';
      OUTPUT_LOAD='(1.0,-1.0)';
      PINUSE='BI';
    'IO32':
      PIN_NUMBER='(32)';
      BIDIRECTIONAL='TRUE';
      INPUT_LOAD='(-0.01,0.01)';
      OUTPUT_LOAD='(1.0,-1.0)';
      PINUSE='BI';
    'IO33':
      PIN_NUMBER='(33)';
      BIDIRECTIONAL='TRUE';
      INPUT_LOAD='(-0.01,0.01)';
      OUTPUT_LOAD='(1.0,-1.0)';
      PINUSE='BI';
    'IO34':
      PIN_NUMBER='(34)';
      BIDIRECTIONAL='TRUE';
      INPUT_LOAD='(-0.01,0.01)';
      OUTPUT_LOAD='(1.0,-1.0)';
      PINUSE='BI';
    'IO35':
      PIN_NUMBER='(35)';
      BIDIRECTIONAL='TRUE';
      INPUT_LOAD='(-0.01,0.01)';
      OUTPUT_LOAD='(1.0,-1.0)';
      PINUSE='BI';
    'IO36':
      PIN_NUMBER='(36)';
      BIDIRECTIONAL='TRUE';
      INPUT_LOAD='(-0.01,0.01)';
      OUTPUT_LOAD='(1.0,-1.0)';
      PINUSE='BI';
    'IO37':
      PIN_NUMBER='(37)';
      BIDIRECTIONAL='TRUE';
      INPUT_LOAD='(-0.01,0.01)';
      OUTPUT_LOAD='(1.0,-1.0)';
      PINUSE='BI';
    'IO38':
      PIN_NUMBER='(38)';
      BIDIRECTIONAL='TRUE';
      INPUT_LOAD='(-0.01,0.01)';
      OUTPUT_LOAD='(1.0,-1.0)';
      PINUSE='BI';
    'IO39':
      PIN_NUMBER='(39)';
      BIDIRECTIONAL='TRUE';
      INPUT_LOAD='(-0.01,0.01)';
      OUTPUT_LOAD='(1.0,-1.0)';
      PINUSE='BI';
    'IO4':
      PIN_NUMBER='(4)';
      BIDIRECTIONAL='TRUE';
      INPUT_LOAD='(-0.01,0.01)';
      OUTPUT_LOAD='(1.0,-1.0)';
      PINUSE='BI';
    'IO40':
      PIN_NUMBER='(40)';
      BIDIRECTIONAL='TRUE';
      INPUT_LOAD='(-0.01,0.01)';
      OUTPUT_LOAD='(1.0,-1.0)';
      PINUSE='BI';
    'IO41':
      PIN_NUMBER='(41)';
      BIDIRECTIONAL='TRUE';
      INPUT_LOAD='(-0.01,0.01)';
      OUTPUT_LOAD='(1.0,-1.0)';
      PINUSE='BI';
    'IO42':
      PIN_NUMBER='(42)';
      BIDIRECTIONAL='TRUE';
      INPUT_LOAD='(-0.01,0.01)';
      OUTPUT_LOAD='(1.0,-1.0)';
      PINUSE='BI';
    'IO43':
      PIN_NUMBER='(43)';
      BIDIRECTIONAL='TRUE';
      INPUT_LOAD='(-0.01,0.01)';
      OUTPUT_LOAD='(1.0,-1.0)';
      PINUSE='BI';
    'IO44':
      PIN_NUMBER='(44)';
      BIDIRECTIONAL='TRUE';
      INPUT_LOAD='(-0.01,0.01)';
      OUTPUT_LOAD='(1.0,-1.0)';
      PINUSE='BI';
    'IO45':
      PIN_NUMBER='(45)';
      BIDIRECTIONAL='TRUE';
      INPUT_LOAD='(-0.01,0.01)';
      OUTPUT_LOAD='(1.0,-1.0)';
      PINUSE='BI';
    'IO46':
      PIN_NUMBER='(46)';
      BIDIRECTIONAL='TRUE';
      INPUT_LOAD='(-0.01,0.01)';
      OUTPUT_LOAD='(1.0,-1.0)';
      PINUSE='BI';
    'IO47':
      PIN_NUMBER='(47)';
      BIDIRECTIONAL='TRUE';
      INPUT_LOAD='(-0.01,0.01)';
      OUTPUT_LOAD='(1.0,-1.0)';
      PINUSE='BI';
    'IO48':
      PIN_NUMBER='(48)';
      BIDIRECTIONAL='TRUE';
      INPUT_LOAD='(-0.01,0.01)';
      OUTPUT_LOAD='(1.0,-1.0)';
      PINUSE='BI';
    'IO49':
      PIN_NUMBER='(49)';
      BIDIRECTIONAL='TRUE';
      INPUT_LOAD='(-0.01,0.01)';
      OUTPUT_LOAD='(1.0,-1.0)';
      PINUSE='BI';
    'IO5':
      PIN_NUMBER='(5)';
      BIDIRECTIONAL='TRUE';
      INPUT_LOAD='(-0.01,0.01)';
      OUTPUT_LOAD='(1.0,-1.0)';
      PINUSE='BI';
    'IO50':
      PIN_NUMBER='(50)';
      BIDIRECTIONAL='TRUE';
      INPUT_LOAD='(-0.01,0.01)';
      OUTPUT_LOAD='(1.0,-1.0)';
      PINUSE='BI';
    'IO51':
      PIN_NUMBER='(51)';
      BIDIRECTIONAL='TRUE';
      INPUT_LOAD='(-0.01,0.01)';
      OUTPUT_LOAD='(1.0,-1.0)';
      PINUSE='BI';
    'IO52':
      PIN_NUMBER='(52)';
      BIDIRECTIONAL='TRUE';
      INPUT_LOAD='(-0.01,0.01)';
      OUTPUT_LOAD='(1.0,-1.0)';
      PINUSE='BI';
    'IO53':
      PIN_NUMBER='(53)';
      BIDIRECTIONAL='TRUE';
      INPUT_LOAD='(-0.01,0.01)';
      OUTPUT_LOAD='(1.0,-1.0)';
      PINUSE='BI';
    'IO54':
      PIN_NUMBER='(54)';
      BIDIRECTIONAL='TRUE';
      INPUT_LOAD='(-0.01,0.01)';
      OUTPUT_LOAD='(1.0,-1.0)';
      PINUSE='BI';
    'IO55':
      PIN_NUMBER='(55)';
      BIDIRECTIONAL='TRUE';
      INPUT_LOAD='(-0.01,0.01)';
      OUTPUT_LOAD='(1.0,-1.0)';
      PINUSE='BI';
    'IO56':
      PIN_NUMBER='(56)';
      BIDIRECTIONAL='TRUE';
      INPUT_LOAD='(-0.01,0.01)';
      OUTPUT_LOAD='(1.0,-1.0)';
      PINUSE='BI';
    'IO57':
      PIN_NUMBER='(57)';
      BIDIRECTIONAL='TRUE';
      INPUT_LOAD='(-0.01,0.01)';
      OUTPUT_LOAD='(1.0,-1.0)';
      PINUSE='BI';
    'IO58':
      PIN_NUMBER='(58)';
      BIDIRECTIONAL='TRUE';
      INPUT_LOAD='(-0.01,0.01)';
      OUTPUT_LOAD='(1.0,-1.0)';
      PINUSE='BI';
    'IO59':
      PIN_NUMBER='(59)';
      BIDIRECTIONAL='TRUE';
      INPUT_LOAD='(-0.01,0.01)';
      OUTPUT_LOAD='(1.0,-1.0)';
      PINUSE='BI';
    'IO6':
      PIN_NUMBER='(6)';
      BIDIRECTIONAL='TRUE';
      INPUT_LOAD='(-0.01,0.01)';
      OUTPUT_LOAD='(1.0,-1.0)';
      PINUSE='BI';
    'IO60':
      PIN_NUMBER='(60)';
      BIDIRECTIONAL='TRUE';
      INPUT_LOAD='(-0.01,0.01)';
      OUTPUT_LOAD='(1.0,-1.0)';
      PINUSE='BI';
    'IO61':
      PIN_NUMBER='(61)';
      BIDIRECTIONAL='TRUE';
      INPUT_LOAD='(-0.01,0.01)';
      OUTPUT_LOAD='(1.0,-1.0)';
      PINUSE='BI';
    'IO62':
      PIN_NUMBER='(62)';
      BIDIRECTIONAL='TRUE';
      INPUT_LOAD='(-0.01,0.01)';
      OUTPUT_LOAD='(1.0,-1.0)';
      PINUSE='BI';
    'IO63':
      PIN_NUMBER='(63)';
      BIDIRECTIONAL='TRUE';
      INPUT_LOAD='(-0.01,0.01)';
      OUTPUT_LOAD='(1.0,-1.0)';
      PINUSE='BI';
    'IO64':
      PIN_NUMBER='(64)';
      BIDIRECTIONAL='TRUE';
      INPUT_LOAD='(-0.01,0.01)';
      OUTPUT_LOAD='(1.0,-1.0)';
      PINUSE='BI';
    'IO65':
      PIN_NUMBER='(65)';
      BIDIRECTIONAL='TRUE';
      INPUT_LOAD='(-0.01,0.01)';
      OUTPUT_LOAD='(1.0,-1.0)';
      PINUSE='BI';
    'IO66':
      PIN_NUMBER='(66)';
      BIDIRECTIONAL='TRUE';
      INPUT_LOAD='(-0.01,0.01)';
      OUTPUT_LOAD='(1.0,-1.0)';
      PINUSE='BI';
    'IO67':
      PIN_NUMBER='(67)';
      BIDIRECTIONAL='TRUE';
      INPUT_LOAD='(-0.01,0.01)';
      OUTPUT_LOAD='(1.0,-1.0)';
      PINUSE='BI';
    'IO68':
      PIN_NUMBER='(68)';
      BIDIRECTIONAL='TRUE';
      INPUT_LOAD='(-0.01,0.01)';
      OUTPUT_LOAD='(1.0,-1.0)';
      PINUSE='BI';
    'IO69':
      PIN_NUMBER='(69)';
      BIDIRECTIONAL='TRUE';
      INPUT_LOAD='(-0.01,0.01)';
      OUTPUT_LOAD='(1.0,-1.0)';
      PINUSE='BI';
    'IO7':
      PIN_NUMBER='(7)';
      BIDIRECTIONAL='TRUE';
      INPUT_LOAD='(-0.01,0.01)';
      OUTPUT_LOAD='(1.0,-1.0)';
      PINUSE='BI';
    'IO70':
      PIN_NUMBER='(70)';
      BIDIRECTIONAL='TRUE';
      INPUT_LOAD='(-0.01,0.01)';
      OUTPUT_LOAD='(1.0,-1.0)';
      PINUSE='BI';
    'IO71':
      PIN_NUMBER='(71)';
      BIDIRECTIONAL='TRUE';
      INPUT_LOAD='(-0.01,0.01)';
      OUTPUT_LOAD='(1.0,-1.0)';
      PINUSE='BI';
    'IO72':
      PIN_NUMBER='(72)';
      BIDIRECTIONAL='TRUE';
      INPUT_LOAD='(-0.01,0.01)';
      OUTPUT_LOAD='(1.0,-1.0)';
      PINUSE='BI';
    'IO73':
      PIN_NUMBER='(73)';
      BIDIRECTIONAL='TRUE';
      INPUT_LOAD='(-0.01,0.01)';
      OUTPUT_LOAD='(1.0,-1.0)';
      PINUSE='BI';
    'IO74':
      PIN_NUMBER='(74)';
      BIDIRECTIONAL='TRUE';
      INPUT_LOAD='(-0.01,0.01)';
      OUTPUT_LOAD='(1.0,-1.0)';
      PINUSE='BI';
    'IO75':
      PIN_NUMBER='(75)';
      BIDIRECTIONAL='TRUE';
      INPUT_LOAD='(-0.01,0.01)';
      OUTPUT_LOAD='(1.0,-1.0)';
      PINUSE='BI';
    'IO76':
      PIN_NUMBER='(76)';
      BIDIRECTIONAL='TRUE';
      INPUT_LOAD='(-0.01,0.01)';
      OUTPUT_LOAD='(1.0,-1.0)';
      PINUSE='BI';
    'IO77':
      PIN_NUMBER='(77)';
      BIDIRECTIONAL='TRUE';
      INPUT_LOAD='(-0.01,0.01)';
      OUTPUT_LOAD='(1.0,-1.0)';
      PINUSE='BI';
    'IO78':
      PIN_NUMBER='(78)';
      BIDIRECTIONAL='TRUE';
      INPUT_LOAD='(-0.01,0.01)';
      OUTPUT_LOAD='(1.0,-1.0)';
      PINUSE='BI';
    'IO79':
      PIN_NUMBER='(79)';
      BIDIRECTIONAL='TRUE';
      INPUT_LOAD='(-0.01,0.01)';
      OUTPUT_LOAD='(1.0,-1.0)';
      PINUSE='BI';
    'IO8':
      PIN_NUMBER='(8)';
      BIDIRECTIONAL='TRUE';
      INPUT_LOAD='(-0.01,0.01)';
      OUTPUT_LOAD='(1.0,-1.0)';
      PINUSE='BI';
    'IO80':
      PIN_NUMBER='(80)';
      BIDIRECTIONAL='TRUE';
      INPUT_LOAD='(-0.01,0.01)';
      OUTPUT_LOAD='(1.0,-1.0)';
      PINUSE='BI';
    'IO9':
      PIN_NUMBER='(9)';
      BIDIRECTIONAL='TRUE';
      INPUT_LOAD='(-0.01,0.01)';
      OUTPUT_LOAD='(1.0,-1.0)';
      PINUSE='BI';
  end_pin;
  body
      PART_NAME='SCONN80_E67482007';
      PHYS_DES_PREFIX='J';
      ENVCOMP='';
      PART_NUMBER='E67482-007';
      JEDEC_TYPE='SCONN80_E67482007';
      CLASS='IO';
      DESCRIPTION='CONN,BTB,80P,RCP,VT,0MM,.8MM';
      HEIGHT='0.472 IN';
      COMPONENT_TYPE='SMTCONN';
      LEAD_LENGTH='';
      LPID='1859';
      SPEED_URL='http://speed.intel.com:8081/speed/module/pdm/item/pdm_item_deta~
il_direct.asp?item_cde=E67482-007&item_rev=01&url_param=unused';
      STATUS='';
      RPL='';
      AML='';
      BUS_UNIT='';
      DAYS='';
      PARENT_PART_TYPE='SCONN80_E67482007_SM';
      PARENT_PPT='SCONN80_E67482007';
      PARENT_PPT_PART='SCONN80_E67482007_SM-CONN,E67482-007';
  end_body;
end_primitive;
primitive 'SE100U16VM-48-GP_SMD-TCG2-SE10A';
  pin
    '1':
      PIN_NUMBER='(1)';
      PIN_TYPE='ANALOG';
      NO_LOAD_CHECK='Both';
      NO_IO_CHECK='Both';
      NO_ASSERT_CHECK='TRUE';
      NO_DIR_CHECK='TRUE';
      ALLOW_CONNECT='TRUE';
      PINUSE='UNSPEC';
    '2':
      PIN_NUMBER='(2)';
      PIN_TYPE='ANALOG';
      NO_LOAD_CHECK='Both';
      NO_IO_CHECK='Both';
      NO_ASSERT_CHECK='TRUE';
      NO_DIR_CHECK='TRUE';
      ALLOW_CONNECT='TRUE';
      PINUSE='UNSPEC';
  end_pin;
  body
      PART_NAME='SE100U16VM-48-GP';
      BODY_NAME='SE100U16VM-48-GP';
      PHYS_DES_PREFIX='TC';
      CLASS='DISCRETE';
      DESCRIPTION='CHIP CAP EL POLAR 100U 16V M 5*5.8';
      JEDEC_TYPE='SE321409H241';
      PARENT_PART_TYPE='SE100U16VM-48-GP';
      PARENT_PPT='SE100U16VM-48-GP';
      PARENT_PPT_PART='SE100U16VM-48-GP_SMD-TCG2-SE100U16VM-48-GP,077.51081.0011';
  end_body;
end_primitive;
primitive 'SHUNT_SH0201-EMPTY,N_A';
  pin
    'A':
      PIN_NUMBER='(1)';
      PIN_TYPE='ANALOG';
      NO_LOAD_CHECK='Both';
      NO_IO_CHECK='Both';
      NO_ASSERT_CHECK='TRUE';
      NO_DIR_CHECK='TRUE';
      ALLOW_CONNECT='TRUE';
      PINUSE='UNSPEC';
    'B':
      PIN_NUMBER='(2)';
      PIN_TYPE='ANALOG';
      NO_LOAD_CHECK='Both';
      NO_IO_CHECK='Both';
      NO_ASSERT_CHECK='TRUE';
      NO_DIR_CHECK='TRUE';
      ALLOW_CONNECT='TRUE';
      PINUSE='UNSPEC';
  end_pin;
  body
      PART_NAME='SHUNT';
      PHYS_DES_PREFIX='SH';
      ENVCOMP='';
      PART_NUMBER='N_A';
      JEDEC_TYPE='SH0201A';
      CLASS='IO';
      DESCRIPTION='SHUNT 0201, ALWAYS EMPTY';
      HEIGHT='0.001 IN';
      COMPONENT_TYPE='PSUEDO';
      LPID='1864';
      STATUS='???';
      RPL='???';
      AML='???';
      BUS_UNIT='';
      DAYS='???';
      PARENT_PART_TYPE='SHUNT';
      PARENT_PPT='SHUNT';
      PARENT_PPT_PART='SHUNT_SH0201-EMPTY,N_A';
  end_body;
end_primitive;
primitive 'SKT-MINI67P-41-GP_SOCKET-G4-SKA';
  pin
    '1':
      PIN_NUMBER='(1)';
      PIN_TYPE='ANALOG';
      NO_LOAD_CHECK='Both';
      NO_IO_CHECK='Both';
      NO_ASSERT_CHECK='TRUE';
      NO_DIR_CHECK='TRUE';
      ALLOW_CONNECT='TRUE';
      PINUSE='UNSPEC';
    '3':
      PIN_NUMBER='(3)';
      PIN_TYPE='ANALOG';
      NO_LOAD_CHECK='Both';
      NO_IO_CHECK='Both';
      NO_ASSERT_CHECK='TRUE';
      NO_DIR_CHECK='TRUE';
      ALLOW_CONNECT='TRUE';
      PINUSE='UNSPEC';
    '5':
      PIN_NUMBER='(5)';
      PIN_TYPE='ANALOG';
      NO_LOAD_CHECK='Both';
      NO_IO_CHECK='Both';
      NO_ASSERT_CHECK='TRUE';
      NO_DIR_CHECK='TRUE';
      ALLOW_CONNECT='TRUE';
      PINUSE='UNSPEC';
    '7':
      PIN_NUMBER='(7)';
      PIN_TYPE='ANALOG';
      NO_LOAD_CHECK='Both';
      NO_IO_CHECK='Both';
      NO_ASSERT_CHECK='TRUE';
      NO_DIR_CHECK='TRUE';
      ALLOW_CONNECT='TRUE';
      PINUSE='UNSPEC';
    '9':
      PIN_NUMBER='(9)';
      PIN_TYPE='ANALOG';
      NO_LOAD_CHECK='Both';
      NO_IO_CHECK='Both';
      NO_ASSERT_CHECK='TRUE';
      NO_DIR_CHECK='TRUE';
      ALLOW_CONNECT='TRUE';
      PINUSE='UNSPEC';
    '11':
      PIN_NUMBER='(11)';
      PIN_TYPE='ANALOG';
      NO_LOAD_CHECK='Both';
      NO_IO_CHECK='Both';
      NO_ASSERT_CHECK='TRUE';
      NO_DIR_CHECK='TRUE';
      ALLOW_CONNECT='TRUE';
      PINUSE='UNSPEC';
    '13':
      PIN_NUMBER='(13)';
      PIN_TYPE='ANALOG';
      NO_LOAD_CHECK='Both';
      NO_IO_CHECK='Both';
      NO_ASSERT_CHECK='TRUE';
      NO_DIR_CHECK='TRUE';
      ALLOW_CONNECT='TRUE';
      PINUSE='UNSPEC';
    '15':
      PIN_NUMBER='(15)';
      PIN_TYPE='ANALOG';
      NO_LOAD_CHECK='Both';
      NO_IO_CHECK='Both';
      NO_ASSERT_CHECK='TRUE';
      NO_DIR_CHECK='TRUE';
      ALLOW_CONNECT='TRUE';
      PINUSE='UNSPEC';
    '17':
      PIN_NUMBER='(17)';
      PIN_TYPE='ANALOG';
      NO_LOAD_CHECK='Both';
      NO_IO_CHECK='Both';
      NO_ASSERT_CHECK='TRUE';
      NO_DIR_CHECK='TRUE';
      ALLOW_CONNECT='TRUE';
      PINUSE='UNSPEC';
    '19':
      PIN_NUMBER='(19)';
      PIN_TYPE='ANALOG';
      NO_LOAD_CHECK='Both';
      NO_IO_CHECK='Both';
      NO_ASSERT_CHECK='TRUE';
      NO_DIR_CHECK='TRUE';
      ALLOW_CONNECT='TRUE';
      PINUSE='UNSPEC';
    '21':
      PIN_NUMBER='(21)';
      PIN_TYPE='ANALOG';
      NO_LOAD_CHECK='Both';
      NO_IO_CHECK='Both';
      NO_ASSERT_CHECK='TRUE';
      NO_DIR_CHECK='TRUE';
      ALLOW_CONNECT='TRUE';
      PINUSE='UNSPEC';
    '23':
      PIN_NUMBER='(23)';
      PIN_TYPE='ANALOG';
      NO_LOAD_CHECK='Both';
      NO_IO_CHECK='Both';
      NO_ASSERT_CHECK='TRUE';
      NO_DIR_CHECK='TRUE';
      ALLOW_CONNECT='TRUE';
      PINUSE='UNSPEC';
    '25':
      PIN_NUMBER='(25)';
      PIN_TYPE='ANALOG';
      NO_LOAD_CHECK='Both';
      NO_IO_CHECK='Both';
      NO_ASSERT_CHECK='TRUE';
      NO_DIR_CHECK='TRUE';
      ALLOW_CONNECT='TRUE';
      PINUSE='UNSPEC';
    '27':
      PIN_NUMBER='(27)';
      PIN_TYPE='ANALOG';
      NO_LOAD_CHECK='Both';
      NO_IO_CHECK='Both';
      NO_ASSERT_CHECK='TRUE';
      NO_DIR_CHECK='TRUE';
      ALLOW_CONNECT='TRUE';
      PINUSE='UNSPEC';
    '29':
      PIN_NUMBER='(29)';
      PIN_TYPE='ANALOG';
      NO_LOAD_CHECK='Both';
      NO_IO_CHECK='Both';
      NO_ASSERT_CHECK='TRUE';
      NO_DIR_CHECK='TRUE';
      ALLOW_CONNECT='TRUE';
      PINUSE='UNSPEC';
    '31':
      PIN_NUMBER='(31)';
      PIN_TYPE='ANALOG';
      NO_LOAD_CHECK='Both';
      NO_IO_CHECK='Both';
      NO_ASSERT_CHECK='TRUE';
      NO_DIR_CHECK='TRUE';
      ALLOW_CONNECT='TRUE';
      PINUSE='UNSPEC';
    '33':
      PIN_NUMBER='(33)';
      PIN_TYPE='ANALOG';
      NO_LOAD_CHECK='Both';
      NO_IO_CHECK='Both';
      NO_ASSERT_CHECK='TRUE';
      NO_DIR_CHECK='TRUE';
      ALLOW_CONNECT='TRUE';
      PINUSE='UNSPEC';
    '35':
      PIN_NUMBER='(35)';
      PIN_TYPE='ANALOG';
      NO_LOAD_CHECK='Both';
      NO_IO_CHECK='Both';
      NO_ASSERT_CHECK='TRUE';
      NO_DIR_CHECK='TRUE';
      ALLOW_CONNECT='TRUE';
      PINUSE='UNSPEC';
    '37':
      PIN_NUMBER='(37)';
      PIN_TYPE='ANALOG';
      NO_LOAD_CHECK='Both';
      NO_IO_CHECK='Both';
      NO_ASSERT_CHECK='TRUE';
      NO_DIR_CHECK='TRUE';
      ALLOW_CONNECT='TRUE';
      PINUSE='UNSPEC';
    '39':
      PIN_NUMBER='(39)';
      PIN_TYPE='ANALOG';
      NO_LOAD_CHECK='Both';
      NO_IO_CHECK='Both';
      NO_ASSERT_CHECK='TRUE';
      NO_DIR_CHECK='TRUE';
      ALLOW_CONNECT='TRUE';
      PINUSE='UNSPEC';
    '41':
      PIN_NUMBER='(41)';
      PIN_TYPE='ANALOG';
      NO_LOAD_CHECK='Both';
      NO_IO_CHECK='Both';
      NO_ASSERT_CHECK='TRUE';
      NO_DIR_CHECK='TRUE';
      ALLOW_CONNECT='TRUE';
      PINUSE='UNSPEC';
    '43':
      PIN_NUMBER='(43)';
      PIN_TYPE='ANALOG';
      NO_LOAD_CHECK='Both';
      NO_IO_CHECK='Both';
      NO_ASSERT_CHECK='TRUE';
      NO_DIR_CHECK='TRUE';
      ALLOW_CONNECT='TRUE';
      PINUSE='UNSPEC';
    '45':
      PIN_NUMBER='(45)';
      PIN_TYPE='ANALOG';
      NO_LOAD_CHECK='Both';
      NO_IO_CHECK='Both';
      NO_ASSERT_CHECK='TRUE';
      NO_DIR_CHECK='TRUE';
      ALLOW_CONNECT='TRUE';
      PINUSE='UNSPEC';
    '47':
      PIN_NUMBER='(47)';
      PIN_TYPE='ANALOG';
      NO_LOAD_CHECK='Both';
      NO_IO_CHECK='Both';
      NO_ASSERT_CHECK='TRUE';
      NO_DIR_CHECK='TRUE';
      ALLOW_CONNECT='TRUE';
      PINUSE='UNSPEC';
    '49':
      PIN_NUMBER='(49)';
      PIN_TYPE='ANALOG';
      NO_LOAD_CHECK='Both';
      NO_IO_CHECK='Both';
      NO_ASSERT_CHECK='TRUE';
      NO_DIR_CHECK='TRUE';
      ALLOW_CONNECT='TRUE';
      PINUSE='UNSPEC';
    '51':
      PIN_NUMBER='(51)';
      PIN_TYPE='ANALOG';
      NO_LOAD_CHECK='Both';
      NO_IO_CHECK='Both';
      NO_ASSERT_CHECK='TRUE';
      NO_DIR_CHECK='TRUE';
      ALLOW_CONNECT='TRUE';
      PINUSE='UNSPEC';
    '53':
      PIN_NUMBER='(53)';
      PIN_TYPE='ANALOG';
      NO_LOAD_CHECK='Both';
      NO_IO_CHECK='Both';
      NO_ASSERT_CHECK='TRUE';
      NO_DIR_CHECK='TRUE';
      ALLOW_CONNECT='TRUE';
      PINUSE='UNSPEC';
    '55':
      PIN_NUMBER='(55)';
      PIN_TYPE='ANALOG';
      NO_LOAD_CHECK='Both';
      NO_IO_CHECK='Both';
      NO_ASSERT_CHECK='TRUE';
      NO_DIR_CHECK='TRUE';
      ALLOW_CONNECT='TRUE';
      PINUSE='UNSPEC';
    '57':
      PIN_NUMBER='(57)';
      PIN_TYPE='ANALOG';
      NO_LOAD_CHECK='Both';
      NO_IO_CHECK='Both';
      NO_ASSERT_CHECK='TRUE';
      NO_DIR_CHECK='TRUE';
      ALLOW_CONNECT='TRUE';
      PINUSE='UNSPEC';
    '67':
      PIN_NUMBER='(67)';
      PIN_TYPE='ANALOG';
      NO_LOAD_CHECK='Both';
      NO_IO_CHECK='Both';
      NO_ASSERT_CHECK='TRUE';
      NO_DIR_CHECK='TRUE';
      ALLOW_CONNECT='TRUE';
      PINUSE='UNSPEC';
    '69':
      PIN_NUMBER='(69)';
      PIN_TYPE='ANALOG';
      NO_LOAD_CHECK='Both';
      NO_IO_CHECK='Both';
      NO_ASSERT_CHECK='TRUE';
      NO_DIR_CHECK='TRUE';
      ALLOW_CONNECT='TRUE';
      PINUSE='UNSPEC';
    '71':
      PIN_NUMBER='(71)';
      PIN_TYPE='ANALOG';
      NO_LOAD_CHECK='Both';
      NO_IO_CHECK='Both';
      NO_ASSERT_CHECK='TRUE';
      NO_DIR_CHECK='TRUE';
      ALLOW_CONNECT='TRUE';
      PINUSE='UNSPEC';
    '73':
      PIN_NUMBER='(73)';
      PIN_TYPE='ANALOG';
      NO_LOAD_CHECK='Both';
      NO_IO_CHECK='Both';
      NO_ASSERT_CHECK='TRUE';
      NO_DIR_CHECK='TRUE';
      ALLOW_CONNECT='TRUE';
      PINUSE='UNSPEC';
    '75':
      PIN_NUMBER='(75)';
      PIN_TYPE='ANALOG';
      NO_LOAD_CHECK='Both';
      NO_IO_CHECK='Both';
      NO_ASSERT_CHECK='TRUE';
      NO_DIR_CHECK='TRUE';
      ALLOW_CONNECT='TRUE';
      PINUSE='UNSPEC';
    '2':
      PIN_NUMBER='(2)';
      PIN_TYPE='ANALOG';
      NO_LOAD_CHECK='Both';
      NO_IO_CHECK='Both';
      NO_ASSERT_CHECK='TRUE';
      NO_DIR_CHECK='TRUE';
      ALLOW_CONNECT='TRUE';
      PINUSE='UNSPEC';
    '4':
      PIN_NUMBER='(4)';
      PIN_TYPE='ANALOG';
      NO_LOAD_CHECK='Both';
      NO_IO_CHECK='Both';
      NO_ASSERT_CHECK='TRUE';
      NO_DIR_CHECK='TRUE';
      ALLOW_CONNECT='TRUE';
      PINUSE='UNSPEC';
    '6':
      PIN_NUMBER='(6)';
      PIN_TYPE='ANALOG';
      NO_LOAD_CHECK='Both';
      NO_IO_CHECK='Both';
      NO_ASSERT_CHECK='TRUE';
      NO_DIR_CHECK='TRUE';
      ALLOW_CONNECT='TRUE';
      PINUSE='UNSPEC';
    '8':
      PIN_NUMBER='(8)';
      PIN_TYPE='ANALOG';
      NO_LOAD_CHECK='Both';
      NO_IO_CHECK='Both';
      NO_ASSERT_CHECK='TRUE';
      NO_DIR_CHECK='TRUE';
      ALLOW_CONNECT='TRUE';
      PINUSE='UNSPEC';
    '10':
      PIN_NUMBER='(10)';
      PIN_TYPE='ANALOG';
      NO_LOAD_CHECK='Both';
      NO_IO_CHECK='Both';
      NO_ASSERT_CHECK='TRUE';
      NO_DIR_CHECK='TRUE';
      ALLOW_CONNECT='TRUE';
      PINUSE='UNSPEC';
    '12':
      PIN_NUMBER='(12)';
      PIN_TYPE='ANALOG';
      NO_LOAD_CHECK='Both';
      NO_IO_CHECK='Both';
      NO_ASSERT_CHECK='TRUE';
      NO_DIR_CHECK='TRUE';
      ALLOW_CONNECT='TRUE';
      PINUSE='UNSPEC';
    '14':
      PIN_NUMBER='(14)';
      PIN_TYPE='ANALOG';
      NO_LOAD_CHECK='Both';
      NO_IO_CHECK='Both';
      NO_ASSERT_CHECK='TRUE';
      NO_DIR_CHECK='TRUE';
      ALLOW_CONNECT='TRUE';
      PINUSE='UNSPEC';
    '16':
      PIN_NUMBER='(16)';
      PIN_TYPE='ANALOG';
      NO_LOAD_CHECK='Both';
      NO_IO_CHECK='Both';
      NO_ASSERT_CHECK='TRUE';
      NO_DIR_CHECK='TRUE';
      ALLOW_CONNECT='TRUE';
      PINUSE='UNSPEC';
    '18':
      PIN_NUMBER='(18)';
      PIN_TYPE='ANALOG';
      NO_LOAD_CHECK='Both';
      NO_IO_CHECK='Both';
      NO_ASSERT_CHECK='TRUE';
      NO_DIR_CHECK='TRUE';
      ALLOW_CONNECT='TRUE';
      PINUSE='UNSPEC';
    '20':
      PIN_NUMBER='(20)';
      PIN_TYPE='ANALOG';
      NO_LOAD_CHECK='Both';
      NO_IO_CHECK='Both';
      NO_ASSERT_CHECK='TRUE';
      NO_DIR_CHECK='TRUE';
      ALLOW_CONNECT='TRUE';
      PINUSE='UNSPEC';
    '22':
      PIN_NUMBER='(22)';
      PIN_TYPE='ANALOG';
      NO_LOAD_CHECK='Both';
      NO_IO_CHECK='Both';
      NO_ASSERT_CHECK='TRUE';
      NO_DIR_CHECK='TRUE';
      ALLOW_CONNECT='TRUE';
      PINUSE='UNSPEC';
    '24':
      PIN_NUMBER='(24)';
      PIN_TYPE='ANALOG';
      NO_LOAD_CHECK='Both';
      NO_IO_CHECK='Both';
      NO_ASSERT_CHECK='TRUE';
      NO_DIR_CHECK='TRUE';
      ALLOW_CONNECT='TRUE';
      PINUSE='UNSPEC';
    '26':
      PIN_NUMBER='(26)';
      PIN_TYPE='ANALOG';
      NO_LOAD_CHECK='Both';
      NO_IO_CHECK='Both';
      NO_ASSERT_CHECK='TRUE';
      NO_DIR_CHECK='TRUE';
      ALLOW_CONNECT='TRUE';
      PINUSE='UNSPEC';
    '28':
      PIN_NUMBER='(28)';
      PIN_TYPE='ANALOG';
      NO_LOAD_CHECK='Both';
      NO_IO_CHECK='Both';
      NO_ASSERT_CHECK='TRUE';
      NO_DIR_CHECK='TRUE';
      ALLOW_CONNECT='TRUE';
      PINUSE='UNSPEC';
    '30':
      PIN_NUMBER='(30)';
      PIN_TYPE='ANALOG';
      NO_LOAD_CHECK='Both';
      NO_IO_CHECK='Both';
      NO_ASSERT_CHECK='TRUE';
      NO_DIR_CHECK='TRUE';
      ALLOW_CONNECT='TRUE';
      PINUSE='UNSPEC';
    '32':
      PIN_NUMBER='(32)';
      PIN_TYPE='ANALOG';
      NO_LOAD_CHECK='Both';
      NO_IO_CHECK='Both';
      NO_ASSERT_CHECK='TRUE';
      NO_DIR_CHECK='TRUE';
      ALLOW_CONNECT='TRUE';
      PINUSE='UNSPEC';
    '34':
      PIN_NUMBER='(34)';
      PIN_TYPE='ANALOG';
      NO_LOAD_CHECK='Both';
      NO_IO_CHECK='Both';
      NO_ASSERT_CHECK='TRUE';
      NO_DIR_CHECK='TRUE';
      ALLOW_CONNECT='TRUE';
      PINUSE='UNSPEC';
    '36':
      PIN_NUMBER='(36)';
      PIN_TYPE='ANALOG';
      NO_LOAD_CHECK='Both';
      NO_IO_CHECK='Both';
      NO_ASSERT_CHECK='TRUE';
      NO_DIR_CHECK='TRUE';
      ALLOW_CONNECT='TRUE';
      PINUSE='UNSPEC';
    '38':
      PIN_NUMBER='(38)';
      PIN_TYPE='ANALOG';
      NO_LOAD_CHECK='Both';
      NO_IO_CHECK='Both';
      NO_ASSERT_CHECK='TRUE';
      NO_DIR_CHECK='TRUE';
      ALLOW_CONNECT='TRUE';
      PINUSE='UNSPEC';
    '40':
      PIN_NUMBER='(40)';
      PIN_TYPE='ANALOG';
      NO_LOAD_CHECK='Both';
      NO_IO_CHECK='Both';
      NO_ASSERT_CHECK='TRUE';
      NO_DIR_CHECK='TRUE';
      ALLOW_CONNECT='TRUE';
      PINUSE='UNSPEC';
    '42':
      PIN_NUMBER='(42)';
      PIN_TYPE='ANALOG';
      NO_LOAD_CHECK='Both';
      NO_IO_CHECK='Both';
      NO_ASSERT_CHECK='TRUE';
      NO_DIR_CHECK='TRUE';
      ALLOW_CONNECT='TRUE';
      PINUSE='UNSPEC';
    '44':
      PIN_NUMBER='(44)';
      PIN_TYPE='ANALOG';
      NO_LOAD_CHECK='Both';
      NO_IO_CHECK='Both';
      NO_ASSERT_CHECK='TRUE';
      NO_DIR_CHECK='TRUE';
      ALLOW_CONNECT='TRUE';
      PINUSE='UNSPEC';
    '46':
      PIN_NUMBER='(46)';
      PIN_TYPE='ANALOG';
      NO_LOAD_CHECK='Both';
      NO_IO_CHECK='Both';
      NO_ASSERT_CHECK='TRUE';
      NO_DIR_CHECK='TRUE';
      ALLOW_CONNECT='TRUE';
      PINUSE='UNSPEC';
    '48':
      PIN_NUMBER='(48)';
      PIN_TYPE='ANALOG';
      NO_LOAD_CHECK='Both';
      NO_IO_CHECK='Both';
      NO_ASSERT_CHECK='TRUE';
      NO_DIR_CHECK='TRUE';
      ALLOW_CONNECT='TRUE';
      PINUSE='UNSPEC';
    '50':
      PIN_NUMBER='(50)';
      PIN_TYPE='ANALOG';
      NO_LOAD_CHECK='Both';
      NO_IO_CHECK='Both';
      NO_ASSERT_CHECK='TRUE';
      NO_DIR_CHECK='TRUE';
      ALLOW_CONNECT='TRUE';
      PINUSE='UNSPEC';
    '52':
      PIN_NUMBER='(52)';
      PIN_TYPE='ANALOG';
      NO_LOAD_CHECK='Both';
      NO_IO_CHECK='Both';
      NO_ASSERT_CHECK='TRUE';
      NO_DIR_CHECK='TRUE';
      ALLOW_CONNECT='TRUE';
      PINUSE='UNSPEC';
    '54':
      PIN_NUMBER='(54)';
      PIN_TYPE='ANALOG';
      NO_LOAD_CHECK='Both';
      NO_IO_CHECK='Both';
      NO_ASSERT_CHECK='TRUE';
      NO_DIR_CHECK='TRUE';
      ALLOW_CONNECT='TRUE';
      PINUSE='UNSPEC';
    '56':
      PIN_NUMBER='(56)';
      PIN_TYPE='ANALOG';
      NO_LOAD_CHECK='Both';
      NO_IO_CHECK='Both';
      NO_ASSERT_CHECK='TRUE';
      NO_DIR_CHECK='TRUE';
      ALLOW_CONNECT='TRUE';
      PINUSE='UNSPEC';
    '58':
      PIN_NUMBER='(58)';
      PIN_TYPE='ANALOG';
      NO_LOAD_CHECK='Both';
      NO_IO_CHECK='Both';
      NO_ASSERT_CHECK='TRUE';
      NO_DIR_CHECK='TRUE';
      ALLOW_CONNECT='TRUE';
      PINUSE='UNSPEC';
    '68':
      PIN_NUMBER='(68)';
      PIN_TYPE='ANALOG';
      NO_LOAD_CHECK='Both';
      NO_IO_CHECK='Both';
      NO_ASSERT_CHECK='TRUE';
      NO_DIR_CHECK='TRUE';
      ALLOW_CONNECT='TRUE';
      PINUSE='UNSPEC';
    '70':
      PIN_NUMBER='(70)';
      PIN_TYPE='ANALOG';
      NO_LOAD_CHECK='Both';
      NO_IO_CHECK='Both';
      NO_ASSERT_CHECK='TRUE';
      NO_DIR_CHECK='TRUE';
      ALLOW_CONNECT='TRUE';
      PINUSE='UNSPEC';
    '72':
      PIN_NUMBER='(72)';
      PIN_TYPE='ANALOG';
      NO_LOAD_CHECK='Both';
      NO_IO_CHECK='Both';
      NO_ASSERT_CHECK='TRUE';
      NO_DIR_CHECK='TRUE';
      ALLOW_CONNECT='TRUE';
      PINUSE='UNSPEC';
    '74':
      PIN_NUMBER='(74)';
      PIN_TYPE='ANALOG';
      NO_LOAD_CHECK='Both';
      NO_IO_CHECK='Both';
      NO_ASSERT_CHECK='TRUE';
      NO_DIR_CHECK='TRUE';
      ALLOW_CONNECT='TRUE';
      PINUSE='UNSPEC';
    '76':
      PIN_NUMBER='(76)';
      PIN_TYPE='ANALOG';
      NO_LOAD_CHECK='Both';
      NO_IO_CHECK='Both';
      NO_ASSERT_CHECK='TRUE';
      NO_DIR_CHECK='TRUE';
      ALLOW_CONNECT='TRUE';
      PINUSE='UNSPEC';
    '77':
      PIN_NUMBER='(77)';
      PIN_TYPE='ANALOG';
      NO_LOAD_CHECK='Both';
      NO_IO_CHECK='Both';
      NO_ASSERT_CHECK='TRUE';
      NO_DIR_CHECK='TRUE';
      ALLOW_CONNECT='TRUE';
      PINUSE='UNSPEC';
    'NP1':
      PIN_NUMBER='(NP1)';
      PIN_TYPE='ANALOG';
      NO_LOAD_CHECK='Both';
      NO_IO_CHECK='Both';
      NO_ASSERT_CHECK='TRUE';
      NO_DIR_CHECK='TRUE';
      ALLOW_CONNECT='TRUE';
      PINUSE='UNSPEC';
    'NP2':
      PIN_NUMBER='(NP2)';
      PIN_TYPE='ANALOG';
      NO_LOAD_CHECK='Both';
      NO_IO_CHECK='Both';
      NO_ASSERT_CHECK='TRUE';
      NO_DIR_CHECK='TRUE';
      ALLOW_CONNECT='TRUE';
      PINUSE='UNSPEC';
  end_pin;
  body
      PART_NAME='SKT-MINI67P-41-GP';
      BODY_NAME='SKT-MINI67P-41-GP';
      PHYS_DES_PREFIX='SKT';
      CLASS='DISCRETE';
      DESCRIPTION='SKT NGFF 67P AS0BC23-S67BM-LH SMD';
      JEDEC_TYPE='AS0BC23-S67BM-LH';
      PARENT_PART_TYPE='SKT-MINI67P-41-GP';
      PARENT_PPT='SKT-MINI67P-41-GP';
      PARENT_PPT_PART='SKT-MINI67P-41-GP_SOCKET-G4-SKT-MINI67P-41-GP,062.10003.0B21';
  end_body;
end_primitive;
primitive 'SKT-RJ45-LED-XFOR-1-GP_SOCKET-A';
  pin
    'L1':
      PIN_NUMBER='(L1)';
      PIN_TYPE='ANALOG';
      NO_LOAD_CHECK='Both';
      NO_IO_CHECK='Both';
      NO_ASSERT_CHECK='TRUE';
      NO_DIR_CHECK='TRUE';
      ALLOW_CONNECT='TRUE';
      PINUSE='UNSPEC';
    'L2':
      PIN_NUMBER='(L2)';
      PIN_TYPE='ANALOG';
      NO_LOAD_CHECK='Both';
      NO_IO_CHECK='Both';
      NO_ASSERT_CHECK='TRUE';
      NO_DIR_CHECK='TRUE';
      ALLOW_CONNECT='TRUE';
      PINUSE='UNSPEC';
    'L3':
      PIN_NUMBER='(L3)';
      PIN_TYPE='ANALOG';
      NO_LOAD_CHECK='Both';
      NO_IO_CHECK='Both';
      NO_ASSERT_CHECK='TRUE';
      NO_DIR_CHECK='TRUE';
      ALLOW_CONNECT='TRUE';
      PINUSE='UNSPEC';
    'L4':
      PIN_NUMBER='(L4)';
      PIN_TYPE='ANALOG';
      NO_LOAD_CHECK='Both';
      NO_IO_CHECK='Both';
      NO_ASSERT_CHECK='TRUE';
      NO_DIR_CHECK='TRUE';
      ALLOW_CONNECT='TRUE';
      PINUSE='UNSPEC';
    'R1':
      PIN_NUMBER='(R1)';
      PIN_TYPE='ANALOG';
      NO_LOAD_CHECK='Both';
      NO_IO_CHECK='Both';
      NO_ASSERT_CHECK='TRUE';
      NO_DIR_CHECK='TRUE';
      ALLOW_CONNECT='TRUE';
      PINUSE='UNSPEC';
    'R2':
      PIN_NUMBER='(R2)';
      PIN_TYPE='ANALOG';
      NO_LOAD_CHECK='Both';
      NO_IO_CHECK='Both';
      NO_ASSERT_CHECK='TRUE';
      NO_DIR_CHECK='TRUE';
      ALLOW_CONNECT='TRUE';
      PINUSE='UNSPEC';
    'R3':
      PIN_NUMBER='(R3)';
      PIN_TYPE='ANALOG';
      NO_LOAD_CHECK='Both';
      NO_IO_CHECK='Both';
      NO_ASSERT_CHECK='TRUE';
      NO_DIR_CHECK='TRUE';
      ALLOW_CONNECT='TRUE';
      PINUSE='UNSPEC';
    'R4':
      PIN_NUMBER='(R4)';
      PIN_TYPE='ANALOG';
      NO_LOAD_CHECK='Both';
      NO_IO_CHECK='Both';
      NO_ASSERT_CHECK='TRUE';
      NO_DIR_CHECK='TRUE';
      ALLOW_CONNECT='TRUE';
      PINUSE='UNSPEC';
    'R5':
      PIN_NUMBER='(R5)';
      PIN_TYPE='ANALOG';
      NO_LOAD_CHECK='Both';
      NO_IO_CHECK='Both';
      NO_ASSERT_CHECK='TRUE';
      NO_DIR_CHECK='TRUE';
      ALLOW_CONNECT='TRUE';
      PINUSE='UNSPEC';
    'R6':
      PIN_NUMBER='(R6)';
      PIN_TYPE='ANALOG';
      NO_LOAD_CHECK='Both';
      NO_IO_CHECK='Both';
      NO_ASSERT_CHECK='TRUE';
      NO_DIR_CHECK='TRUE';
      ALLOW_CONNECT='TRUE';
      PINUSE='UNSPEC';
    'R7':
      PIN_NUMBER='(R7)';
      PIN_TYPE='ANALOG';
      NO_LOAD_CHECK='Both';
      NO_IO_CHECK='Both';
      NO_ASSERT_CHECK='TRUE';
      NO_DIR_CHECK='TRUE';
      ALLOW_CONNECT='TRUE';
      PINUSE='UNSPEC';
    'R8':
      PIN_NUMBER='(R8)';
      PIN_TYPE='ANALOG';
      NO_LOAD_CHECK='Both';
      NO_IO_CHECK='Both';
      NO_ASSERT_CHECK='TRUE';
      NO_DIR_CHECK='TRUE';
      ALLOW_CONNECT='TRUE';
      PINUSE='UNSPEC';
    'R9':
      PIN_NUMBER='(R9)';
      PIN_TYPE='ANALOG';
      NO_LOAD_CHECK='Both';
      NO_IO_CHECK='Both';
      NO_ASSERT_CHECK='TRUE';
      NO_DIR_CHECK='TRUE';
      ALLOW_CONNECT='TRUE';
      PINUSE='UNSPEC';
    'R10':
      PIN_NUMBER='(R10)';
      PIN_TYPE='ANALOG';
      NO_LOAD_CHECK='Both';
      NO_IO_CHECK='Both';
      NO_ASSERT_CHECK='TRUE';
      NO_DIR_CHECK='TRUE';
      ALLOW_CONNECT='TRUE';
      PINUSE='UNSPEC';
    'R11':
      PIN_NUMBER='(R11)';
      PIN_TYPE='ANALOG';
      NO_LOAD_CHECK='Both';
      NO_IO_CHECK='Both';
      NO_ASSERT_CHECK='TRUE';
      NO_DIR_CHECK='TRUE';
      ALLOW_CONNECT='TRUE';
      PINUSE='UNSPEC';
    '1':
      PIN_NUMBER='(1)';
      PIN_TYPE='ANALOG';
      NO_LOAD_CHECK='Both';
      NO_IO_CHECK='Both';
      NO_ASSERT_CHECK='TRUE';
      NO_DIR_CHECK='TRUE';
      ALLOW_CONNECT='TRUE';
      PINUSE='UNSPEC';
    '2':
      PIN_NUMBER='(2)';
      PIN_TYPE='ANALOG';
      NO_LOAD_CHECK='Both';
      NO_IO_CHECK='Both';
      NO_ASSERT_CHECK='TRUE';
      NO_DIR_CHECK='TRUE';
      ALLOW_CONNECT='TRUE';
      PINUSE='UNSPEC';
  end_pin;
  body
      PART_NAME='SKT-RJ45-LED-XFOR-1-GP';
      BODY_NAME='SKT-RJ45-LED-XFOR-1-GP';
      PHYS_DES_PREFIX='RJ';
      CLASS='IO';
      DESCRIPTION='SKT RJ45+LED+XFOR RS3-WT-0001, PA6T';
      JEDEC_TYPE='RS3-2840H41A';
      PARENT_PART_TYPE='SKT-RJ45-LED-XFOR-1-GP';
      PARENT_PPT='SKT-RJ45-LED-XFOR-1-GP';
      PARENT_PPT_PART='SKT-RJ45-LED-XFOR-1-GP_SOCKET-G2-SKT-RJ45-LED-XFOR-1-GP,022.10001.0S51';
  end_body;
end_primitive;
primitive 'SKT-SATA7P-6P-165-GP-U1_SOCKETA';
  pin
    'S1':
      PIN_NUMBER='(S1)';
      PIN_TYPE='ANALOG';
      NO_LOAD_CHECK='Both';
      NO_IO_CHECK='Both';
      NO_ASSERT_CHECK='TRUE';
      NO_DIR_CHECK='TRUE';
      ALLOW_CONNECT='TRUE';
      PINUSE='UNSPEC';
    'S2':
      PIN_NUMBER='(S2)';
      PIN_TYPE='ANALOG';
      NO_LOAD_CHECK='Both';
      NO_IO_CHECK='Both';
      NO_ASSERT_CHECK='TRUE';
      NO_DIR_CHECK='TRUE';
      ALLOW_CONNECT='TRUE';
      PINUSE='UNSPEC';
    'S3':
      PIN_NUMBER='(S3)';
      PIN_TYPE='ANALOG';
      NO_LOAD_CHECK='Both';
      NO_IO_CHECK='Both';
      NO_ASSERT_CHECK='TRUE';
      NO_DIR_CHECK='TRUE';
      ALLOW_CONNECT='TRUE';
      PINUSE='UNSPEC';
    'S4':
      PIN_NUMBER='(S4)';
      PIN_TYPE='ANALOG';
      NO_LOAD_CHECK='Both';
      NO_IO_CHECK='Both';
      NO_ASSERT_CHECK='TRUE';
      NO_DIR_CHECK='TRUE';
      ALLOW_CONNECT='TRUE';
      PINUSE='UNSPEC';
    'S5':
      PIN_NUMBER='(S5)';
      PIN_TYPE='ANALOG';
      NO_LOAD_CHECK='Both';
      NO_IO_CHECK='Both';
      NO_ASSERT_CHECK='TRUE';
      NO_DIR_CHECK='TRUE';
      ALLOW_CONNECT='TRUE';
      PINUSE='UNSPEC';
    'S6':
      PIN_NUMBER='(S6)';
      PIN_TYPE='ANALOG';
      NO_LOAD_CHECK='Both';
      NO_IO_CHECK='Both';
      NO_ASSERT_CHECK='TRUE';
      NO_DIR_CHECK='TRUE';
      ALLOW_CONNECT='TRUE';
      PINUSE='UNSPEC';
    'S7':
      PIN_NUMBER='(S7)';
      PIN_TYPE='ANALOG';
      NO_LOAD_CHECK='Both';
      NO_IO_CHECK='Both';
      NO_ASSERT_CHECK='TRUE';
      NO_DIR_CHECK='TRUE';
      ALLOW_CONNECT='TRUE';
      PINUSE='UNSPEC';
    'P1':
      PIN_NUMBER='(P1)';
      PIN_TYPE='ANALOG';
      NO_LOAD_CHECK='Both';
      NO_IO_CHECK='Both';
      NO_ASSERT_CHECK='TRUE';
      NO_DIR_CHECK='TRUE';
      ALLOW_CONNECT='TRUE';
      PINUSE='UNSPEC';
    'P2':
      PIN_NUMBER='(P2)';
      PIN_TYPE='ANALOG';
      NO_LOAD_CHECK='Both';
      NO_IO_CHECK='Both';
      NO_ASSERT_CHECK='TRUE';
      NO_DIR_CHECK='TRUE';
      ALLOW_CONNECT='TRUE';
      PINUSE='UNSPEC';
    'P3':
      PIN_NUMBER='(P3)';
      PIN_TYPE='ANALOG';
      NO_LOAD_CHECK='Both';
      NO_IO_CHECK='Both';
      NO_ASSERT_CHECK='TRUE';
      NO_DIR_CHECK='TRUE';
      ALLOW_CONNECT='TRUE';
      PINUSE='UNSPEC';
    'P4':
      PIN_NUMBER='(P4)';
      PIN_TYPE='ANALOG';
      NO_LOAD_CHECK='Both';
      NO_IO_CHECK='Both';
      NO_ASSERT_CHECK='TRUE';
      NO_DIR_CHECK='TRUE';
      ALLOW_CONNECT='TRUE';
      PINUSE='UNSPEC';
    'P5':
      PIN_NUMBER='(P5)';
      PIN_TYPE='ANALOG';
      NO_LOAD_CHECK='Both';
      NO_IO_CHECK='Both';
      NO_ASSERT_CHECK='TRUE';
      NO_DIR_CHECK='TRUE';
      ALLOW_CONNECT='TRUE';
      PINUSE='UNSPEC';
    'P6':
      PIN_NUMBER='(P6)';
      PIN_TYPE='ANALOG';
      NO_LOAD_CHECK='Both';
      NO_IO_CHECK='Both';
      NO_ASSERT_CHECK='TRUE';
      NO_DIR_CHECK='TRUE';
      ALLOW_CONNECT='TRUE';
      PINUSE='UNSPEC';
    'NP1':
      PIN_NUMBER='(NP1)';
      PIN_TYPE='ANALOG';
      NO_LOAD_CHECK='Both';
      NO_IO_CHECK='Both';
      NO_ASSERT_CHECK='TRUE';
      NO_DIR_CHECK='TRUE';
      ALLOW_CONNECT='TRUE';
      PINUSE='UNSPEC';
    'NP2':
      PIN_NUMBER='(NP2)';
      PIN_TYPE='ANALOG';
      NO_LOAD_CHECK='Both';
      NO_IO_CHECK='Both';
      NO_ASSERT_CHECK='TRUE';
      NO_DIR_CHECK='TRUE';
      ALLOW_CONNECT='TRUE';
      PINUSE='UNSPEC';
    'H1':
      PIN_NUMBER='(H1)';
      PIN_TYPE='ANALOG';
      NO_LOAD_CHECK='Both';
      NO_IO_CHECK='Both';
      NO_ASSERT_CHECK='TRUE';
      NO_DIR_CHECK='TRUE';
      ALLOW_CONNECT='TRUE';
      PINUSE='UNSPEC';
    'H2':
      PIN_NUMBER='(H2)';
      PIN_TYPE='ANALOG';
      NO_LOAD_CHECK='Both';
      NO_IO_CHECK='Both';
      NO_ASSERT_CHECK='TRUE';
      NO_DIR_CHECK='TRUE';
      ALLOW_CONNECT='TRUE';
      PINUSE='UNSPEC';
  end_pin;
  body
      PART_NAME='SKT-SATA7P-6P-165-GP-U1';
      BODY_NAME='SKT-SATA7P-6P-165-GP-U1';
      PHYS_DES_PREFIX='SKT';
      CLASS='IO';
      DESCRIPTION='SKT SATA 7+6P ST C18625-11331-L MT DIP';
      JEDEC_TYPE='C18625-11331-L-U1';
      PARENT_PART_TYPE='SKT-SATA7P-6P-165-GP-U1';
      PARENT_PPT='SKT-SATA7P-6P-165-GP-U1';
      PARENT_PPT_PART='SKT-SATA7P-6P-165-GP-U1_SOCKET-G6-SKT-SATA7P-6P-165-GP-U1,022.10014.0121';
  end_body;
end_primitive;
primitive 'SKT-USB32-8-GP_SOCKET-G4-SKT-UA';
  pin
    'SSTXP1':
      PIN_NUMBER='(A2)';
      PIN_TYPE='ANALOG';
      NO_LOAD_CHECK='Both';
      NO_IO_CHECK='Both';
      NO_ASSERT_CHECK='TRUE';
      NO_DIR_CHECK='TRUE';
      ALLOW_CONNECT='TRUE';
      PINUSE='UNSPEC';
    'SSTXN1':
      PIN_NUMBER='(A3)';
      PIN_TYPE='ANALOG';
      NO_LOAD_CHECK='Both';
      NO_IO_CHECK='Both';
      NO_ASSERT_CHECK='TRUE';
      NO_DIR_CHECK='TRUE';
      ALLOW_CONNECT='TRUE';
      PINUSE='UNSPEC';
    'CC1':
      PIN_NUMBER='(A5)';
      PIN_TYPE='ANALOG';
      NO_LOAD_CHECK='Both';
      NO_IO_CHECK='Both';
      NO_ASSERT_CHECK='TRUE';
      NO_DIR_CHECK='TRUE';
      ALLOW_CONNECT='TRUE';
      PINUSE='UNSPEC';
    'DP1':
      PIN_NUMBER='(A6)';
      PIN_TYPE='ANALOG';
      NO_LOAD_CHECK='Both';
      NO_IO_CHECK='Both';
      NO_ASSERT_CHECK='TRUE';
      NO_DIR_CHECK='TRUE';
      ALLOW_CONNECT='TRUE';
      PINUSE='UNSPEC';
    'DN1':
      PIN_NUMBER='(A7)';
      PIN_TYPE='ANALOG';
      NO_LOAD_CHECK='Both';
      NO_IO_CHECK='Both';
      NO_ASSERT_CHECK='TRUE';
      NO_DIR_CHECK='TRUE';
      ALLOW_CONNECT='TRUE';
      PINUSE='UNSPEC';
    'CC2':
      PIN_NUMBER='(B5)';
      PIN_TYPE='ANALOG';
      NO_LOAD_CHECK='Both';
      NO_IO_CHECK='Both';
      NO_ASSERT_CHECK='TRUE';
      NO_DIR_CHECK='TRUE';
      ALLOW_CONNECT='TRUE';
      PINUSE='UNSPEC';
    'DP2':
      PIN_NUMBER='(B6)';
      PIN_TYPE='ANALOG';
      NO_LOAD_CHECK='Both';
      NO_IO_CHECK='Both';
      NO_ASSERT_CHECK='TRUE';
      NO_DIR_CHECK='TRUE';
      ALLOW_CONNECT='TRUE';
      PINUSE='UNSPEC';
    'DN2':
      PIN_NUMBER='(B7)';
      PIN_TYPE='ANALOG';
      NO_LOAD_CHECK='Both';
      NO_IO_CHECK='Both';
      NO_ASSERT_CHECK='TRUE';
      NO_DIR_CHECK='TRUE';
      ALLOW_CONNECT='TRUE';
      PINUSE='UNSPEC';
    'SSRXN1':
      PIN_NUMBER='(B10)';
      PIN_TYPE='ANALOG';
      NO_LOAD_CHECK='Both';
      NO_IO_CHECK='Both';
      NO_ASSERT_CHECK='TRUE';
      NO_DIR_CHECK='TRUE';
      ALLOW_CONNECT='TRUE';
      PINUSE='UNSPEC';
    'SSRXP1':
      PIN_NUMBER='(B11)';
      PIN_TYPE='ANALOG';
      NO_LOAD_CHECK='Both';
      NO_IO_CHECK='Both';
      NO_ASSERT_CHECK='TRUE';
      NO_DIR_CHECK='TRUE';
      ALLOW_CONNECT='TRUE';
      PINUSE='UNSPEC';
    'VBUS'<0>:
      PIN_NUMBER='(A4)';
      PINUSE='POWER';
      NO_LOAD_CHECK='Both';
      NO_IO_CHECK='Both';
      NO_ASSERT_CHECK='TRUE';
      NO_DIR_CHECK='TRUE';
      ALLOW_CONNECT='TRUE';
    'VBUS'<1>:
      PIN_NUMBER='(A9)';
      PINUSE='POWER';
      NO_LOAD_CHECK='Both';
      NO_IO_CHECK='Both';
      NO_ASSERT_CHECK='TRUE';
      NO_DIR_CHECK='TRUE';
      ALLOW_CONNECT='TRUE';
    'VBUS'<2>:
      PIN_NUMBER='(B4)';
      PINUSE='POWER';
      NO_LOAD_CHECK='Both';
      NO_IO_CHECK='Both';
      NO_ASSERT_CHECK='TRUE';
      NO_DIR_CHECK='TRUE';
      ALLOW_CONNECT='TRUE';
    'VBUS'<3>:
      PIN_NUMBER='(B9)';
      PINUSE='POWER';
      NO_LOAD_CHECK='Both';
      NO_IO_CHECK='Both';
      NO_ASSERT_CHECK='TRUE';
      NO_DIR_CHECK='TRUE';
      ALLOW_CONNECT='TRUE';
    'SSRXP2':
      PIN_NUMBER='(A11)';
      PIN_TYPE='ANALOG';
      NO_LOAD_CHECK='Both';
      NO_IO_CHECK='Both';
      NO_ASSERT_CHECK='TRUE';
      NO_DIR_CHECK='TRUE';
      ALLOW_CONNECT='TRUE';
      PINUSE='UNSPEC';
    'SSRXN2':
      PIN_NUMBER='(A10)';
      PIN_TYPE='ANALOG';
      NO_LOAD_CHECK='Both';
      NO_IO_CHECK='Both';
      NO_ASSERT_CHECK='TRUE';
      NO_DIR_CHECK='TRUE';
      ALLOW_CONNECT='TRUE';
      PINUSE='UNSPEC';
    'SSTXP2':
      PIN_NUMBER='(B2)';
      PIN_TYPE='ANALOG';
      NO_LOAD_CHECK='Both';
      NO_IO_CHECK='Both';
      NO_ASSERT_CHECK='TRUE';
      NO_DIR_CHECK='TRUE';
      ALLOW_CONNECT='TRUE';
      PINUSE='UNSPEC';
    'SSTXN2':
      PIN_NUMBER='(B3)';
      PIN_TYPE='ANALOG';
      NO_LOAD_CHECK='Both';
      NO_IO_CHECK='Both';
      NO_ASSERT_CHECK='TRUE';
      NO_DIR_CHECK='TRUE';
      ALLOW_CONNECT='TRUE';
      PINUSE='UNSPEC';
    'NP1':
      PIN_NUMBER='(NP1)';
      PIN_TYPE='ANALOG';
      NO_LOAD_CHECK='Both';
      NO_IO_CHECK='Both';
      NO_ASSERT_CHECK='TRUE';
      NO_DIR_CHECK='TRUE';
      ALLOW_CONNECT='TRUE';
      PINUSE='UNSPEC';
    'NP2':
      PIN_NUMBER='(NP2)';
      PIN_TYPE='ANALOG';
      NO_LOAD_CHECK='Both';
      NO_IO_CHECK='Both';
      NO_ASSERT_CHECK='TRUE';
      NO_DIR_CHECK='TRUE';
      ALLOW_CONNECT='TRUE';
      PINUSE='UNSPEC';
    'SBU1':
      PIN_NUMBER='(A8)';
      PIN_TYPE='ANALOG';
      NO_LOAD_CHECK='Both';
      NO_IO_CHECK='Both';
      NO_ASSERT_CHECK='TRUE';
      NO_DIR_CHECK='TRUE';
      ALLOW_CONNECT='TRUE';
      PINUSE='UNSPEC';
    'SBU2':
      PIN_NUMBER='(B8)';
      PIN_TYPE='ANALOG';
      NO_LOAD_CHECK='Both';
      NO_IO_CHECK='Both';
      NO_ASSERT_CHECK='TRUE';
      NO_DIR_CHECK='TRUE';
      ALLOW_CONNECT='TRUE';
      PINUSE='UNSPEC';
    'PTH1':
      PIN_NUMBER='(PTH1)';
      PIN_TYPE='ANALOG';
      NO_LOAD_CHECK='Both';
      NO_IO_CHECK='Both';
      NO_ASSERT_CHECK='TRUE';
      NO_DIR_CHECK='TRUE';
      ALLOW_CONNECT='TRUE';
      PINUSE='UNSPEC';
    'PTH2':
      PIN_NUMBER='(PTH2)';
      PIN_TYPE='ANALOG';
      NO_LOAD_CHECK='Both';
      NO_IO_CHECK='Both';
      NO_ASSERT_CHECK='TRUE';
      NO_DIR_CHECK='TRUE';
      ALLOW_CONNECT='TRUE';
      PINUSE='UNSPEC';
    'PTH3':
      PIN_NUMBER='(PTH3)';
      PIN_TYPE='ANALOG';
      NO_LOAD_CHECK='Both';
      NO_IO_CHECK='Both';
      NO_ASSERT_CHECK='TRUE';
      NO_DIR_CHECK='TRUE';
      ALLOW_CONNECT='TRUE';
      PINUSE='UNSPEC';
    'PTH4':
      PIN_NUMBER='(PTH4)';
      PIN_TYPE='ANALOG';
      NO_LOAD_CHECK='Both';
      NO_IO_CHECK='Both';
      NO_ASSERT_CHECK='TRUE';
      NO_DIR_CHECK='TRUE';
      ALLOW_CONNECT='TRUE';
      PINUSE='UNSPEC';
    'PTH5':
      PIN_NUMBER='(PTH5)';
      PIN_TYPE='ANALOG';
      NO_LOAD_CHECK='Both';
      NO_IO_CHECK='Both';
      NO_ASSERT_CHECK='TRUE';
      NO_DIR_CHECK='TRUE';
      ALLOW_CONNECT='TRUE';
      PINUSE='UNSPEC';
    'PTH6':
      PIN_NUMBER='(PTH6)';
      PIN_TYPE='ANALOG';
      NO_LOAD_CHECK='Both';
      NO_IO_CHECK='Both';
      NO_ASSERT_CHECK='TRUE';
      NO_DIR_CHECK='TRUE';
      ALLOW_CONNECT='TRUE';
      PINUSE='UNSPEC';
    'PTH7':
      PIN_NUMBER='(PTH7)';
      PIN_TYPE='ANALOG';
      NO_LOAD_CHECK='Both';
      NO_IO_CHECK='Both';
      NO_ASSERT_CHECK='TRUE';
      NO_DIR_CHECK='TRUE';
      ALLOW_CONNECT='TRUE';
      PINUSE='UNSPEC';
    'PTH8':
      PIN_NUMBER='(PTH8)';
      PIN_TYPE='ANALOG';
      NO_LOAD_CHECK='Both';
      NO_IO_CHECK='Both';
      NO_ASSERT_CHECK='TRUE';
      NO_DIR_CHECK='TRUE';
      ALLOW_CONNECT='TRUE';
      PINUSE='UNSPEC';
    'GND'<0>:
      PIN_NUMBER='(A1)';
      PINUSE='POWER';
      NO_LOAD_CHECK='Both';
      NO_IO_CHECK='Both';
      NO_ASSERT_CHECK='TRUE';
      NO_DIR_CHECK='TRUE';
      ALLOW_CONNECT='TRUE';
    'GND'<1>:
      PIN_NUMBER='(A12)';
      PINUSE='POWER';
      NO_LOAD_CHECK='Both';
      NO_IO_CHECK='Both';
      NO_ASSERT_CHECK='TRUE';
      NO_DIR_CHECK='TRUE';
      ALLOW_CONNECT='TRUE';
    'GND'<2>:
      PIN_NUMBER='(B1)';
      PINUSE='POWER';
      NO_LOAD_CHECK='Both';
      NO_IO_CHECK='Both';
      NO_ASSERT_CHECK='TRUE';
      NO_DIR_CHECK='TRUE';
      ALLOW_CONNECT='TRUE';
    'GND'<3>:
      PIN_NUMBER='(B12)';
      PINUSE='POWER';
      NO_LOAD_CHECK='Both';
      NO_IO_CHECK='Both';
      NO_ASSERT_CHECK='TRUE';
      NO_DIR_CHECK='TRUE';
      ALLOW_CONNECT='TRUE';
  end_pin;
  body
      PART_NAME='SKT-USB32-8-GP';
      BODY_NAME='SKT-USB32-8-GP';
      PHYS_DES_PREFIX='SKT';
      CLASS='DISCRETE';
      DESCRIPTION='SKT USB 32P UT12113-11601-7H SMD';
      JEDEC_TYPE='SKT-USB32-925895';
      PARENT_PART_TYPE='SKT-USB32-8-GP';
      PARENT_PPT='SKT-USB32-8-GP';
      PARENT_PPT_PART='SKT-USB32-8-GP_SOCKET-G4-SKT-USB32-8-GP,062.10009.0621';
  end_body;
end_primitive;
primitive 'SKX_EXT_B_BGA1-IC,TBD';
  pin
    'BCLK0_DN':
      PIN_NUMBER='(AU24,0,0,0,0,0,0,0,0,0,0,0,0,0,0,0,0,0,0,0,0,0,0,0,0,0,0,0,0,~
0)';
      INPUT_LOAD='(-0.01,0.01)';
      PINUSE='IN';
    'BCLK0_DP':
      PIN_NUMBER='(AW24,0,0,0,0,0,0,0,0,0,0,0,0,0,0,0,0,0,0,0,0,0,0,0,0,0,0,0,0,~
0)';
      INPUT_LOAD='(-0.01,0.01)';
      PINUSE='IN';
    'BCLK1_DN':
      PIN_NUMBER='(CR26,0,0,0,0,0,0,0,0,0,0,0,0,0,0,0,0,0,0,0,0,0,0,0,0,0,0,0,0,~
0)';
      INPUT_LOAD='(-0.01,0.01)';
      PINUSE='IN';
    'BCLK1_DP':
      PIN_NUMBER='(CP27,0,0,0,0,0,0,0,0,0,0,0,0,0,0,0,0,0,0,0,0,0,0,0,0,0,0,0,0,~
0)';
      INPUT_LOAD='(-0.01,0.01)';
      PINUSE='IN';
    'BCLK2_DN':
      PIN_NUMBER='(CT25,0,0,0,0,0,0,0,0,0,0,0,0,0,0,0,0,0,0,0,0,0,0,0,0,0,0,0,0,~
0)';
      INPUT_LOAD='(-0.01,0.01)';
      PINUSE='IN';
    'BCLK2_DP':
      PIN_NUMBER='(CU26,0,0,0,0,0,0,0,0,0,0,0,0,0,0,0,0,0,0,0,0,0,0,0,0,0,0,0,0,~
0)';
      INPUT_LOAD='(-0.01,0.01)';
      PINUSE='IN';
    'BIST_ENABLE':
      PIN_NUMBER='(BA20,0,0,0,0,0,0,0,0,0,0,0,0,0,0,0,0,0,0,0,0,0,0,0,0,0,0,0,0,~
0)';
      INPUT_LOAD='(-0.01,0.01)';
      PINUSE='IN';
    'BMCINIT':
      PIN_NUMBER='(BD23,0,0,0,0,0,0,0,0,0,0,0,0,0,0,0,0,0,0,0,0,0,0,0,0,0,0,0,0,~
0)';
      INPUT_LOAD='(-0.01,0.01)';
      PINUSE='IN';
    'BPM_N'<7>:
      PIN_NUMBER='(AC12,0,0,0,0,0,0,0,0,0,0,0,0,0,0,0,0,0,0,0,0,0,0,0,0,0,0,0,0,~
0)';
      BIDIRECTIONAL='TRUE';
      INPUT_LOAD='(-0.01,0.01)';
      OUTPUT_LOAD='(1.0,-1.0)';
      PINUSE='BI';
    'BPM_N'<6>:
      PIN_NUMBER='(AE12,0,0,0,0,0,0,0,0,0,0,0,0,0,0,0,0,0,0,0,0,0,0,0,0,0,0,0,0,~
0)';
      BIDIRECTIONAL='TRUE';
      INPUT_LOAD='(-0.01,0.01)';
      OUTPUT_LOAD='(1.0,-1.0)';
      PINUSE='BI';
    'BPM_N'<5>:
      PIN_NUMBER='(Y11,0,0,0,0,0,0,0,0,0,0,0,0,0,0,0,0,0,0,0,0,0,0,0,0,0,0,0,0,0~
)';
      BIDIRECTIONAL='TRUE';
      INPUT_LOAD='(-0.01,0.01)';
      OUTPUT_LOAD='(1.0,-1.0)';
      PINUSE='BI';
    'BPM_N'<4>:
      PIN_NUMBER='(AA12,0,0,0,0,0,0,0,0,0,0,0,0,0,0,0,0,0,0,0,0,0,0,0,0,0,0,0,0,~
0)';
      BIDIRECTIONAL='TRUE';
      INPUT_LOAD='(-0.01,0.01)';
      OUTPUT_LOAD='(1.0,-1.0)';
      PINUSE='BI';
    'BPM_N'<3>:
      PIN_NUMBER='(AF11,0,0,0,0,0,0,0,0,0,0,0,0,0,0,0,0,0,0,0,0,0,0,0,0,0,0,0,0,~
0)';
      BIDIRECTIONAL='TRUE';
      INPUT_LOAD='(-0.01,0.01)';
      OUTPUT_LOAD='(1.0,-1.0)';
      PINUSE='BI';
    'BPM_N'<2>:
      PIN_NUMBER='(AG10,0,0,0,0,0,0,0,0,0,0,0,0,0,0,0,0,0,0,0,0,0,0,0,0,0,0,0,0,~
0)';
      BIDIRECTIONAL='TRUE';
      INPUT_LOAD='(-0.01,0.01)';
      OUTPUT_LOAD='(1.0,-1.0)';
      PINUSE='BI';
    'BPM_N'<1>:
      PIN_NUMBER='(AH11,0,0,0,0,0,0,0,0,0,0,0,0,0,0,0,0,0,0,0,0,0,0,0,0,0,0,0,0,~
0)';
      BIDIRECTIONAL='TRUE';
      INPUT_LOAD='(-0.01,0.01)';
      OUTPUT_LOAD='(1.0,-1.0)';
      PINUSE='BI';
    'BPM_N'<0>:
      PIN_NUMBER='(AJ10,0,0,0,0,0,0,0,0,0,0,0,0,0,0,0,0,0,0,0,0,0,0,0,0,0,0,0,0,~
0)';
      BIDIRECTIONAL='TRUE';
      INPUT_LOAD='(-0.01,0.01)';
      OUTPUT_LOAD='(1.0,-1.0)';
      PINUSE='BI';
    'CATERR_N':
      PIN_NUMBER='(AL14,0,0,0,0,0,0,0,0,0,0,0,0,0,0,0,0,0,0,0,0,0,0,0,0,0,0,0,0,~
0)';
      BIDIRECTIONAL='TRUE';
      INPUT_LOAD='(-0.01,0.01)';
      OUTPUT_LOAD='(1.0,-1.0)';
      PINUSE='BI';
    'CD_HFI0_I2CCLK':
      PIN_NUMBER='(0,0,0,0,0,0,0,0,BN22,0,0,0,0,0,0,0,0,0,0,0,0,0,0,0,0,0,0,0,0,~
0)';
      BIDIRECTIONAL='TRUE';
      INPUT_LOAD='(-0.01,0.01)';
      OUTPUT_LOAD='(1.0,-1.0)';
      PINUSE='BI';
    'CD_HFI0_I2CDAT':
      PIN_NUMBER='(0,0,0,0,0,0,0,0,BP23,0,0,0,0,0,0,0,0,0,0,0,0,0,0,0,0,0,0,0,0,~
0)';
      BIDIRECTIONAL='TRUE';
      INPUT_LOAD='(-0.01,0.01)';
      OUTPUT_LOAD='(1.0,-1.0)';
      PINUSE='BI';
    'CD_HFI0_INT_N':
      PIN_NUMBER='(0,0,0,0,0,0,0,0,BP19,0,0,0,0,0,0,0,0,0,0,0,0,0,0,0,0,0,0,0,0,~
0)';
      INPUT_LOAD='(-0.01,0.01)';
      PINUSE='IN';
    'CD_HFI0_LED_N':
      PIN_NUMBER='(0,0,0,0,0,0,0,0,BK21,0,0,0,0,0,0,0,0,0,0,0,0,0,0,0,0,0,0,0,0,~
0)';
      OUTPUT_LOAD='(1.0,-1.0)';
      PINUSE='OUT';
    'CD_HFI0_MODPRST_N':
      PIN_NUMBER='(0,0,0,0,0,0,0,0,BR20,0,0,0,0,0,0,0,0,0,0,0,0,0,0,0,0,0,0,0,0,~
0)';
      INPUT_LOAD='(-0.01,0.01)';
      PINUSE='IN';
    'CD_HFI0_RESET_N':
      PIN_NUMBER='(0,0,0,0,0,0,0,0,BN24,0,0,0,0,0,0,0,0,0,0,0,0,0,0,0,0,0,0,0,0,~
0)';
      OUTPUT_LOAD='(1.0,-1.0)';
      PINUSE='OUT';
    'CD_HFI1_I2CCLK':
      PIN_NUMBER='(0,0,0,0,0,0,0,0,BJ22,0,0,0,0,0,0,0,0,0,0,0,0,0,0,0,0,0,0,0,0,~
0)';
      BIDIRECTIONAL='TRUE';
      INPUT_LOAD='(-0.01,0.01)';
      OUTPUT_LOAD='(1.0,-1.0)';
      PINUSE='BI';
    'CD_HFI1_I2CDAT':
      PIN_NUMBER='(0,0,0,0,0,0,0,0,BH23,0,0,0,0,0,0,0,0,0,0,0,0,0,0,0,0,0,0,0,0,~
0)';
      BIDIRECTIONAL='TRUE';
      INPUT_LOAD='(-0.01,0.01)';
      OUTPUT_LOAD='(1.0,-1.0)';
      PINUSE='BI';
    'CD_HFI1_INT_N':
      PIN_NUMBER='(0,0,0,0,0,0,0,0,BM21,0,0,0,0,0,0,0,0,0,0,0,0,0,0,0,0,0,0,0,0,~
0)';
      INPUT_LOAD='(-0.01,0.01)';
      PINUSE='IN';
    'CD_HFI1_LED_N':
      PIN_NUMBER='(0,0,0,0,0,0,0,0,BM23,0,0,0,0,0,0,0,0,0,0,0,0,0,0,0,0,0,0,0,0,~
0)';
      OUTPUT_LOAD='(1.0,-1.0)';
      PINUSE='OUT';
    'CD_HFI1_MODPRST_N':
      PIN_NUMBER='(0,0,0,0,0,0,0,0,BT19,0,0,0,0,0,0,0,0,0,0,0,0,0,0,0,0,0,0,0,0,~
0)';
      INPUT_LOAD='(-0.01,0.01)';
      PINUSE='IN';
    'CD_HFI1_RESET_N':
      PIN_NUMBER='(0,0,0,0,0,0,0,0,BK23,0,0,0,0,0,0,0,0,0,0,0,0,0,0,0,0,0,0,0,0,~
0)';
      OUTPUT_LOAD='(1.0,-1.0)';
      PINUSE='OUT';
    'CD_HFI_REFCLK_DN':
      PIN_NUMBER='(0,0,0,0,0,0,0,0,BE16,0,0,0,0,0,0,0,0,0,0,0,0,0,0,0,0,0,0,0,0,~
0)';
      INPUT_LOAD='(-0.01,0.01)';
      PINUSE='IN';
    'CD_HFI_REFCLK_DP':
      PIN_NUMBER='(0,0,0,0,0,0,0,0,BG16,0,0,0,0,0,0,0,0,0,0,0,0,0,0,0,0,0,0,0,0,~
0)';
      INPUT_LOAD='(-0.01,0.01)';
      PINUSE='IN';
    'CD_PE_REFCLK_DN':
      PIN_NUMBER='(0,0,0,0,0,0,0,0,BU24,0,0,0,0,0,0,0,0,0,0,0,0,0,0,0,0,0,0,0,0,~
0)';
      INPUT_LOAD='(-0.01,0.01)';
      PINUSE='IN';
    'CD_PE_REFCLK_DP':
      PIN_NUMBER='(0,0,0,0,0,0,0,0,BW24,0,0,0,0,0,0,0,0,0,0,0,0,0,0,0,0,0,0,0,0,~
0)';
      INPUT_LOAD='(-0.01,0.01)';
      PINUSE='IN';
    'CD_POR_N':
      PIN_NUMBER='(0,0,0,0,0,0,0,0,CF25,0,0,0,0,0,0,0,0,0,0,0,0,0,0,0,0,0,0,0,0,~
0)';
      BIDIRECTIONAL='TRUE';
      INPUT_LOAD='(-0.01,0.01)';
      OUTPUT_LOAD='(1.0,-1.0)';
      PINUSE='BI';
    'CD_TCLK':
      PIN_NUMBER='(0,0,0,0,0,0,0,0,CB23,0,0,0,0,0,0,0,0,0,0,0,0,0,0,0,0,0,0,0,0,~
0)';
      INPUT_LOAD='(-0.01,0.01)';
      PINUSE='IN';
    'CD_TDI':
      PIN_NUMBER='(0,0,0,0,0,0,0,0,BY21,0,0,0,0,0,0,0,0,0,0,0,0,0,0,0,0,0,0,0,0,~
0)';
      INPUT_LOAD='(-0.01,0.01)';
      PINUSE='IN';
    'CD_TDO':
      PIN_NUMBER='(0,0,0,0,0,0,0,0,CC22,0,0,0,0,0,0,0,0,0,0,0,0,0,0,0,0,0,0,0,0,~
0)';
      OUTPUT_LOAD='(1.0,-1.0)';
      PINUSE='OUT';
    'CD_TMS':
      PIN_NUMBER='(0,0,0,0,0,0,0,0,CE24,0,0,0,0,0,0,0,0,0,0,0,0,0,0,0,0,0,0,0,0,~
0)';
      INPUT_LOAD='(-0.01,0.01)';
      PINUSE='IN';
    'CD_TRST_N':
      PIN_NUMBER='(0,0,0,0,0,0,0,0,CD23,0,0,0,0,0,0,0,0,0,0,0,0,0,0,0,0,0,0,0,0,~
0)';
      INPUT_LOAD='(-0.01,0.01)';
      PINUSE='IN';
    'CD_VCCIN'<3>:
      PIN_NUMBER='(0,0,0,0,0,0,0,0,0,0,0,0,0,0,0,0,0,0,0,0,BY27,0,0,0,0,0,0,0,0,~
0)';
      PINUSE='POWER';
      NO_LOAD_CHECK='Both';
      NO_IO_CHECK='Both';
      NO_ASSERT_CHECK='TRUE';
      NO_DIR_CHECK='TRUE';
      ALLOW_CONNECT='TRUE';
    'CD_VCCIN'<2>:
      PIN_NUMBER='(0,0,0,0,0,0,0,0,0,0,0,0,0,0,0,0,0,0,0,0,BV27,0,0,0,0,0,0,0,0,~
0)';
      PINUSE='POWER';
      NO_LOAD_CHECK='Both';
      NO_IO_CHECK='Both';
      NO_ASSERT_CHECK='TRUE';
      NO_DIR_CHECK='TRUE';
      ALLOW_CONNECT='TRUE';
    'CD_VCCIN'<1>:
      PIN_NUMBER='(0,0,0,0,0,0,0,0,0,0,0,0,0,0,0,0,0,0,0,0,BU26,0,0,0,0,0,0,0,0,~
0)';
      PINUSE='POWER';
      NO_LOAD_CHECK='Both';
      NO_IO_CHECK='Both';
      NO_ASSERT_CHECK='TRUE';
      NO_DIR_CHECK='TRUE';
      ALLOW_CONNECT='TRUE';
    'CD_VCCIN'<0>:
      PIN_NUMBER='(0,0,0,0,0,0,0,0,0,0,0,0,0,0,0,0,0,0,0,0,BT27,0,0,0,0,0,0,0,0,~
0)';
      PINUSE='POWER';
      NO_LOAD_CHECK='Both';
      NO_IO_CHECK='Both';
      NO_ASSERT_CHECK='TRUE';
      NO_DIR_CHECK='TRUE';
      ALLOW_CONNECT='TRUE';
    'CD_VCCP'<15>:
      PIN_NUMBER='(0,0,0,0,0,0,0,0,0,0,0,0,0,0,0,0,0,0,0,0,BM11,0,0,0,0,0,0,0,0,~
0)';
      PINUSE='POWER';
      NO_LOAD_CHECK='Both';
      NO_IO_CHECK='Both';
      NO_ASSERT_CHECK='TRUE';
      NO_DIR_CHECK='TRUE';
      ALLOW_CONNECT='TRUE';
    'CD_VCCP'<14>:
      PIN_NUMBER='(0,0,0,0,0,0,0,0,0,0,0,0,0,0,0,0,0,0,0,0,BN12,0,0,0,0,0,0,0,0,~
0)';
      PINUSE='POWER';
      NO_LOAD_CHECK='Both';
      NO_IO_CHECK='Both';
      NO_ASSERT_CHECK='TRUE';
      NO_DIR_CHECK='TRUE';
      ALLOW_CONNECT='TRUE';
    'CD_VCCP'<13>:
      PIN_NUMBER='(0,0,0,0,0,0,0,0,0,0,0,0,0,0,0,0,0,0,0,0,BN14,0,0,0,0,0,0,0,0,~
0)';
      PINUSE='POWER';
      NO_LOAD_CHECK='Both';
      NO_IO_CHECK='Both';
      NO_ASSERT_CHECK='TRUE';
      NO_DIR_CHECK='TRUE';
      ALLOW_CONNECT='TRUE';
    'CD_VCCP'<12>:
      PIN_NUMBER='(0,0,0,0,0,0,0,0,0,0,0,0,0,0,0,0,0,0,0,0,BP11,0,0,0,0,0,0,0,0,~
0)';
      PINUSE='POWER';
      NO_LOAD_CHECK='Both';
      NO_IO_CHECK='Both';
      NO_ASSERT_CHECK='TRUE';
      NO_DIR_CHECK='TRUE';
      ALLOW_CONNECT='TRUE';
    'CD_VCCP'<11>:
      PIN_NUMBER='(0,0,0,0,0,0,0,0,0,0,0,0,0,0,0,0,0,0,0,0,BP13,0,0,0,0,0,0,0,0,~
0)';
      PINUSE='POWER';
      NO_LOAD_CHECK='Both';
      NO_IO_CHECK='Both';
      NO_ASSERT_CHECK='TRUE';
      NO_DIR_CHECK='TRUE';
      ALLOW_CONNECT='TRUE';
    'CD_VCCP'<10>:
      PIN_NUMBER='(0,0,0,0,0,0,0,0,0,0,0,0,0,0,0,0,0,0,0,0,BP15,0,0,0,0,0,0,0,0,~
0)';
      PINUSE='POWER';
      NO_LOAD_CHECK='Both';
      NO_IO_CHECK='Both';
      NO_ASSERT_CHECK='TRUE';
      NO_DIR_CHECK='TRUE';
      ALLOW_CONNECT='TRUE';
    'CD_VCCP'<9>:
      PIN_NUMBER='(0,0,0,0,0,0,0,0,0,0,0,0,0,0,0,0,0,0,0,0,BR12,0,0,0,0,0,0,0,0,~
0)';
      PINUSE='POWER';
      NO_LOAD_CHECK='Both';
      NO_IO_CHECK='Both';
      NO_ASSERT_CHECK='TRUE';
      NO_DIR_CHECK='TRUE';
      ALLOW_CONNECT='TRUE';
    'CD_VCCP'<8>:
      PIN_NUMBER='(0,0,0,0,0,0,0,0,0,0,0,0,0,0,0,0,0,0,0,0,BR14,0,0,0,0,0,0,0,0,~
0)';
      PINUSE='POWER';
      NO_LOAD_CHECK='Both';
      NO_IO_CHECK='Both';
      NO_ASSERT_CHECK='TRUE';
      NO_DIR_CHECK='TRUE';
      ALLOW_CONNECT='TRUE';
    'CD_VCCP'<7>:
      PIN_NUMBER='(0,0,0,0,0,0,0,0,0,0,0,0,0,0,0,0,0,0,0,0,BT11,0,0,0,0,0,0,0,0,~
0)';
      PINUSE='POWER';
      NO_LOAD_CHECK='Both';
      NO_IO_CHECK='Both';
      NO_ASSERT_CHECK='TRUE';
      NO_DIR_CHECK='TRUE';
      ALLOW_CONNECT='TRUE';
    'CD_VCCP'<6>:
      PIN_NUMBER='(0,0,0,0,0,0,0,0,0,0,0,0,0,0,0,0,0,0,0,0,BT13,0,0,0,0,0,0,0,0,~
0)';
      PINUSE='POWER';
      NO_LOAD_CHECK='Both';
      NO_IO_CHECK='Both';
      NO_ASSERT_CHECK='TRUE';
      NO_DIR_CHECK='TRUE';
      ALLOW_CONNECT='TRUE';
    'CD_VCCP'<5>:
      PIN_NUMBER='(0,0,0,0,0,0,0,0,0,0,0,0,0,0,0,0,0,0,0,0,BT15,0,0,0,0,0,0,0,0,~
0)';
      PINUSE='POWER';
      NO_LOAD_CHECK='Both';
      NO_IO_CHECK='Both';
      NO_ASSERT_CHECK='TRUE';
      NO_DIR_CHECK='TRUE';
      ALLOW_CONNECT='TRUE';
    'CD_VCCP'<4>:
      PIN_NUMBER='(0,0,0,0,0,0,0,0,0,0,0,0,0,0,0,0,0,0,0,0,BU12,0,0,0,0,0,0,0,0,~
0)';
      PINUSE='POWER';
      NO_LOAD_CHECK='Both';
      NO_IO_CHECK='Both';
      NO_ASSERT_CHECK='TRUE';
      NO_DIR_CHECK='TRUE';
      ALLOW_CONNECT='TRUE';
    'CD_VCCP'<3>:
      PIN_NUMBER='(0,0,0,0,0,0,0,0,0,0,0,0,0,0,0,0,0,0,0,0,BU14,0,0,0,0,0,0,0,0,~
0)';
      PINUSE='POWER';
      NO_LOAD_CHECK='Both';
      NO_IO_CHECK='Both';
      NO_ASSERT_CHECK='TRUE';
      NO_DIR_CHECK='TRUE';
      ALLOW_CONNECT='TRUE';
    'CD_VCCP'<2>:
      PIN_NUMBER='(0,0,0,0,0,0,0,0,0,0,0,0,0,0,0,0,0,0,0,0,BV11,0,0,0,0,0,0,0,0,~
0)';
      PINUSE='POWER';
      NO_LOAD_CHECK='Both';
      NO_IO_CHECK='Both';
      NO_ASSERT_CHECK='TRUE';
      NO_DIR_CHECK='TRUE';
      ALLOW_CONNECT='TRUE';
    'CD_VCCP'<1>:
      PIN_NUMBER='(0,0,0,0,0,0,0,0,0,0,0,0,0,0,0,0,0,0,0,0,BV13,0,0,0,0,0,0,0,0,~
0)';
      PINUSE='POWER';
      NO_LOAD_CHECK='Both';
      NO_IO_CHECK='Both';
      NO_ASSERT_CHECK='TRUE';
      NO_DIR_CHECK='TRUE';
      ALLOW_CONNECT='TRUE';
    'CD_VCCP'<0>:
      PIN_NUMBER='(0,0,0,0,0,0,0,0,0,0,0,0,0,0,0,0,0,0,0,0,BV15,0,0,0,0,0,0,0,0,~
0)';
      PINUSE='POWER';
      NO_LOAD_CHECK='Both';
      NO_IO_CHECK='Both';
      NO_ASSERT_CHECK='TRUE';
      NO_DIR_CHECK='TRUE';
      ALLOW_CONNECT='TRUE';
    'CD_VCCP_SENSE'<1>:
      PIN_NUMBER='(0,0,0,0,0,0,0,0,0,0,0,0,0,0,0,0,0,0,0,0,0,BT17,0,0,0,0,0,0,0,~
0)';
      PINUSE='POWER';
      NO_LOAD_CHECK='Both';
      NO_IO_CHECK='Both';
      NO_ASSERT_CHECK='TRUE';
      NO_DIR_CHECK='TRUE';
      ALLOW_CONNECT='TRUE';
    'CD_VCCP_SENSE'<0>:
      PIN_NUMBER='(0,0,0,0,0,0,0,0,0,0,0,0,0,0,0,0,0,0,0,0,0,BU16,0,0,0,0,0,0,0,~
0)';
      PINUSE='POWER';
      NO_LOAD_CHECK='Both';
      NO_IO_CHECK='Both';
      NO_ASSERT_CHECK='TRUE';
      NO_DIR_CHECK='TRUE';
      ALLOW_CONNECT='TRUE';
    'CD_VCC_CORE'<12>:
      PIN_NUMBER='(0,0,0,0,0,0,0,0,0,0,0,0,0,0,0,0,0,0,0,0,BD13,0,0,0,0,0,0,0,0,~
0)';
      PINUSE='POWER';
      NO_LOAD_CHECK='Both';
      NO_IO_CHECK='Both';
      NO_ASSERT_CHECK='TRUE';
      NO_DIR_CHECK='TRUE';
      ALLOW_CONNECT='TRUE';
    'CD_VCC_CORE'<11>:
      PIN_NUMBER='(0,0,0,0,0,0,0,0,0,0,0,0,0,0,0,0,0,0,0,0,BE12,0,0,0,0,0,0,0,0,~
0)';
      PINUSE='POWER';
      NO_LOAD_CHECK='Both';
      NO_IO_CHECK='Both';
      NO_ASSERT_CHECK='TRUE';
      NO_DIR_CHECK='TRUE';
      ALLOW_CONNECT='TRUE';
    'CD_VCC_CORE'<10>:
      PIN_NUMBER='(0,0,0,0,0,0,0,0,0,0,0,0,0,0,0,0,0,0,0,0,BE14,0,0,0,0,0,0,0,0,~
0)';
      PINUSE='POWER';
      NO_LOAD_CHECK='Both';
      NO_IO_CHECK='Both';
      NO_ASSERT_CHECK='TRUE';
      NO_DIR_CHECK='TRUE';
      ALLOW_CONNECT='TRUE';
    'CD_VCC_CORE'<9>:
      PIN_NUMBER='(0,0,0,0,0,0,0,0,0,0,0,0,0,0,0,0,0,0,0,0,BF11,0,0,0,0,0,0,0,0,~
0)';
      PINUSE='POWER';
      NO_LOAD_CHECK='Both';
      NO_IO_CHECK='Both';
      NO_ASSERT_CHECK='TRUE';
      NO_DIR_CHECK='TRUE';
      ALLOW_CONNECT='TRUE';
    'CD_VCC_CORE'<8>:
      PIN_NUMBER='(0,0,0,0,0,0,0,0,0,0,0,0,0,0,0,0,0,0,0,0,BF13,0,0,0,0,0,0,0,0,~
0)';
      PINUSE='POWER';
      NO_LOAD_CHECK='Both';
      NO_IO_CHECK='Both';
      NO_ASSERT_CHECK='TRUE';
      NO_DIR_CHECK='TRUE';
      ALLOW_CONNECT='TRUE';
    'CD_VCC_CORE'<7>:
      PIN_NUMBER='(0,0,0,0,0,0,0,0,0,0,0,0,0,0,0,0,0,0,0,0,BG12,0,0,0,0,0,0,0,0,~
0)';
      PINUSE='POWER';
      NO_LOAD_CHECK='Both';
      NO_IO_CHECK='Both';
      NO_ASSERT_CHECK='TRUE';
      NO_DIR_CHECK='TRUE';
      ALLOW_CONNECT='TRUE';
    'CD_VCC_CORE'<6>:
      PIN_NUMBER='(0,0,0,0,0,0,0,0,0,0,0,0,0,0,0,0,0,0,0,0,BG14,0,0,0,0,0,0,0,0,~
0)';
      PINUSE='POWER';
      NO_LOAD_CHECK='Both';
      NO_IO_CHECK='Both';
      NO_ASSERT_CHECK='TRUE';
      NO_DIR_CHECK='TRUE';
      ALLOW_CONNECT='TRUE';
    'CD_VCC_CORE'<5>:
      PIN_NUMBER='(0,0,0,0,0,0,0,0,0,0,0,0,0,0,0,0,0,0,0,0,BH13,0,0,0,0,0,0,0,0,~
0)';
      PINUSE='POWER';
      NO_LOAD_CHECK='Both';
      NO_IO_CHECK='Both';
      NO_ASSERT_CHECK='TRUE';
      NO_DIR_CHECK='TRUE';
      ALLOW_CONNECT='TRUE';
    'CD_VCC_CORE'<4>:
      PIN_NUMBER='(0,0,0,0,0,0,0,0,0,0,0,0,0,0,0,0,0,0,0,0,BJ12,0,0,0,0,0,0,0,0,~
0)';
      PINUSE='POWER';
      NO_LOAD_CHECK='Both';
      NO_IO_CHECK='Both';
      NO_ASSERT_CHECK='TRUE';
      NO_DIR_CHECK='TRUE';
      ALLOW_CONNECT='TRUE';
    'CD_VCC_CORE'<3>:
      PIN_NUMBER='(0,0,0,0,0,0,0,0,0,0,0,0,0,0,0,0,0,0,0,0,BJ14,0,0,0,0,0,0,0,0,~
0)';
      PINUSE='POWER';
      NO_LOAD_CHECK='Both';
      NO_IO_CHECK='Both';
      NO_ASSERT_CHECK='TRUE';
      NO_DIR_CHECK='TRUE';
      ALLOW_CONNECT='TRUE';
    'CD_VCC_CORE'<2>:
      PIN_NUMBER='(0,0,0,0,0,0,0,0,0,0,0,0,0,0,0,0,0,0,0,0,BK13,0,0,0,0,0,0,0,0,~
0)';
      PINUSE='POWER';
      NO_LOAD_CHECK='Both';
      NO_IO_CHECK='Both';
      NO_ASSERT_CHECK='TRUE';
      NO_DIR_CHECK='TRUE';
      ALLOW_CONNECT='TRUE';
    'CD_VCC_CORE'<1>:
      PIN_NUMBER='(0,0,0,0,0,0,0,0,0,0,0,0,0,0,0,0,0,0,0,0,BK15,0,0,0,0,0,0,0,0,~
0)';
      PINUSE='POWER';
      NO_LOAD_CHECK='Both';
      NO_IO_CHECK='Both';
      NO_ASSERT_CHECK='TRUE';
      NO_DIR_CHECK='TRUE';
      ALLOW_CONNECT='TRUE';
    'CD_VCC_CORE'<0>:
      PIN_NUMBER='(0,0,0,0,0,0,0,0,0,0,0,0,0,0,0,0,0,0,0,0,BL14,0,0,0,0,0,0,0,0,~
0)';
      PINUSE='POWER';
      NO_LOAD_CHECK='Both';
      NO_IO_CHECK='Both';
      NO_ASSERT_CHECK='TRUE';
      NO_DIR_CHECK='TRUE';
      ALLOW_CONNECT='TRUE';
    'CD_VCC_CORE_SENSE':
      PIN_NUMBER='(0,0,0,0,0,0,0,0,0,0,0,0,0,0,0,0,0,0,0,0,0,BN16,0,0,0,0,0,0,0,~
0)';
      PINUSE='POWER';
      NO_LOAD_CHECK='Both';
      NO_IO_CHECK='Both';
      NO_ASSERT_CHECK='TRUE';
      NO_DIR_CHECK='TRUE';
      ALLOW_CONNECT='TRUE';
    'CD_VPP'<3>:
      PIN_NUMBER='(0,0,0,0,0,0,0,0,0,0,0,0,0,0,0,0,0,0,0,0,A8,0,0,0,0,0,0,0,0,0)~
';
      PINUSE='POWER';
      NO_LOAD_CHECK='Both';
      NO_IO_CHECK='Both';
      NO_ASSERT_CHECK='TRUE';
      NO_DIR_CHECK='TRUE';
      ALLOW_CONNECT='TRUE';
    'CD_VPP'<2>:
      PIN_NUMBER='(0,0,0,0,0,0,0,0,0,0,0,0,0,0,0,0,0,0,0,0,A10,0,0,0,0,0,0,0,0,0~
)';
      PINUSE='POWER';
      NO_LOAD_CHECK='Both';
      NO_IO_CHECK='Both';
      NO_ASSERT_CHECK='TRUE';
      NO_DIR_CHECK='TRUE';
      ALLOW_CONNECT='TRUE';
    'CD_VPP'<1>:
      PIN_NUMBER='(0,0,0,0,0,0,0,0,0,0,0,0,0,0,0,0,0,0,0,0,A12,0,0,0,0,0,0,0,0,0~
)';
      PINUSE='POWER';
      NO_LOAD_CHECK='Both';
      NO_IO_CHECK='Both';
      NO_ASSERT_CHECK='TRUE';
      NO_DIR_CHECK='TRUE';
      ALLOW_CONNECT='TRUE';
    'CD_VPP'<0>:
      PIN_NUMBER='(0,0,0,0,0,0,0,0,0,0,0,0,0,0,0,0,0,0,0,0,B11,0,0,0,0,0,0,0,0,0~
)';
      PINUSE='POWER';
      NO_LOAD_CHECK='Both';
      NO_IO_CHECK='Both';
      NO_ASSERT_CHECK='TRUE';
      NO_DIR_CHECK='TRUE';
      ALLOW_CONNECT='TRUE';
    'CD_VSS_VCC_CORE_SENSE':
      PIN_NUMBER='(0,0,0,0,0,0,0,0,0,0,0,0,0,0,0,0,0,0,0,0,0,BL16,0,0,0,0,0,0,0,~
0)';
      PINUSE='POWER';
      NO_LOAD_CHECK='Both';
      NO_IO_CHECK='Both';
      NO_ASSERT_CHECK='TRUE';
      NO_DIR_CHECK='TRUE';
      ALLOW_CONNECT='TRUE';
    'DDR012_DRAM_PWR_OK':
      PIN_NUMBER='(AN30,0,0,0,0,0,0,0,0,0,0,0,0,0,0,0,0,0,0,0,0,0,0,0,0,0,0,0,0,~
0)';
      INPUT_LOAD='(-0.01,0.01)';
      PINUSE='IN';
    'DDR012_RCOMP'<2>:
      PIN_NUMBER='(AC42,0,0,0,0,0,0,0,0,0,0,0,0,0,0,0,0,0,0,0,0,0,0,0,0,0,0,0,0,~
0)';
      BIDIRECTIONAL='TRUE';
      INPUT_LOAD='(-0.01,0.01)';
      OUTPUT_LOAD='(1.0,-1.0)';
      PINUSE='BI';
    'DDR012_RCOMP'<1>:
      PIN_NUMBER='(AB43,0,0,0,0,0,0,0,0,0,0,0,0,0,0,0,0,0,0,0,0,0,0,0,0,0,0,0,0,~
0)';
      BIDIRECTIONAL='TRUE';
      INPUT_LOAD='(-0.01,0.01)';
      OUTPUT_LOAD='(1.0,-1.0)';
      PINUSE='BI';
    'DDR012_RCOMP'<0>:
      PIN_NUMBER='(Y43,0,0,0,0,0,0,0,0,0,0,0,0,0,0,0,0,0,0,0,0,0,0,0,0,0,0,0,0,0~
)';
      BIDIRECTIONAL='TRUE';
      INPUT_LOAD='(-0.01,0.01)';
      OUTPUT_LOAD='(1.0,-1.0)';
      PINUSE='BI';
    'DDR012_RESET_N':
      PIN_NUMBER='(U64,0,0,0,0,0,0,0,0,0,0,0,0,0,0,0,0,0,0,0,0,0,0,0,0,0,0,0,0,0~
)';
      OUTPUT_LOAD='(1.0,-1.0)';
      PINUSE='OUT';
    'DDR012_SPDSCL':
      PIN_NUMBER='(AJ18,0,0,0,0,0,0,0,0,0,0,0,0,0,0,0,0,0,0,0,0,0,0,0,0,0,0,0,0,~
0)';
      BIDIRECTIONAL='TRUE';
      INPUT_LOAD='(-0.01,0.01)';
      OUTPUT_LOAD='(1.0,-1.0)';
      PINUSE='BI';
    'DDR012_SPDSDA':
      PIN_NUMBER='(AF17,0,0,0,0,0,0,0,0,0,0,0,0,0,0,0,0,0,0,0,0,0,0,0,0,0,0,0,0,~
0)';
      BIDIRECTIONAL='TRUE';
      INPUT_LOAD='(-0.01,0.01)';
      OUTPUT_LOAD='(1.0,-1.0)';
      PINUSE='BI';
    'DDR0_ACT_N':
      PIN_NUMBER='(0,0,J60,0,0,0,0,0,0,0,0,0,0,0,0,0,0,0,0,0,0,0,0,0,0,0,0,0,0,0~
)';
      OUTPUT_LOAD='(1.0,-1.0)';
      PINUSE='OUT';
    'DDR0_ALERT_N':
      PIN_NUMBER='(0,0,B61,0,0,0,0,0,0,0,0,0,0,0,0,0,0,0,0,0,0,0,0,0,0,0,0,0,0,0~
)';
      INPUT_LOAD='(-0.01,0.01)';
      PINUSE='IN';
    'DDR0_BA'<1>:
      PIN_NUMBER='(0,0,G54,0,0,0,0,0,0,0,0,0,0,0,0,0,0,0,0,0,0,0,0,0,0,0,0,0,0,0~
)';
      OUTPUT_LOAD='(1.0,-1.0)';
      PINUSE='OUT';
    'DDR0_BA'<0>:
      PIN_NUMBER='(0,0,C52,0,0,0,0,0,0,0,0,0,0,0,0,0,0,0,0,0,0,0,0,0,0,0,0,0,0,0~
)';
      OUTPUT_LOAD='(1.0,-1.0)';
      PINUSE='OUT';
    'DDR0_BG'<1>:
      PIN_NUMBER='(0,0,F63,0,0,0,0,0,0,0,0,0,0,0,0,0,0,0,0,0,0,0,0,0,0,0,0,0,0,0~
)';
      OUTPUT_LOAD='(1.0,-1.0)';
      PINUSE='OUT';
    'DDR0_BG'<0>:
      PIN_NUMBER='(0,0,D61,0,0,0,0,0,0,0,0,0,0,0,0,0,0,0,0,0,0,0,0,0,0,0,0,0,0,0~
)';
      OUTPUT_LOAD='(1.0,-1.0)';
      PINUSE='OUT';
    'DDR0_CAVREF':
      PIN_NUMBER='(AJ64,0,0,0,0,0,0,0,0,0,0,0,0,0,0,0,0,0,0,0,0,0,0,0,0,0,0,0,0,~
0)';
      OUTPUT_LOAD='(1.0,-1.0)';
      PINUSE='OUT';
    'DDR0_CID'<2>:
      PIN_NUMBER='(0,0,G46,0,0,0,0,0,0,0,0,0,0,0,0,0,0,0,0,0,0,0,0,0,0,0,0,0,0,0~
)';
      OUTPUT_LOAD='(1.0,-1.0)';
      PINUSE='OUT';
    'DDR0_CKE'<3>:
      PIN_NUMBER='(0,0,D63,0,0,0,0,0,0,0,0,0,0,0,0,0,0,0,0,0,0,0,0,0,0,0,0,0,0,0~
)';
      OUTPUT_LOAD='(1.0,-1.0)';
      PINUSE='OUT';
    'DDR0_CKE'<2>:
      PIN_NUMBER='(0,0,B63,0,0,0,0,0,0,0,0,0,0,0,0,0,0,0,0,0,0,0,0,0,0,0,0,0,0,0~
)';
      OUTPUT_LOAD='(1.0,-1.0)';
      PINUSE='OUT';
    'DDR0_CKE'<1>:
      PIN_NUMBER='(0,0,C64,0,0,0,0,0,0,0,0,0,0,0,0,0,0,0,0,0,0,0,0,0,0,0,0,0,0,0~
)';
      OUTPUT_LOAD='(1.0,-1.0)';
      PINUSE='OUT';
    'DDR0_CKE'<0>:
      PIN_NUMBER='(0,0,C62,0,0,0,0,0,0,0,0,0,0,0,0,0,0,0,0,0,0,0,0,0,0,0,0,0,0,0~
)';
      OUTPUT_LOAD='(1.0,-1.0)';
      PINUSE='OUT';
    'DDR0_CLK_DN'<3>:
      PIN_NUMBER='(0,0,C56,0,0,0,0,0,0,0,0,0,0,0,0,0,0,0,0,0,0,0,0,0,0,0,0,0,0,0~
)';
      OUTPUT_LOAD='(1.0,-1.0)';
      PINUSE='OUT';
    'DDR0_CLK_DN'<2>:
      PIN_NUMBER='(0,0,J56,0,0,0,0,0,0,0,0,0,0,0,0,0,0,0,0,0,0,0,0,0,0,0,0,0,0,0~
)';
      OUTPUT_LOAD='(1.0,-1.0)';
      PINUSE='OUT';
    'DDR0_CLK_DN'<1>:
      PIN_NUMBER='(0,0,C54,0,0,0,0,0,0,0,0,0,0,0,0,0,0,0,0,0,0,0,0,0,0,0,0,0,0,0~
)';
      OUTPUT_LOAD='(1.0,-1.0)';
      PINUSE='OUT';
    'DDR0_CLK_DN'<0>:
      PIN_NUMBER='(0,0,F55,0,0,0,0,0,0,0,0,0,0,0,0,0,0,0,0,0,0,0,0,0,0,0,0,0,0,0~
)';
      OUTPUT_LOAD='(1.0,-1.0)';
      PINUSE='OUT';
    'DDR0_CLK_DP'<3>:
      PIN_NUMBER='(0,0,B57,0,0,0,0,0,0,0,0,0,0,0,0,0,0,0,0,0,0,0,0,0,0,0,0,0,0,0~
)';
      OUTPUT_LOAD='(1.0,-1.0)';
      PINUSE='OUT';
    'DDR0_CLK_DP'<2>:
      PIN_NUMBER='(0,0,G56,0,0,0,0,0,0,0,0,0,0,0,0,0,0,0,0,0,0,0,0,0,0,0,0,0,0,0~
)';
      OUTPUT_LOAD='(1.0,-1.0)';
      PINUSE='OUT';
    'DDR0_CLK_DP'<1>:
      PIN_NUMBER='(0,0,B55,0,0,0,0,0,0,0,0,0,0,0,0,0,0,0,0,0,0,0,0,0,0,0,0,0,0,0~
)';
      OUTPUT_LOAD='(1.0,-1.0)';
      PINUSE='OUT';
    'DDR0_CLK_DP'<0>:
      PIN_NUMBER='(0,0,D55,0,0,0,0,0,0,0,0,0,0,0,0,0,0,0,0,0,0,0,0,0,0,0,0,0,0,0~
)';
      OUTPUT_LOAD='(1.0,-1.0)';
      PINUSE='OUT';
    'DDR0_CS_N'<7>:
      PIN_NUMBER='(0,0,K45,0,0,0,0,0,0,0,0,0,0,0,0,0,0,0,0,0,0,0,0,0,0,0,0,0,0,0~
)';
      OUTPUT_LOAD='(1.0,-1.0)';
      PINUSE='OUT';
    'DDR0_CS_N'<6>:
      PIN_NUMBER='(0,0,F45,0,0,0,0,0,0,0,0,0,0,0,0,0,0,0,0,0,0,0,0,0,0,0,0,0,0,0~
)';
      OUTPUT_LOAD='(1.0,-1.0)';
      PINUSE='OUT';
    'DDR0_CS_N'<5>:
      PIN_NUMBER='(0,0,D49,0,0,0,0,0,0,0,0,0,0,0,0,0,0,0,0,0,0,0,0,0,0,0,0,0,0,0~
)';
      OUTPUT_LOAD='(1.0,-1.0)';
      PINUSE='OUT';
    'DDR0_CS_N'<4>:
      PIN_NUMBER='(0,0,B51,0,0,0,0,0,0,0,0,0,0,0,0,0,0,0,0,0,0,0,0,0,0,0,0,0,0,0~
)';
      OUTPUT_LOAD='(1.0,-1.0)';
      PINUSE='OUT';
    'DDR0_CS_N'<3>:
      PIN_NUMBER='(0,0,F47,0,0,0,0,0,0,0,0,0,0,0,0,0,0,0,0,0,0,0,0,0,0,0,0,0,0,0~
)';
      OUTPUT_LOAD='(1.0,-1.0)';
      PINUSE='OUT';
    'DDR0_CS_N'<2>:
      PIN_NUMBER='(0,0,D47,0,0,0,0,0,0,0,0,0,0,0,0,0,0,0,0,0,0,0,0,0,0,0,0,0,0,0~
)';
      OUTPUT_LOAD='(1.0,-1.0)';
      PINUSE='OUT';
    'DDR0_CS_N'<1>:
      PIN_NUMBER='(0,0,F49,0,0,0,0,0,0,0,0,0,0,0,0,0,0,0,0,0,0,0,0,0,0,0,0,0,0,0~
)';
      OUTPUT_LOAD='(1.0,-1.0)';
      PINUSE='OUT';
    'DDR0_CS_N'<0>:
      PIN_NUMBER='(0,0,G52,0,0,0,0,0,0,0,0,0,0,0,0,0,0,0,0,0,0,0,0,0,0,0,0,0,0,0~
)';
      OUTPUT_LOAD='(1.0,-1.0)';
      PINUSE='OUT';
    'DDR0_DQ'<63>:
      PIN_NUMBER='(0,0,K23,0,0,0,0,0,0,0,0,0,0,0,0,0,0,0,0,0,0,0,0,0,0,0,0,0,0,0~
)';
      BIDIRECTIONAL='TRUE';
      INPUT_LOAD='(-0.01,0.01)';
      OUTPUT_LOAD='(1.0,-1.0)';
      PINUSE='BI';
    'DDR0_DQ'<62>:
      PIN_NUMBER='(0,0,H23,0,0,0,0,0,0,0,0,0,0,0,0,0,0,0,0,0,0,0,0,0,0,0,0,0,0,0~
)';
      BIDIRECTIONAL='TRUE';
      INPUT_LOAD='(-0.01,0.01)';
      OUTPUT_LOAD='(1.0,-1.0)';
      PINUSE='BI';
    'DDR0_DQ'<61>:
      PIN_NUMBER='(0,0,N26,0,0,0,0,0,0,0,0,0,0,0,0,0,0,0,0,0,0,0,0,0,0,0,0,0,0,0~
)';
      BIDIRECTIONAL='TRUE';
      INPUT_LOAD='(-0.01,0.01)';
      OUTPUT_LOAD='(1.0,-1.0)';
      PINUSE='BI';
    'DDR0_DQ'<60>:
      PIN_NUMBER='(0,0,L26,0,0,0,0,0,0,0,0,0,0,0,0,0,0,0,0,0,0,0,0,0,0,0,0,0,0,0~
)';
      BIDIRECTIONAL='TRUE';
      INPUT_LOAD='(-0.01,0.01)';
      OUTPUT_LOAD='(1.0,-1.0)';
      PINUSE='BI';
    'DDR0_DQ'<59>:
      PIN_NUMBER='(0,0,T23,0,0,0,0,0,0,0,0,0,0,0,0,0,0,0,0,0,0,0,0,0,0,0,0,0,0,0~
)';
      BIDIRECTIONAL='TRUE';
      INPUT_LOAD='(-0.01,0.01)';
      OUTPUT_LOAD='(1.0,-1.0)';
      PINUSE='BI';
    'DDR0_DQ'<58>:
      PIN_NUMBER='(0,0,P23,0,0,0,0,0,0,0,0,0,0,0,0,0,0,0,0,0,0,0,0,0,0,0,0,0,0,0~
)';
      BIDIRECTIONAL='TRUE';
      INPUT_LOAD='(-0.01,0.01)';
      OUTPUT_LOAD='(1.0,-1.0)';
      PINUSE='BI';
    'DDR0_DQ'<57>:
      PIN_NUMBER='(0,0,P25,0,0,0,0,0,0,0,0,0,0,0,0,0,0,0,0,0,0,0,0,0,0,0,0,0,0,0~
)';
      BIDIRECTIONAL='TRUE';
      INPUT_LOAD='(-0.01,0.01)';
      OUTPUT_LOAD='(1.0,-1.0)';
      PINUSE='BI';
    'DDR0_DQ'<56>:
      PIN_NUMBER='(0,0,K25,0,0,0,0,0,0,0,0,0,0,0,0,0,0,0,0,0,0,0,0,0,0,0,0,0,0,0~
)';
      BIDIRECTIONAL='TRUE';
      INPUT_LOAD='(-0.01,0.01)';
      OUTPUT_LOAD='(1.0,-1.0)';
      PINUSE='BI';
    'DDR0_DQ'<55>:
      PIN_NUMBER='(0,0,P29,0,0,0,0,0,0,0,0,0,0,0,0,0,0,0,0,0,0,0,0,0,0,0,0,0,0,0~
)';
      BIDIRECTIONAL='TRUE';
      INPUT_LOAD='(-0.01,0.01)';
      OUTPUT_LOAD='(1.0,-1.0)';
      PINUSE='BI';
    'DDR0_DQ'<54>:
      PIN_NUMBER='(0,0,K29,0,0,0,0,0,0,0,0,0,0,0,0,0,0,0,0,0,0,0,0,0,0,0,0,0,0,0~
)';
      BIDIRECTIONAL='TRUE';
      INPUT_LOAD='(-0.01,0.01)';
      OUTPUT_LOAD='(1.0,-1.0)';
      PINUSE='BI';
    'DDR0_DQ'<53>:
      PIN_NUMBER='(0,0,N32,0,0,0,0,0,0,0,0,0,0,0,0,0,0,0,0,0,0,0,0,0,0,0,0,0,0,0~
)';
      BIDIRECTIONAL='TRUE';
      INPUT_LOAD='(-0.01,0.01)';
      OUTPUT_LOAD='(1.0,-1.0)';
      PINUSE='BI';
    'DDR0_DQ'<52>:
      PIN_NUMBER='(0,0,L32,0,0,0,0,0,0,0,0,0,0,0,0,0,0,0,0,0,0,0,0,0,0,0,0,0,0,0~
)';
      BIDIRECTIONAL='TRUE';
      INPUT_LOAD='(-0.01,0.01)';
      OUTPUT_LOAD='(1.0,-1.0)';
      PINUSE='BI';
    'DDR0_DQ'<51>:
      PIN_NUMBER='(0,0,N28,0,0,0,0,0,0,0,0,0,0,0,0,0,0,0,0,0,0,0,0,0,0,0,0,0,0,0~
)';
      BIDIRECTIONAL='TRUE';
      INPUT_LOAD='(-0.01,0.01)';
      OUTPUT_LOAD='(1.0,-1.0)';
      PINUSE='BI';
    'DDR0_DQ'<50>:
      PIN_NUMBER='(0,0,L28,0,0,0,0,0,0,0,0,0,0,0,0,0,0,0,0,0,0,0,0,0,0,0,0,0,0,0~
)';
      BIDIRECTIONAL='TRUE';
      INPUT_LOAD='(-0.01,0.01)';
      OUTPUT_LOAD='(1.0,-1.0)';
      PINUSE='BI';
    'DDR0_DQ'<49>:
      PIN_NUMBER='(0,0,P31,0,0,0,0,0,0,0,0,0,0,0,0,0,0,0,0,0,0,0,0,0,0,0,0,0,0,0~
)';
      BIDIRECTIONAL='TRUE';
      INPUT_LOAD='(-0.01,0.01)';
      OUTPUT_LOAD='(1.0,-1.0)';
      PINUSE='BI';
    'DDR0_DQ'<48>:
      PIN_NUMBER='(0,0,K31,0,0,0,0,0,0,0,0,0,0,0,0,0,0,0,0,0,0,0,0,0,0,0,0,0,0,0~
)';
      BIDIRECTIONAL='TRUE';
      INPUT_LOAD='(-0.01,0.01)';
      OUTPUT_LOAD='(1.0,-1.0)';
      PINUSE='BI';
    'DDR0_DQ'<47>:
      PIN_NUMBER='(0,0,P35,0,0,0,0,0,0,0,0,0,0,0,0,0,0,0,0,0,0,0,0,0,0,0,0,0,0,0~
)';
      BIDIRECTIONAL='TRUE';
      INPUT_LOAD='(-0.01,0.01)';
      OUTPUT_LOAD='(1.0,-1.0)';
      PINUSE='BI';
    'DDR0_DQ'<46>:
      PIN_NUMBER='(0,0,K35,0,0,0,0,0,0,0,0,0,0,0,0,0,0,0,0,0,0,0,0,0,0,0,0,0,0,0~
)';
      BIDIRECTIONAL='TRUE';
      INPUT_LOAD='(-0.01,0.01)';
      OUTPUT_LOAD='(1.0,-1.0)';
      PINUSE='BI';
    'DDR0_DQ'<45>:
      PIN_NUMBER='(0,0,N38,0,0,0,0,0,0,0,0,0,0,0,0,0,0,0,0,0,0,0,0,0,0,0,0,0,0,0~
)';
      BIDIRECTIONAL='TRUE';
      INPUT_LOAD='(-0.01,0.01)';
      OUTPUT_LOAD='(1.0,-1.0)';
      PINUSE='BI';
    'DDR0_DQ'<44>:
      PIN_NUMBER='(0,0,L38,0,0,0,0,0,0,0,0,0,0,0,0,0,0,0,0,0,0,0,0,0,0,0,0,0,0,0~
)';
      BIDIRECTIONAL='TRUE';
      INPUT_LOAD='(-0.01,0.01)';
      OUTPUT_LOAD='(1.0,-1.0)';
      PINUSE='BI';
    'DDR0_DQ'<43>:
      PIN_NUMBER='(0,0,N34,0,0,0,0,0,0,0,0,0,0,0,0,0,0,0,0,0,0,0,0,0,0,0,0,0,0,0~
)';
      BIDIRECTIONAL='TRUE';
      INPUT_LOAD='(-0.01,0.01)';
      OUTPUT_LOAD='(1.0,-1.0)';
      PINUSE='BI';
    'DDR0_DQ'<42>:
      PIN_NUMBER='(0,0,L34,0,0,0,0,0,0,0,0,0,0,0,0,0,0,0,0,0,0,0,0,0,0,0,0,0,0,0~
)';
      BIDIRECTIONAL='TRUE';
      INPUT_LOAD='(-0.01,0.01)';
      OUTPUT_LOAD='(1.0,-1.0)';
      PINUSE='BI';
    'DDR0_DQ'<41>:
      PIN_NUMBER='(0,0,P37,0,0,0,0,0,0,0,0,0,0,0,0,0,0,0,0,0,0,0,0,0,0,0,0,0,0,0~
)';
      BIDIRECTIONAL='TRUE';
      INPUT_LOAD='(-0.01,0.01)';
      OUTPUT_LOAD='(1.0,-1.0)';
      PINUSE='BI';
    'DDR0_DQ'<40>:
      PIN_NUMBER='(0,0,K37,0,0,0,0,0,0,0,0,0,0,0,0,0,0,0,0,0,0,0,0,0,0,0,0,0,0,0~
)';
      BIDIRECTIONAL='TRUE';
      INPUT_LOAD='(-0.01,0.01)';
      OUTPUT_LOAD='(1.0,-1.0)';
      PINUSE='BI';
    'DDR0_DQ'<39>:
      PIN_NUMBER='(0,0,F39,0,0,0,0,0,0,0,0,0,0,0,0,0,0,0,0,0,0,0,0,0,0,0,0,0,0,0~
)';
      BIDIRECTIONAL='TRUE';
      INPUT_LOAD='(-0.01,0.01)';
      OUTPUT_LOAD='(1.0,-1.0)';
      PINUSE='BI';
    'DDR0_DQ'<38>:
      PIN_NUMBER='(0,0,B39,0,0,0,0,0,0,0,0,0,0,0,0,0,0,0,0,0,0,0,0,0,0,0,0,0,0,0~
)';
      BIDIRECTIONAL='TRUE';
      INPUT_LOAD='(-0.01,0.01)';
      OUTPUT_LOAD='(1.0,-1.0)';
      PINUSE='BI';
    'DDR0_DQ'<37>:
      PIN_NUMBER='(0,0,F41,0,0,0,0,0,0,0,0,0,0,0,0,0,0,0,0,0,0,0,0,0,0,0,0,0,0,0~
)';
      BIDIRECTIONAL='TRUE';
      INPUT_LOAD='(-0.01,0.01)';
      OUTPUT_LOAD='(1.0,-1.0)';
      PINUSE='BI';
    'DDR0_DQ'<36>:
      PIN_NUMBER='(0,0,E42,0,0,0,0,0,0,0,0,0,0,0,0,0,0,0,0,0,0,0,0,0,0,0,0,0,0,0~
)';
      BIDIRECTIONAL='TRUE';
      INPUT_LOAD='(-0.01,0.01)';
      OUTPUT_LOAD='(1.0,-1.0)';
      PINUSE='BI';
    'DDR0_DQ'<35>:
      PIN_NUMBER='(0,0,E38,0,0,0,0,0,0,0,0,0,0,0,0,0,0,0,0,0,0,0,0,0,0,0,0,0,0,0~
)';
      BIDIRECTIONAL='TRUE';
      INPUT_LOAD='(-0.01,0.01)';
      OUTPUT_LOAD='(1.0,-1.0)';
      PINUSE='BI';
    'DDR0_DQ'<34>:
      PIN_NUMBER='(0,0,C38,0,0,0,0,0,0,0,0,0,0,0,0,0,0,0,0,0,0,0,0,0,0,0,0,0,0,0~
)';
      BIDIRECTIONAL='TRUE';
      INPUT_LOAD='(-0.01,0.01)';
      OUTPUT_LOAD='(1.0,-1.0)';
      PINUSE='BI';
    'DDR0_DQ'<33>:
      PIN_NUMBER='(0,0,B41,0,0,0,0,0,0,0,0,0,0,0,0,0,0,0,0,0,0,0,0,0,0,0,0,0,0,0~
)';
      BIDIRECTIONAL='TRUE';
      INPUT_LOAD='(-0.01,0.01)';
      OUTPUT_LOAD='(1.0,-1.0)';
      PINUSE='BI';
    'DDR0_DQ'<32>:
      PIN_NUMBER='(0,0,C42,0,0,0,0,0,0,0,0,0,0,0,0,0,0,0,0,0,0,0,0,0,0,0,0,0,0,0~
)';
      BIDIRECTIONAL='TRUE';
      INPUT_LOAD='(-0.01,0.01)';
      OUTPUT_LOAD='(1.0,-1.0)';
      PINUSE='BI';
    'DDR0_DQ'<31>:
      PIN_NUMBER='(0,0,R74,0,0,0,0,0,0,0,0,0,0,0,0,0,0,0,0,0,0,0,0,0,0,0,0,0,0,0~
)';
      BIDIRECTIONAL='TRUE';
      INPUT_LOAD='(-0.01,0.01)';
      OUTPUT_LOAD='(1.0,-1.0)';
      PINUSE='BI';
    'DDR0_DQ'<30>:
      PIN_NUMBER='(0,0,L74,0,0,0,0,0,0,0,0,0,0,0,0,0,0,0,0,0,0,0,0,0,0,0,0,0,0,0~
)';
      BIDIRECTIONAL='TRUE';
      INPUT_LOAD='(-0.01,0.01)';
      OUTPUT_LOAD='(1.0,-1.0)';
      PINUSE='BI';
    'DDR0_DQ'<29>:
      PIN_NUMBER='(0,0,P77,0,0,0,0,0,0,0,0,0,0,0,0,0,0,0,0,0,0,0,0,0,0,0,0,0,0,0~
)';
      BIDIRECTIONAL='TRUE';
      INPUT_LOAD='(-0.01,0.01)';
      OUTPUT_LOAD='(1.0,-1.0)';
      PINUSE='BI';
    'DDR0_DQ'<28>:
      PIN_NUMBER='(0,0,M77,0,0,0,0,0,0,0,0,0,0,0,0,0,0,0,0,0,0,0,0,0,0,0,0,0,0,0~
)';
      BIDIRECTIONAL='TRUE';
      INPUT_LOAD='(-0.01,0.01)';
      OUTPUT_LOAD='(1.0,-1.0)';
      PINUSE='BI';
    'DDR0_DQ'<27>:
      PIN_NUMBER='(0,0,P73,0,0,0,0,0,0,0,0,0,0,0,0,0,0,0,0,0,0,0,0,0,0,0,0,0,0,0~
)';
      BIDIRECTIONAL='TRUE';
      INPUT_LOAD='(-0.01,0.01)';
      OUTPUT_LOAD='(1.0,-1.0)';
      PINUSE='BI';
    'DDR0_DQ'<26>:
      PIN_NUMBER='(0,0,M73,0,0,0,0,0,0,0,0,0,0,0,0,0,0,0,0,0,0,0,0,0,0,0,0,0,0,0~
)';
      BIDIRECTIONAL='TRUE';
      INPUT_LOAD='(-0.01,0.01)';
      OUTPUT_LOAD='(1.0,-1.0)';
      PINUSE='BI';
    'DDR0_DQ'<25>:
      PIN_NUMBER='(0,0,R76,0,0,0,0,0,0,0,0,0,0,0,0,0,0,0,0,0,0,0,0,0,0,0,0,0,0,0~
)';
      BIDIRECTIONAL='TRUE';
      INPUT_LOAD='(-0.01,0.01)';
      OUTPUT_LOAD='(1.0,-1.0)';
      PINUSE='BI';
    'DDR0_DQ'<24>:
      PIN_NUMBER='(0,0,L76,0,0,0,0,0,0,0,0,0,0,0,0,0,0,0,0,0,0,0,0,0,0,0,0,0,0,0~
)';
      BIDIRECTIONAL='TRUE';
      INPUT_LOAD='(-0.01,0.01)';
      OUTPUT_LOAD='(1.0,-1.0)';
      PINUSE='BI';
    'DDR0_DQ'<23>:
      PIN_NUMBER='(0,0,N80,0,0,0,0,0,0,0,0,0,0,0,0,0,0,0,0,0,0,0,0,0,0,0,0,0,0,0~
)';
      BIDIRECTIONAL='TRUE';
      INPUT_LOAD='(-0.01,0.01)';
      OUTPUT_LOAD='(1.0,-1.0)';
      PINUSE='BI';
    'DDR0_DQ'<22>:
      PIN_NUMBER='(0,0,R82,0,0,0,0,0,0,0,0,0,0,0,0,0,0,0,0,0,0,0,0,0,0,0,0,0,0,0~
)';
      BIDIRECTIONAL='TRUE';
      INPUT_LOAD='(-0.01,0.01)';
      OUTPUT_LOAD='(1.0,-1.0)';
      PINUSE='BI';
    'DDR0_DQ'<21>:
      PIN_NUMBER='(0,0,V79,0,0,0,0,0,0,0,0,0,0,0,0,0,0,0,0,0,0,0,0,0,0,0,0,0,0,0~
)';
      BIDIRECTIONAL='TRUE';
      INPUT_LOAD='(-0.01,0.01)';
      OUTPUT_LOAD='(1.0,-1.0)';
      PINUSE='BI';
    'DDR0_DQ'<20>:
      PIN_NUMBER='(0,0,W80,0,0,0,0,0,0,0,0,0,0,0,0,0,0,0,0,0,0,0,0,0,0,0,0,0,0,0~
)';
      BIDIRECTIONAL='TRUE';
      INPUT_LOAD='(-0.01,0.01)';
      OUTPUT_LOAD='(1.0,-1.0)';
      PINUSE='BI';
    'DDR0_DQ'<19>:
      PIN_NUMBER='(0,0,M81,0,0,0,0,0,0,0,0,0,0,0,0,0,0,0,0,0,0,0,0,0,0,0,0,0,0,0~
)';
      BIDIRECTIONAL='TRUE';
      INPUT_LOAD='(-0.01,0.01)';
      OUTPUT_LOAD='(1.0,-1.0)';
      PINUSE='BI';
    'DDR0_DQ'<18>:
      PIN_NUMBER='(0,0,N82,0,0,0,0,0,0,0,0,0,0,0,0,0,0,0,0,0,0,0,0,0,0,0,0,0,0,0~
)';
      BIDIRECTIONAL='TRUE';
      INPUT_LOAD='(-0.01,0.01)';
      OUTPUT_LOAD='(1.0,-1.0)';
      PINUSE='BI';
    'DDR0_DQ'<17>:
      PIN_NUMBER='(0,0,T79,0,0,0,0,0,0,0,0,0,0,0,0,0,0,0,0,0,0,0,0,0,0,0,0,0,0,0~
)';
      BIDIRECTIONAL='TRUE';
      INPUT_LOAD='(-0.01,0.01)';
      OUTPUT_LOAD='(1.0,-1.0)';
      PINUSE='BI';
    'DDR0_DQ'<16>:
      PIN_NUMBER='(0,0,V81,0,0,0,0,0,0,0,0,0,0,0,0,0,0,0,0,0,0,0,0,0,0,0,0,0,0,0~
)';
      BIDIRECTIONAL='TRUE';
      INPUT_LOAD='(-0.01,0.01)';
      OUTPUT_LOAD='(1.0,-1.0)';
      PINUSE='BI';
    'DDR0_DQ'<15>:
      PIN_NUMBER='(0,0,N84,0,0,0,0,0,0,0,0,0,0,0,0,0,0,0,0,0,0,0,0,0,0,0,0,0,0,0~
)';
      BIDIRECTIONAL='TRUE';
      INPUT_LOAD='(-0.01,0.01)';
      OUTPUT_LOAD='(1.0,-1.0)';
      PINUSE='BI';
    'DDR0_DQ'<14>:
      PIN_NUMBER='(0,0,N86,0,0,0,0,0,0,0,0,0,0,0,0,0,0,0,0,0,0,0,0,0,0,0,0,0,0,0~
)';
      BIDIRECTIONAL='TRUE';
      INPUT_LOAD='(-0.01,0.01)';
      OUTPUT_LOAD='(1.0,-1.0)';
      PINUSE='BI';
    'DDR0_DQ'<13>:
      PIN_NUMBER='(0,0,AA84,0,0,0,0,0,0,0,0,0,0,0,0,0,0,0,0,0,0,0,0,0,0,0,0,0,0,~
0)';
      BIDIRECTIONAL='TRUE';
      INPUT_LOAD='(-0.01,0.01)';
      OUTPUT_LOAD='(1.0,-1.0)';
      PINUSE='BI';
    'DDR0_DQ'<12>:
      PIN_NUMBER='(0,0,AA86,0,0,0,0,0,0,0,0,0,0,0,0,0,0,0,0,0,0,0,0,0,0,0,0,0,0,~
0)';
      BIDIRECTIONAL='TRUE';
      INPUT_LOAD='(-0.01,0.01)';
      OUTPUT_LOAD='(1.0,-1.0)';
      PINUSE='BI';
    'DDR0_DQ'<11>:
      PIN_NUMBER='(0,0,L84,0,0,0,0,0,0,0,0,0,0,0,0,0,0,0,0,0,0,0,0,0,0,0,0,0,0,0~
)';
      BIDIRECTIONAL='TRUE';
      INPUT_LOAD='(-0.01,0.01)';
      OUTPUT_LOAD='(1.0,-1.0)';
      PINUSE='BI';
    'DDR0_DQ'<10>:
      PIN_NUMBER='(0,0,L86,0,0,0,0,0,0,0,0,0,0,0,0,0,0,0,0,0,0,0,0,0,0,0,0,0,0,0~
)';
      BIDIRECTIONAL='TRUE';
      INPUT_LOAD='(-0.01,0.01)';
      OUTPUT_LOAD='(1.0,-1.0)';
      PINUSE='BI';
    'DDR0_DQ'<9>:
      PIN_NUMBER='(0,0,W84,0,0,0,0,0,0,0,0,0,0,0,0,0,0,0,0,0,0,0,0,0,0,0,0,0,0,0~
)';
      BIDIRECTIONAL='TRUE';
      INPUT_LOAD='(-0.01,0.01)';
      OUTPUT_LOAD='(1.0,-1.0)';
      PINUSE='BI';
    'DDR0_DQ'<8>:
      PIN_NUMBER='(0,0,W86,0,0,0,0,0,0,0,0,0,0,0,0,0,0,0,0,0,0,0,0,0,0,0,0,0,0,0~
)';
      BIDIRECTIONAL='TRUE';
      INPUT_LOAD='(-0.01,0.01)';
      OUTPUT_LOAD='(1.0,-1.0)';
      PINUSE='BI';
    'DDR0_DQ'<7>:
      PIN_NUMBER='(0,0,AG84,0,0,0,0,0,0,0,0,0,0,0,0,0,0,0,0,0,0,0,0,0,0,0,0,0,0,~
0)';
      BIDIRECTIONAL='TRUE';
      INPUT_LOAD='(-0.01,0.01)';
      OUTPUT_LOAD='(1.0,-1.0)';
      PINUSE='BI';
    'DDR0_DQ'<6>:
      PIN_NUMBER='(0,0,AG86,0,0,0,0,0,0,0,0,0,0,0,0,0,0,0,0,0,0,0,0,0,0,0,0,0,0,~
0)';
      BIDIRECTIONAL='TRUE';
      INPUT_LOAD='(-0.01,0.01)';
      OUTPUT_LOAD='(1.0,-1.0)';
      PINUSE='BI';
    'DDR0_DQ'<5>:
      PIN_NUMBER='(0,0,AR84,0,0,0,0,0,0,0,0,0,0,0,0,0,0,0,0,0,0,0,0,0,0,0,0,0,0,~
0)';
      BIDIRECTIONAL='TRUE';
      INPUT_LOAD='(-0.01,0.01)';
      OUTPUT_LOAD='(1.0,-1.0)';
      PINUSE='BI';
    'DDR0_DQ'<4>:
      PIN_NUMBER='(0,0,AR86,0,0,0,0,0,0,0,0,0,0,0,0,0,0,0,0,0,0,0,0,0,0,0,0,0,0,~
0)';
      BIDIRECTIONAL='TRUE';
      INPUT_LOAD='(-0.01,0.01)';
      OUTPUT_LOAD='(1.0,-1.0)';
      PINUSE='BI';
    'DDR0_DQ'<3>:
      PIN_NUMBER='(0,0,AE84,0,0,0,0,0,0,0,0,0,0,0,0,0,0,0,0,0,0,0,0,0,0,0,0,0,0,~
0)';
      BIDIRECTIONAL='TRUE';
      INPUT_LOAD='(-0.01,0.01)';
      OUTPUT_LOAD='(1.0,-1.0)';
      PINUSE='BI';
    'DDR0_DQ'<2>:
      PIN_NUMBER='(0,0,AE86,0,0,0,0,0,0,0,0,0,0,0,0,0,0,0,0,0,0,0,0,0,0,0,0,0,0,~
0)';
      BIDIRECTIONAL='TRUE';
      INPUT_LOAD='(-0.01,0.01)';
      OUTPUT_LOAD='(1.0,-1.0)';
      PINUSE='BI';
    'DDR0_DQ'<1>:
      PIN_NUMBER='(0,0,AN84,0,0,0,0,0,0,0,0,0,0,0,0,0,0,0,0,0,0,0,0,0,0,0,0,0,0,~
0)';
      BIDIRECTIONAL='TRUE';
      INPUT_LOAD='(-0.01,0.01)';
      OUTPUT_LOAD='(1.0,-1.0)';
      PINUSE='BI';
    'DDR0_DQ'<0>:
      PIN_NUMBER='(0,0,AN86,0,0,0,0,0,0,0,0,0,0,0,0,0,0,0,0,0,0,0,0,0,0,0,0,0,0,~
0)';
      BIDIRECTIONAL='TRUE';
      INPUT_LOAD='(-0.01,0.01)';
      OUTPUT_LOAD='(1.0,-1.0)';
      PINUSE='BI';
    'DDR0_DQS_DN'<17>:
      PIN_NUMBER='(0,0,AB67,0,0,0,0,0,0,0,0,0,0,0,0,0,0,0,0,0,0,0,0,0,0,0,0,0,0,~
0)';
      BIDIRECTIONAL='TRUE';
      INPUT_LOAD='(-0.01,0.01)';
      OUTPUT_LOAD='(1.0,-1.0)';
      PINUSE='BI';
    'DDR0_DQS_DN'<16>:
      PIN_NUMBER='(0,0,J24,0,0,0,0,0,0,0,0,0,0,0,0,0,0,0,0,0,0,0,0,0,0,0,0,0,0,0~
)';
      BIDIRECTIONAL='TRUE';
      INPUT_LOAD='(-0.01,0.01)';
      OUTPUT_LOAD='(1.0,-1.0)';
      PINUSE='BI';
    'DDR0_DQS_DN'<15>:
      PIN_NUMBER='(0,0,J30,0,0,0,0,0,0,0,0,0,0,0,0,0,0,0,0,0,0,0,0,0,0,0,0,0,0,0~
)';
      BIDIRECTIONAL='TRUE';
      INPUT_LOAD='(-0.01,0.01)';
      OUTPUT_LOAD='(1.0,-1.0)';
      PINUSE='BI';
    'DDR0_DQS_DN'<14>:
      PIN_NUMBER='(0,0,J36,0,0,0,0,0,0,0,0,0,0,0,0,0,0,0,0,0,0,0,0,0,0,0,0,0,0,0~
)';
      BIDIRECTIONAL='TRUE';
      INPUT_LOAD='(-0.01,0.01)';
      OUTPUT_LOAD='(1.0,-1.0)';
      PINUSE='BI';
    'DDR0_DQS_DN'<13>:
      PIN_NUMBER='(0,0,A40,0,0,0,0,0,0,0,0,0,0,0,0,0,0,0,0,0,0,0,0,0,0,0,0,0,0,0~
)';
      BIDIRECTIONAL='TRUE';
      INPUT_LOAD='(-0.01,0.01)';
      OUTPUT_LOAD='(1.0,-1.0)';
      PINUSE='BI';
    'DDR0_DQS_DN'<12>:
      PIN_NUMBER='(0,0,K75,0,0,0,0,0,0,0,0,0,0,0,0,0,0,0,0,0,0,0,0,0,0,0,0,0,0,0~
)';
      BIDIRECTIONAL='TRUE';
      INPUT_LOAD='(-0.01,0.01)';
      OUTPUT_LOAD='(1.0,-1.0)';
      PINUSE='BI';
    'DDR0_DQS_DN'<11>:
      PIN_NUMBER='(0,0,U82,0,0,0,0,0,0,0,0,0,0,0,0,0,0,0,0,0,0,0,0,0,0,0,0,0,0,0~
)';
      BIDIRECTIONAL='TRUE';
      INPUT_LOAD='(-0.01,0.01)';
      OUTPUT_LOAD='(1.0,-1.0)';
      PINUSE='BI';
    'DDR0_DQS_DN'<10>:
      PIN_NUMBER='(0,0,U84,0,0,0,0,0,0,0,0,0,0,0,0,0,0,0,0,0,0,0,0,0,0,0,0,0,0,0~
)';
      BIDIRECTIONAL='TRUE';
      INPUT_LOAD='(-0.01,0.01)';
      OUTPUT_LOAD='(1.0,-1.0)';
      PINUSE='BI';
    'DDR0_DQS_DN'<9>:
      PIN_NUMBER='(0,0,AL84,0,0,0,0,0,0,0,0,0,0,0,0,0,0,0,0,0,0,0,0,0,0,0,0,0,0,~
0)';
      BIDIRECTIONAL='TRUE';
      INPUT_LOAD='(-0.01,0.01)';
      OUTPUT_LOAD='(1.0,-1.0)';
      PINUSE='BI';
    'DDR0_DQS_DN'<8>:
      PIN_NUMBER='(0,0,AH67,0,0,0,0,0,0,0,0,0,0,0,0,0,0,0,0,0,0,0,0,0,0,0,0,0,0,~
0)';
      BIDIRECTIONAL='TRUE';
      INPUT_LOAD='(-0.01,0.01)';
      OUTPUT_LOAD='(1.0,-1.0)';
      PINUSE='BI';
    'DDR0_DQS_DN'<7>:
      PIN_NUMBER='(0,0,N24,0,0,0,0,0,0,0,0,0,0,0,0,0,0,0,0,0,0,0,0,0,0,0,0,0,0,0~
)';
      BIDIRECTIONAL='TRUE';
      INPUT_LOAD='(-0.01,0.01)';
      OUTPUT_LOAD='(1.0,-1.0)';
      PINUSE='BI';
    'DDR0_DQS_DN'<6>:
      PIN_NUMBER='(0,0,R30,0,0,0,0,0,0,0,0,0,0,0,0,0,0,0,0,0,0,0,0,0,0,0,0,0,0,0~
)';
      BIDIRECTIONAL='TRUE';
      INPUT_LOAD='(-0.01,0.01)';
      OUTPUT_LOAD='(1.0,-1.0)';
      PINUSE='BI';
    'DDR0_DQS_DN'<5>:
      PIN_NUMBER='(0,0,R36,0,0,0,0,0,0,0,0,0,0,0,0,0,0,0,0,0,0,0,0,0,0,0,0,0,0,0~
)';
      BIDIRECTIONAL='TRUE';
      INPUT_LOAD='(-0.01,0.01)';
      OUTPUT_LOAD='(1.0,-1.0)';
      PINUSE='BI';
    'DDR0_DQS_DN'<4>:
      PIN_NUMBER='(0,0,G40,0,0,0,0,0,0,0,0,0,0,0,0,0,0,0,0,0,0,0,0,0,0,0,0,0,0,0~
)';
      BIDIRECTIONAL='TRUE';
      INPUT_LOAD='(-0.01,0.01)';
      OUTPUT_LOAD='(1.0,-1.0)';
      PINUSE='BI';
    'DDR0_DQS_DN'<3>:
      PIN_NUMBER='(0,0,T75,0,0,0,0,0,0,0,0,0,0,0,0,0,0,0,0,0,0,0,0,0,0,0,0,0,0,0~
)';
      BIDIRECTIONAL='TRUE';
      INPUT_LOAD='(-0.01,0.01)';
      OUTPUT_LOAD='(1.0,-1.0)';
      PINUSE='BI';
    'DDR0_DQS_DN'<2>:
      PIN_NUMBER='(0,0,P79,0,0,0,0,0,0,0,0,0,0,0,0,0,0,0,0,0,0,0,0,0,0,0,0,0,0,0~
)';
      BIDIRECTIONAL='TRUE';
      INPUT_LOAD='(-0.01,0.01)';
      OUTPUT_LOAD='(1.0,-1.0)';
      PINUSE='BI';
    'DDR0_DQS_DN'<1>:
      PIN_NUMBER='(0,0,R84,0,0,0,0,0,0,0,0,0,0,0,0,0,0,0,0,0,0,0,0,0,0,0,0,0,0,0~
)';
      BIDIRECTIONAL='TRUE';
      INPUT_LOAD='(-0.01,0.01)';
      OUTPUT_LOAD='(1.0,-1.0)';
      PINUSE='BI';
    'DDR0_DQS_DN'<0>:
      PIN_NUMBER='(0,0,AJ84,0,0,0,0,0,0,0,0,0,0,0,0,0,0,0,0,0,0,0,0,0,0,0,0,0,0,~
0)';
      BIDIRECTIONAL='TRUE';
      INPUT_LOAD='(-0.01,0.01)';
      OUTPUT_LOAD='(1.0,-1.0)';
      PINUSE='BI';
    'DDR0_DQS_DP'<17>:
      PIN_NUMBER='(0,0,AD67,0,0,0,0,0,0,0,0,0,0,0,0,0,0,0,0,0,0,0,0,0,0,0,0,0,0,~
0)';
      BIDIRECTIONAL='TRUE';
      INPUT_LOAD='(-0.01,0.01)';
      OUTPUT_LOAD='(1.0,-1.0)';
      PINUSE='BI';
    'DDR0_DQS_DP'<16>:
      PIN_NUMBER='(0,0,L24,0,0,0,0,0,0,0,0,0,0,0,0,0,0,0,0,0,0,0,0,0,0,0,0,0,0,0~
)';
      BIDIRECTIONAL='TRUE';
      INPUT_LOAD='(-0.01,0.01)';
      OUTPUT_LOAD='(1.0,-1.0)';
      PINUSE='BI';
    'DDR0_DQS_DP'<15>:
      PIN_NUMBER='(0,0,L30,0,0,0,0,0,0,0,0,0,0,0,0,0,0,0,0,0,0,0,0,0,0,0,0,0,0,0~
)';
      BIDIRECTIONAL='TRUE';
      INPUT_LOAD='(-0.01,0.01)';
      OUTPUT_LOAD='(1.0,-1.0)';
      PINUSE='BI';
    'DDR0_DQS_DP'<14>:
      PIN_NUMBER='(0,0,L36,0,0,0,0,0,0,0,0,0,0,0,0,0,0,0,0,0,0,0,0,0,0,0,0,0,0,0~
)';
      BIDIRECTIONAL='TRUE';
      INPUT_LOAD='(-0.01,0.01)';
      OUTPUT_LOAD='(1.0,-1.0)';
      PINUSE='BI';
    'DDR0_DQS_DP'<13>:
      PIN_NUMBER='(0,0,C40,0,0,0,0,0,0,0,0,0,0,0,0,0,0,0,0,0,0,0,0,0,0,0,0,0,0,0~
)';
      BIDIRECTIONAL='TRUE';
      INPUT_LOAD='(-0.01,0.01)';
      OUTPUT_LOAD='(1.0,-1.0)';
      PINUSE='BI';
    'DDR0_DQS_DP'<12>:
      PIN_NUMBER='(0,0,M75,0,0,0,0,0,0,0,0,0,0,0,0,0,0,0,0,0,0,0,0,0,0,0,0,0,0,0~
)';
      BIDIRECTIONAL='TRUE';
      INPUT_LOAD='(-0.01,0.01)';
      OUTPUT_LOAD='(1.0,-1.0)';
      PINUSE='BI';
    'DDR0_DQS_DP'<11>:
      PIN_NUMBER='(0,0,T81,0,0,0,0,0,0,0,0,0,0,0,0,0,0,0,0,0,0,0,0,0,0,0,0,0,0,0~
)';
      BIDIRECTIONAL='TRUE';
      INPUT_LOAD='(-0.01,0.01)';
      OUTPUT_LOAD='(1.0,-1.0)';
      PINUSE='BI';
    'DDR0_DQS_DP'<10>:
      PIN_NUMBER='(0,0,V85,0,0,0,0,0,0,0,0,0,0,0,0,0,0,0,0,0,0,0,0,0,0,0,0,0,0,0~
)';
      BIDIRECTIONAL='TRUE';
      INPUT_LOAD='(-0.01,0.01)';
      OUTPUT_LOAD='(1.0,-1.0)';
      PINUSE='BI';
    'DDR0_DQS_DP'<9>:
      PIN_NUMBER='(0,0,AM85,0,0,0,0,0,0,0,0,0,0,0,0,0,0,0,0,0,0,0,0,0,0,0,0,0,0,~
0)';
      BIDIRECTIONAL='TRUE';
      INPUT_LOAD='(-0.01,0.01)';
      OUTPUT_LOAD='(1.0,-1.0)';
      PINUSE='BI';
    'DDR0_DQS_DP'<8>:
      PIN_NUMBER='(0,0,AF67,0,0,0,0,0,0,0,0,0,0,0,0,0,0,0,0,0,0,0,0,0,0,0,0,0,0,~
0)';
      BIDIRECTIONAL='TRUE';
      INPUT_LOAD='(-0.01,0.01)';
      OUTPUT_LOAD='(1.0,-1.0)';
      PINUSE='BI';
    'DDR0_DQS_DP'<7>:
      PIN_NUMBER='(0,0,R24,0,0,0,0,0,0,0,0,0,0,0,0,0,0,0,0,0,0,0,0,0,0,0,0,0,0,0~
)';
      BIDIRECTIONAL='TRUE';
      INPUT_LOAD='(-0.01,0.01)';
      OUTPUT_LOAD='(1.0,-1.0)';
      PINUSE='BI';
    'DDR0_DQS_DP'<6>:
      PIN_NUMBER='(0,0,N30,0,0,0,0,0,0,0,0,0,0,0,0,0,0,0,0,0,0,0,0,0,0,0,0,0,0,0~
)';
      BIDIRECTIONAL='TRUE';
      INPUT_LOAD='(-0.01,0.01)';
      OUTPUT_LOAD='(1.0,-1.0)';
      PINUSE='BI';
    'DDR0_DQS_DP'<5>:
      PIN_NUMBER='(0,0,N36,0,0,0,0,0,0,0,0,0,0,0,0,0,0,0,0,0,0,0,0,0,0,0,0,0,0,0~
)';
      BIDIRECTIONAL='TRUE';
      INPUT_LOAD='(-0.01,0.01)';
      OUTPUT_LOAD='(1.0,-1.0)';
      PINUSE='BI';
    'DDR0_DQS_DP'<4>:
      PIN_NUMBER='(0,0,E40,0,0,0,0,0,0,0,0,0,0,0,0,0,0,0,0,0,0,0,0,0,0,0,0,0,0,0~
)';
      BIDIRECTIONAL='TRUE';
      INPUT_LOAD='(-0.01,0.01)';
      OUTPUT_LOAD='(1.0,-1.0)';
      PINUSE='BI';
    'DDR0_DQS_DP'<3>:
      PIN_NUMBER='(0,0,P75,0,0,0,0,0,0,0,0,0,0,0,0,0,0,0,0,0,0,0,0,0,0,0,0,0,0,0~
)';
      BIDIRECTIONAL='TRUE';
      INPUT_LOAD='(-0.01,0.01)';
      OUTPUT_LOAD='(1.0,-1.0)';
      PINUSE='BI';
    'DDR0_DQS_DP'<2>:
      PIN_NUMBER='(0,0,R80,0,0,0,0,0,0,0,0,0,0,0,0,0,0,0,0,0,0,0,0,0,0,0,0,0,0,0~
)';
      BIDIRECTIONAL='TRUE';
      INPUT_LOAD='(-0.01,0.01)';
      OUTPUT_LOAD='(1.0,-1.0)';
      PINUSE='BI';
    'DDR0_DQS_DP'<1>:
      PIN_NUMBER='(0,0,P85,0,0,0,0,0,0,0,0,0,0,0,0,0,0,0,0,0,0,0,0,0,0,0,0,0,0,0~
)';
      BIDIRECTIONAL='TRUE';
      INPUT_LOAD='(-0.01,0.01)';
      OUTPUT_LOAD='(1.0,-1.0)';
      PINUSE='BI';
    'DDR0_DQS_DP'<0>:
      PIN_NUMBER='(0,0,AH85,0,0,0,0,0,0,0,0,0,0,0,0,0,0,0,0,0,0,0,0,0,0,0,0,0,0,~
0)';
      BIDIRECTIONAL='TRUE';
      INPUT_LOAD='(-0.01,0.01)';
      OUTPUT_LOAD='(1.0,-1.0)';
      PINUSE='BI';
    'DDR0_ECC'<7>:
      PIN_NUMBER='(0,0,AG66,0,0,0,0,0,0,0,0,0,0,0,0,0,0,0,0,0,0,0,0,0,0,0,0,0,0,~
0)';
      BIDIRECTIONAL='TRUE';
      INPUT_LOAD='(-0.01,0.01)';
      OUTPUT_LOAD='(1.0,-1.0)';
      PINUSE='BI';
    'DDR0_ECC'<6>:
      PIN_NUMBER='(0,0,AC66,0,0,0,0,0,0,0,0,0,0,0,0,0,0,0,0,0,0,0,0,0,0,0,0,0,0,~
0)';
      BIDIRECTIONAL='TRUE';
      INPUT_LOAD='(-0.01,0.01)';
      OUTPUT_LOAD='(1.0,-1.0)';
      PINUSE='BI';
    'DDR0_ECC'<5>:
      PIN_NUMBER='(0,0,AF69,0,0,0,0,0,0,0,0,0,0,0,0,0,0,0,0,0,0,0,0,0,0,0,0,0,0,~
0)';
      BIDIRECTIONAL='TRUE';
      INPUT_LOAD='(-0.01,0.01)';
      OUTPUT_LOAD='(1.0,-1.0)';
      PINUSE='BI';
    'DDR0_ECC'<4>:
      PIN_NUMBER='(0,0,AD69,0,0,0,0,0,0,0,0,0,0,0,0,0,0,0,0,0,0,0,0,0,0,0,0,0,0,~
0)';
      BIDIRECTIONAL='TRUE';
      INPUT_LOAD='(-0.01,0.01)';
      OUTPUT_LOAD='(1.0,-1.0)';
      PINUSE='BI';
    'DDR0_ECC'<3>:
      PIN_NUMBER='(0,0,AF65,0,0,0,0,0,0,0,0,0,0,0,0,0,0,0,0,0,0,0,0,0,0,0,0,0,0,~
0)';
      BIDIRECTIONAL='TRUE';
      INPUT_LOAD='(-0.01,0.01)';
      OUTPUT_LOAD='(1.0,-1.0)';
      PINUSE='BI';
    'DDR0_ECC'<2>:
      PIN_NUMBER='(0,0,AD65,0,0,0,0,0,0,0,0,0,0,0,0,0,0,0,0,0,0,0,0,0,0,0,0,0,0,~
0)';
      BIDIRECTIONAL='TRUE';
      INPUT_LOAD='(-0.01,0.01)';
      OUTPUT_LOAD='(1.0,-1.0)';
      PINUSE='BI';
    'DDR0_ECC'<1>:
      PIN_NUMBER='(0,0,AG68,0,0,0,0,0,0,0,0,0,0,0,0,0,0,0,0,0,0,0,0,0,0,0,0,0,0,~
0)';
      BIDIRECTIONAL='TRUE';
      INPUT_LOAD='(-0.01,0.01)';
      OUTPUT_LOAD='(1.0,-1.0)';
      PINUSE='BI';
    'DDR0_ECC'<0>:
      PIN_NUMBER='(0,0,AC68,0,0,0,0,0,0,0,0,0,0,0,0,0,0,0,0,0,0,0,0,0,0,0,0,0,0,~
0)';
      BIDIRECTIONAL='TRUE';
      INPUT_LOAD='(-0.01,0.01)';
      OUTPUT_LOAD='(1.0,-1.0)';
      PINUSE='BI';
    'DDR0_MA'<17>:
      PIN_NUMBER='(0,0,K47,0,0,0,0,0,0,0,0,0,0,0,0,0,0,0,0,0,0,0,0,0,0,0,0,0,0,0~
)';
      OUTPUT_LOAD='(1.0,-1.0)';
      PINUSE='OUT';
    'DDR0_MA'<16>:
      PIN_NUMBER='(0,0,D51,0,0,0,0,0,0,0,0,0,0,0,0,0,0,0,0,0,0,0,0,0,0,0,0,0,0,0~
)';
      OUTPUT_LOAD='(1.0,-1.0)';
      PINUSE='OUT';
    'DDR0_MA'<15>:
      PIN_NUMBER='(0,0,K49,0,0,0,0,0,0,0,0,0,0,0,0,0,0,0,0,0,0,0,0,0,0,0,0,0,0,0~
)';
      OUTPUT_LOAD='(1.0,-1.0)';
      PINUSE='OUT';
    'DDR0_MA'<14>:
      PIN_NUMBER='(0,0,F51,0,0,0,0,0,0,0,0,0,0,0,0,0,0,0,0,0,0,0,0,0,0,0,0,0,0,0~
)';
      OUTPUT_LOAD='(1.0,-1.0)';
      PINUSE='OUT';
    'DDR0_MA'<13>:
      PIN_NUMBER='(0,0,J48,0,0,0,0,0,0,0,0,0,0,0,0,0,0,0,0,0,0,0,0,0,0,0,0,0,0,0~
)';
      OUTPUT_LOAD='(1.0,-1.0)';
      PINUSE='OUT';
    'DDR0_MA'<12>:
      PIN_NUMBER='(0,0,J64,0,0,0,0,0,0,0,0,0,0,0,0,0,0,0,0,0,0,0,0,0,0,0,0,0,0,0~
)';
      OUTPUT_LOAD='(1.0,-1.0)';
      PINUSE='OUT';
    'DDR0_MA'<11>:
      PIN_NUMBER='(0,0,G62,0,0,0,0,0,0,0,0,0,0,0,0,0,0,0,0,0,0,0,0,0,0,0,0,0,0,0~
)';
      OUTPUT_LOAD='(1.0,-1.0)';
      PINUSE='OUT';
    'DDR0_MA'<10>:
      PIN_NUMBER='(0,0,J54,0,0,0,0,0,0,0,0,0,0,0,0,0,0,0,0,0,0,0,0,0,0,0,0,0,0,0~
)';
      OUTPUT_LOAD='(1.0,-1.0)';
      PINUSE='OUT';
    'DDR0_MA'<9>:
      PIN_NUMBER='(0,0,F61,0,0,0,0,0,0,0,0,0,0,0,0,0,0,0,0,0,0,0,0,0,0,0,0,0,0,0~
)';
      OUTPUT_LOAD='(1.0,-1.0)';
      PINUSE='OUT';
    'DDR0_MA'<8>:
      PIN_NUMBER='(0,0,C60,0,0,0,0,0,0,0,0,0,0,0,0,0,0,0,0,0,0,0,0,0,0,0,0,0,0,0~
)';
      OUTPUT_LOAD='(1.0,-1.0)';
      PINUSE='OUT';
    'DDR0_MA'<7>:
      PIN_NUMBER='(0,0,G60,0,0,0,0,0,0,0,0,0,0,0,0,0,0,0,0,0,0,0,0,0,0,0,0,0,0,0~
)';
      OUTPUT_LOAD='(1.0,-1.0)';
      PINUSE='OUT';
    'DDR0_MA'<6>:
      PIN_NUMBER='(0,0,D59,0,0,0,0,0,0,0,0,0,0,0,0,0,0,0,0,0,0,0,0,0,0,0,0,0,0,0~
)';
      OUTPUT_LOAD='(1.0,-1.0)';
      PINUSE='OUT';
    'DDR0_MA'<5>:
      PIN_NUMBER='(0,0,F59,0,0,0,0,0,0,0,0,0,0,0,0,0,0,0,0,0,0,0,0,0,0,0,0,0,0,0~
)';
      OUTPUT_LOAD='(1.0,-1.0)';
      PINUSE='OUT';
    'DDR0_MA'<4>:
      PIN_NUMBER='(0,0,G58,0,0,0,0,0,0,0,0,0,0,0,0,0,0,0,0,0,0,0,0,0,0,0,0,0,0,0~
)';
      OUTPUT_LOAD='(1.0,-1.0)';
      PINUSE='OUT';
    'DDR0_MA'<3>:
      PIN_NUMBER='(0,0,C58,0,0,0,0,0,0,0,0,0,0,0,0,0,0,0,0,0,0,0,0,0,0,0,0,0,0,0~
)';
      OUTPUT_LOAD='(1.0,-1.0)';
      PINUSE='OUT';
    'DDR0_MA'<2>:
      PIN_NUMBER='(0,0,D57,0,0,0,0,0,0,0,0,0,0,0,0,0,0,0,0,0,0,0,0,0,0,0,0,0,0,0~
)';
      OUTPUT_LOAD='(1.0,-1.0)';
      PINUSE='OUT';
    'DDR0_MA'<1>:
      PIN_NUMBER='(0,0,F57,0,0,0,0,0,0,0,0,0,0,0,0,0,0,0,0,0,0,0,0,0,0,0,0,0,0,0~
)';
      OUTPUT_LOAD='(1.0,-1.0)';
      PINUSE='OUT';
    'DDR0_MA'<0>:
      PIN_NUMBER='(0,0,F53,0,0,0,0,0,0,0,0,0,0,0,0,0,0,0,0,0,0,0,0,0,0,0,0,0,0,0~
)';
      OUTPUT_LOAD='(1.0,-1.0)';
      PINUSE='OUT';
    'DDR0_ODT'<3>:
      PIN_NUMBER='(0,0,G48,0,0,0,0,0,0,0,0,0,0,0,0,0,0,0,0,0,0,0,0,0,0,0,0,0,0,0~
)';
      OUTPUT_LOAD='(1.0,-1.0)';
      PINUSE='OUT';
    'DDR0_ODT'<2>:
      PIN_NUMBER='(0,0,G50,0,0,0,0,0,0,0,0,0,0,0,0,0,0,0,0,0,0,0,0,0,0,0,0,0,0,0~
)';
      OUTPUT_LOAD='(1.0,-1.0)';
      PINUSE='OUT';
    'DDR0_ODT'<1>:
      PIN_NUMBER='(0,0,C48,0,0,0,0,0,0,0,0,0,0,0,0,0,0,0,0,0,0,0,0,0,0,0,0,0,0,0~
)';
      OUTPUT_LOAD='(1.0,-1.0)';
      PINUSE='OUT';
    'DDR0_ODT'<0>:
      PIN_NUMBER='(0,0,C50,0,0,0,0,0,0,0,0,0,0,0,0,0,0,0,0,0,0,0,0,0,0,0,0,0,0,0~
)';
      OUTPUT_LOAD='(1.0,-1.0)';
      PINUSE='OUT';
    'DDR0_PAR':
      PIN_NUMBER='(0,0,D53,0,0,0,0,0,0,0,0,0,0,0,0,0,0,0,0,0,0,0,0,0,0,0,0,0,0,0~
)';
      OUTPUT_LOAD='(1.0,-1.0)';
      PINUSE='OUT';
    'DDR1_ACT_N':
      PIN_NUMBER='(0,0,0,T63,0,0,0,0,0,0,0,0,0,0,0,0,0,0,0,0,0,0,0,0,0,0,0,0,0,0~
)';
      OUTPUT_LOAD='(1.0,-1.0)';
      PINUSE='OUT';
    'DDR1_ALERT_N':
      PIN_NUMBER='(0,0,0,W62,0,0,0,0,0,0,0,0,0,0,0,0,0,0,0,0,0,0,0,0,0,0,0,0,0,0~
)';
      INPUT_LOAD='(-0.01,0.01)';
      PINUSE='IN';
    'DDR1_BA'<1>:
      PIN_NUMBER='(0,0,0,K55,0,0,0,0,0,0,0,0,0,0,0,0,0,0,0,0,0,0,0,0,0,0,0,0,0,0~
)';
      OUTPUT_LOAD='(1.0,-1.0)';
      PINUSE='OUT';
    'DDR1_BA'<0>:
      PIN_NUMBER='(0,0,0,T53,0,0,0,0,0,0,0,0,0,0,0,0,0,0,0,0,0,0,0,0,0,0,0,0,0,0~
)';
      OUTPUT_LOAD='(1.0,-1.0)';
      PINUSE='OUT';
    'DDR1_BG'<1>:
      PIN_NUMBER='(0,0,0,N60,0,0,0,0,0,0,0,0,0,0,0,0,0,0,0,0,0,0,0,0,0,0,0,0,0,0~
)';
      OUTPUT_LOAD='(1.0,-1.0)';
      PINUSE='OUT';
    'DDR1_BG'<0>:
      PIN_NUMBER='(0,0,0,M61,0,0,0,0,0,0,0,0,0,0,0,0,0,0,0,0,0,0,0,0,0,0,0,0,0,0~
)';
      OUTPUT_LOAD='(1.0,-1.0)';
      PINUSE='OUT';
    'DDR1_CAVREF':
      PIN_NUMBER='(AK63,0,0,0,0,0,0,0,0,0,0,0,0,0,0,0,0,0,0,0,0,0,0,0,0,0,0,0,0,~
0)';
      OUTPUT_LOAD='(1.0,-1.0)';
      PINUSE='OUT';
    'DDR1_CID'<2>:
      PIN_NUMBER='(0,0,0,M47,0,0,0,0,0,0,0,0,0,0,0,0,0,0,0,0,0,0,0,0,0,0,0,0,0,0~
)';
      OUTPUT_LOAD='(1.0,-1.0)';
      PINUSE='OUT';
    'DDR1_CKE'<3>:
      PIN_NUMBER='(0,0,0,L64,0,0,0,0,0,0,0,0,0,0,0,0,0,0,0,0,0,0,0,0,0,0,0,0,0,0~
)';
      OUTPUT_LOAD='(1.0,-1.0)';
      PINUSE='OUT';
    'DDR1_CKE'<2>:
      PIN_NUMBER='(0,0,0,K63,0,0,0,0,0,0,0,0,0,0,0,0,0,0,0,0,0,0,0,0,0,0,0,0,0,0~
)';
      OUTPUT_LOAD='(1.0,-1.0)';
      PINUSE='OUT';
    'DDR1_CKE'<1>:
      PIN_NUMBER='(0,0,0,R64,0,0,0,0,0,0,0,0,0,0,0,0,0,0,0,0,0,0,0,0,0,0,0,0,0,0~
)';
      OUTPUT_LOAD='(1.0,-1.0)';
      PINUSE='OUT';
    'DDR1_CKE'<0>:
      PIN_NUMBER='(0,0,0,N62,0,0,0,0,0,0,0,0,0,0,0,0,0,0,0,0,0,0,0,0,0,0,0,0,0,0~
)';
      OUTPUT_LOAD='(1.0,-1.0)';
      PINUSE='OUT';
    'DDR1_CLK_DN'<3>:
      PIN_NUMBER='(0,0,0,R56,0,0,0,0,0,0,0,0,0,0,0,0,0,0,0,0,0,0,0,0,0,0,0,0,0,0~
)';
      OUTPUT_LOAD='(1.0,-1.0)';
      PINUSE='OUT';
    'DDR1_CLK_DN'<2>:
      PIN_NUMBER='(0,0,0,N56,0,0,0,0,0,0,0,0,0,0,0,0,0,0,0,0,0,0,0,0,0,0,0,0,0,0~
)';
      OUTPUT_LOAD='(1.0,-1.0)';
      PINUSE='OUT';
    'DDR1_CLK_DN'<1>:
      PIN_NUMBER='(0,0,0,R54,0,0,0,0,0,0,0,0,0,0,0,0,0,0,0,0,0,0,0,0,0,0,0,0,0,0~
)';
      OUTPUT_LOAD='(1.0,-1.0)';
      PINUSE='OUT';
    'DDR1_CLK_DN'<0>:
      PIN_NUMBER='(0,0,0,M53,0,0,0,0,0,0,0,0,0,0,0,0,0,0,0,0,0,0,0,0,0,0,0,0,0,0~
)';
      OUTPUT_LOAD='(1.0,-1.0)';
      PINUSE='OUT';
    'DDR1_CLK_DP'<3>:
      PIN_NUMBER='(0,0,0,T57,0,0,0,0,0,0,0,0,0,0,0,0,0,0,0,0,0,0,0,0,0,0,0,0,0,0~
)';
      OUTPUT_LOAD='(1.0,-1.0)';
      PINUSE='OUT';
    'DDR1_CLK_DP'<2>:
      PIN_NUMBER='(0,0,0,M57,0,0,0,0,0,0,0,0,0,0,0,0,0,0,0,0,0,0,0,0,0,0,0,0,0,0~
)';
      OUTPUT_LOAD='(1.0,-1.0)';
      PINUSE='OUT';
    'DDR1_CLK_DP'<1>:
      PIN_NUMBER='(0,0,0,T55,0,0,0,0,0,0,0,0,0,0,0,0,0,0,0,0,0,0,0,0,0,0,0,0,0,0~
)';
      OUTPUT_LOAD='(1.0,-1.0)';
      PINUSE='OUT';
    'DDR1_CLK_DP'<0>:
      PIN_NUMBER='(0,0,0,N54,0,0,0,0,0,0,0,0,0,0,0,0,0,0,0,0,0,0,0,0,0,0,0,0,0,0~
)';
      OUTPUT_LOAD='(1.0,-1.0)';
      PINUSE='OUT';
    'DDR1_CS_N'<7>:
      PIN_NUMBER='(0,0,0,R46,0,0,0,0,0,0,0,0,0,0,0,0,0,0,0,0,0,0,0,0,0,0,0,0,0,0~
)';
      OUTPUT_LOAD='(1.0,-1.0)';
      PINUSE='OUT';
    'DDR1_CS_N'<6>:
      PIN_NUMBER='(0,0,0,M45,0,0,0,0,0,0,0,0,0,0,0,0,0,0,0,0,0,0,0,0,0,0,0,0,0,0~
)';
      OUTPUT_LOAD='(1.0,-1.0)';
      PINUSE='OUT';
    'DDR1_CS_N'<5>:
      PIN_NUMBER='(0,0,0,T49,0,0,0,0,0,0,0,0,0,0,0,0,0,0,0,0,0,0,0,0,0,0,0,0,0,0~
)';
      OUTPUT_LOAD='(1.0,-1.0)';
      PINUSE='OUT';
    'DDR1_CS_N'<4>:
      PIN_NUMBER='(0,0,0,J50,0,0,0,0,0,0,0,0,0,0,0,0,0,0,0,0,0,0,0,0,0,0,0,0,0,0~
)';
      OUTPUT_LOAD='(1.0,-1.0)';
      PINUSE='OUT';
    'DDR1_CS_N'<3>:
      PIN_NUMBER='(0,0,0,V47,0,0,0,0,0,0,0,0,0,0,0,0,0,0,0,0,0,0,0,0,0,0,0,0,0,0~
)';
      OUTPUT_LOAD='(1.0,-1.0)';
      PINUSE='OUT';
    'DDR1_CS_N'<2>:
      PIN_NUMBER='(0,0,0,N46,0,0,0,0,0,0,0,0,0,0,0,0,0,0,0,0,0,0,0,0,0,0,0,0,0,0~
)';
      OUTPUT_LOAD='(1.0,-1.0)';
      PINUSE='OUT';
    'DDR1_CS_N'<1>:
      PIN_NUMBER='(0,0,0,R50,0,0,0,0,0,0,0,0,0,0,0,0,0,0,0,0,0,0,0,0,0,0,0,0,0,0~
)';
      OUTPUT_LOAD='(1.0,-1.0)';
      PINUSE='OUT';
    'DDR1_CS_N'<0>:
      PIN_NUMBER='(0,0,0,K51,0,0,0,0,0,0,0,0,0,0,0,0,0,0,0,0,0,0,0,0,0,0,0,0,0,0~
)';
      OUTPUT_LOAD='(1.0,-1.0)';
      PINUSE='OUT';
    'DDR1_DQ'<63>:
      PIN_NUMBER='(0,0,0,AA26,0,0,0,0,0,0,0,0,0,0,0,0,0,0,0,0,0,0,0,0,0,0,0,0,0,~
0)';
      BIDIRECTIONAL='TRUE';
      INPUT_LOAD='(-0.01,0.01)';
      OUTPUT_LOAD='(1.0,-1.0)';
      PINUSE='BI';
    'DDR1_DQ'<62>:
      PIN_NUMBER='(0,0,0,U26,0,0,0,0,0,0,0,0,0,0,0,0,0,0,0,0,0,0,0,0,0,0,0,0,0,0~
)';
      BIDIRECTIONAL='TRUE';
      INPUT_LOAD='(-0.01,0.01)';
      OUTPUT_LOAD='(1.0,-1.0)';
      PINUSE='BI';
    'DDR1_DQ'<61>:
      PIN_NUMBER='(0,0,0,Y29,0,0,0,0,0,0,0,0,0,0,0,0,0,0,0,0,0,0,0,0,0,0,0,0,0,0~
)';
      BIDIRECTIONAL='TRUE';
      INPUT_LOAD='(-0.01,0.01)';
      OUTPUT_LOAD='(1.0,-1.0)';
      PINUSE='BI';
    'DDR1_DQ'<60>:
      PIN_NUMBER='(0,0,0,V29,0,0,0,0,0,0,0,0,0,0,0,0,0,0,0,0,0,0,0,0,0,0,0,0,0,0~
)';
      BIDIRECTIONAL='TRUE';
      INPUT_LOAD='(-0.01,0.01)';
      OUTPUT_LOAD='(1.0,-1.0)';
      PINUSE='BI';
    'DDR1_DQ'<59>:
      PIN_NUMBER='(0,0,0,Y25,0,0,0,0,0,0,0,0,0,0,0,0,0,0,0,0,0,0,0,0,0,0,0,0,0,0~
)';
      BIDIRECTIONAL='TRUE';
      INPUT_LOAD='(-0.01,0.01)';
      OUTPUT_LOAD='(1.0,-1.0)';
      PINUSE='BI';
    'DDR1_DQ'<58>:
      PIN_NUMBER='(0,0,0,V25,0,0,0,0,0,0,0,0,0,0,0,0,0,0,0,0,0,0,0,0,0,0,0,0,0,0~
)';
      BIDIRECTIONAL='TRUE';
      INPUT_LOAD='(-0.01,0.01)';
      OUTPUT_LOAD='(1.0,-1.0)';
      PINUSE='BI';
    'DDR1_DQ'<57>:
      PIN_NUMBER='(0,0,0,AA28,0,0,0,0,0,0,0,0,0,0,0,0,0,0,0,0,0,0,0,0,0,0,0,0,0,~
0)';
      BIDIRECTIONAL='TRUE';
      INPUT_LOAD='(-0.01,0.01)';
      OUTPUT_LOAD='(1.0,-1.0)';
      PINUSE='BI';
    'DDR1_DQ'<56>:
      PIN_NUMBER='(0,0,0,U28,0,0,0,0,0,0,0,0,0,0,0,0,0,0,0,0,0,0,0,0,0,0,0,0,0,0~
)';
      BIDIRECTIONAL='TRUE';
      INPUT_LOAD='(-0.01,0.01)';
      OUTPUT_LOAD='(1.0,-1.0)';
      PINUSE='BI';
    'DDR1_DQ'<55>:
      PIN_NUMBER='(0,0,0,F27,0,0,0,0,0,0,0,0,0,0,0,0,0,0,0,0,0,0,0,0,0,0,0,0,0,0~
)';
      BIDIRECTIONAL='TRUE';
      INPUT_LOAD='(-0.01,0.01)';
      OUTPUT_LOAD='(1.0,-1.0)';
      PINUSE='BI';
    'DDR1_DQ'<54>:
      PIN_NUMBER='(0,0,0,B27,0,0,0,0,0,0,0,0,0,0,0,0,0,0,0,0,0,0,0,0,0,0,0,0,0,0~
)';
      BIDIRECTIONAL='TRUE';
      INPUT_LOAD='(-0.01,0.01)';
      OUTPUT_LOAD='(1.0,-1.0)';
      PINUSE='BI';
    'DDR1_DQ'<53>:
      PIN_NUMBER='(0,0,0,F29,0,0,0,0,0,0,0,0,0,0,0,0,0,0,0,0,0,0,0,0,0,0,0,0,0,0~
)';
      BIDIRECTIONAL='TRUE';
      INPUT_LOAD='(-0.01,0.01)';
      OUTPUT_LOAD='(1.0,-1.0)';
      PINUSE='BI';
    'DDR1_DQ'<52>:
      PIN_NUMBER='(0,0,0,E30,0,0,0,0,0,0,0,0,0,0,0,0,0,0,0,0,0,0,0,0,0,0,0,0,0,0~
)';
      BIDIRECTIONAL='TRUE';
      INPUT_LOAD='(-0.01,0.01)';
      OUTPUT_LOAD='(1.0,-1.0)';
      PINUSE='BI';
    'DDR1_DQ'<51>:
      PIN_NUMBER='(0,0,0,E26,0,0,0,0,0,0,0,0,0,0,0,0,0,0,0,0,0,0,0,0,0,0,0,0,0,0~
)';
      BIDIRECTIONAL='TRUE';
      INPUT_LOAD='(-0.01,0.01)';
      OUTPUT_LOAD='(1.0,-1.0)';
      PINUSE='BI';
    'DDR1_DQ'<50>:
      PIN_NUMBER='(0,0,0,C26,0,0,0,0,0,0,0,0,0,0,0,0,0,0,0,0,0,0,0,0,0,0,0,0,0,0~
)';
      BIDIRECTIONAL='TRUE';
      INPUT_LOAD='(-0.01,0.01)';
      OUTPUT_LOAD='(1.0,-1.0)';
      PINUSE='BI';
    'DDR1_DQ'<49>:
      PIN_NUMBER='(0,0,0,B29,0,0,0,0,0,0,0,0,0,0,0,0,0,0,0,0,0,0,0,0,0,0,0,0,0,0~
)';
      BIDIRECTIONAL='TRUE';
      INPUT_LOAD='(-0.01,0.01)';
      OUTPUT_LOAD='(1.0,-1.0)';
      PINUSE='BI';
    'DDR1_DQ'<48>:
      PIN_NUMBER='(0,0,0,C30,0,0,0,0,0,0,0,0,0,0,0,0,0,0,0,0,0,0,0,0,0,0,0,0,0,0~
)';
      BIDIRECTIONAL='TRUE';
      INPUT_LOAD='(-0.01,0.01)';
      OUTPUT_LOAD='(1.0,-1.0)';
      PINUSE='BI';
    'DDR1_DQ'<47>:
      PIN_NUMBER='(0,0,0,F33,0,0,0,0,0,0,0,0,0,0,0,0,0,0,0,0,0,0,0,0,0,0,0,0,0,0~
)';
      BIDIRECTIONAL='TRUE';
      INPUT_LOAD='(-0.01,0.01)';
      OUTPUT_LOAD='(1.0,-1.0)';
      PINUSE='BI';
    'DDR1_DQ'<46>:
      PIN_NUMBER='(0,0,0,B33,0,0,0,0,0,0,0,0,0,0,0,0,0,0,0,0,0,0,0,0,0,0,0,0,0,0~
)';
      BIDIRECTIONAL='TRUE';
      INPUT_LOAD='(-0.01,0.01)';
      OUTPUT_LOAD='(1.0,-1.0)';
      PINUSE='BI';
    'DDR1_DQ'<45>:
      PIN_NUMBER='(0,0,0,F35,0,0,0,0,0,0,0,0,0,0,0,0,0,0,0,0,0,0,0,0,0,0,0,0,0,0~
)';
      BIDIRECTIONAL='TRUE';
      INPUT_LOAD='(-0.01,0.01)';
      OUTPUT_LOAD='(1.0,-1.0)';
      PINUSE='BI';
    'DDR1_DQ'<44>:
      PIN_NUMBER='(0,0,0,E36,0,0,0,0,0,0,0,0,0,0,0,0,0,0,0,0,0,0,0,0,0,0,0,0,0,0~
)';
      BIDIRECTIONAL='TRUE';
      INPUT_LOAD='(-0.01,0.01)';
      OUTPUT_LOAD='(1.0,-1.0)';
      PINUSE='BI';
    'DDR1_DQ'<43>:
      PIN_NUMBER='(0,0,0,E32,0,0,0,0,0,0,0,0,0,0,0,0,0,0,0,0,0,0,0,0,0,0,0,0,0,0~
)';
      BIDIRECTIONAL='TRUE';
      INPUT_LOAD='(-0.01,0.01)';
      OUTPUT_LOAD='(1.0,-1.0)';
      PINUSE='BI';
    'DDR1_DQ'<42>:
      PIN_NUMBER='(0,0,0,C32,0,0,0,0,0,0,0,0,0,0,0,0,0,0,0,0,0,0,0,0,0,0,0,0,0,0~
)';
      BIDIRECTIONAL='TRUE';
      INPUT_LOAD='(-0.01,0.01)';
      OUTPUT_LOAD='(1.0,-1.0)';
      PINUSE='BI';
    'DDR1_DQ'<41>:
      PIN_NUMBER='(0,0,0,B35,0,0,0,0,0,0,0,0,0,0,0,0,0,0,0,0,0,0,0,0,0,0,0,0,0,0~
)';
      BIDIRECTIONAL='TRUE';
      INPUT_LOAD='(-0.01,0.01)';
      OUTPUT_LOAD='(1.0,-1.0)';
      PINUSE='BI';
    'DDR1_DQ'<40>:
      PIN_NUMBER='(0,0,0,C36,0,0,0,0,0,0,0,0,0,0,0,0,0,0,0,0,0,0,0,0,0,0,0,0,0,0~
)';
      BIDIRECTIONAL='TRUE';
      INPUT_LOAD='(-0.01,0.01)';
      OUTPUT_LOAD='(1.0,-1.0)';
      PINUSE='BI';
    'DDR1_DQ'<39>:
      PIN_NUMBER='(0,0,0,P41,0,0,0,0,0,0,0,0,0,0,0,0,0,0,0,0,0,0,0,0,0,0,0,0,0,0~
)';
      BIDIRECTIONAL='TRUE';
      INPUT_LOAD='(-0.01,0.01)';
      OUTPUT_LOAD='(1.0,-1.0)';
      PINUSE='BI';
    'DDR1_DQ'<38>:
      PIN_NUMBER='(0,0,0,K41,0,0,0,0,0,0,0,0,0,0,0,0,0,0,0,0,0,0,0,0,0,0,0,0,0,0~
)';
      BIDIRECTIONAL='TRUE';
      INPUT_LOAD='(-0.01,0.01)';
      OUTPUT_LOAD='(1.0,-1.0)';
      PINUSE='BI';
    'DDR1_DQ'<37>:
      PIN_NUMBER='(0,0,0,T43,0,0,0,0,0,0,0,0,0,0,0,0,0,0,0,0,0,0,0,0,0,0,0,0,0,0~
)';
      BIDIRECTIONAL='TRUE';
      INPUT_LOAD='(-0.01,0.01)';
      OUTPUT_LOAD='(1.0,-1.0)';
      PINUSE='BI';
    'DDR1_DQ'<36>:
      PIN_NUMBER='(0,0,0,P43,0,0,0,0,0,0,0,0,0,0,0,0,0,0,0,0,0,0,0,0,0,0,0,0,0,0~
)';
      BIDIRECTIONAL='TRUE';
      INPUT_LOAD='(-0.01,0.01)';
      OUTPUT_LOAD='(1.0,-1.0)';
      PINUSE='BI';
    'DDR1_DQ'<35>:
      PIN_NUMBER='(0,0,0,N40,0,0,0,0,0,0,0,0,0,0,0,0,0,0,0,0,0,0,0,0,0,0,0,0,0,0~
)';
      BIDIRECTIONAL='TRUE';
      INPUT_LOAD='(-0.01,0.01)';
      OUTPUT_LOAD='(1.0,-1.0)';
      PINUSE='BI';
    'DDR1_DQ'<34>:
      PIN_NUMBER='(0,0,0,L40,0,0,0,0,0,0,0,0,0,0,0,0,0,0,0,0,0,0,0,0,0,0,0,0,0,0~
)';
      BIDIRECTIONAL='TRUE';
      INPUT_LOAD='(-0.01,0.01)';
      OUTPUT_LOAD='(1.0,-1.0)';
      PINUSE='BI';
    'DDR1_DQ'<33>:
      PIN_NUMBER='(0,0,0,H43,0,0,0,0,0,0,0,0,0,0,0,0,0,0,0,0,0,0,0,0,0,0,0,0,0,0~
)';
      BIDIRECTIONAL='TRUE';
      INPUT_LOAD='(-0.01,0.01)';
      OUTPUT_LOAD='(1.0,-1.0)';
      PINUSE='BI';
    'DDR1_DQ'<32>:
      PIN_NUMBER='(0,0,0,K43,0,0,0,0,0,0,0,0,0,0,0,0,0,0,0,0,0,0,0,0,0,0,0,0,0,0~
)';
      BIDIRECTIONAL='TRUE';
      INPUT_LOAD='(-0.01,0.01)';
      OUTPUT_LOAD='(1.0,-1.0)';
      PINUSE='BI';
    'DDR1_DQ'<31>:
      PIN_NUMBER='(0,0,0,G72,0,0,0,0,0,0,0,0,0,0,0,0,0,0,0,0,0,0,0,0,0,0,0,0,0,0~
)';
      BIDIRECTIONAL='TRUE';
      INPUT_LOAD='(-0.01,0.01)';
      OUTPUT_LOAD='(1.0,-1.0)';
      PINUSE='BI';
    'DDR1_DQ'<30>:
      PIN_NUMBER='(0,0,0,C72,0,0,0,0,0,0,0,0,0,0,0,0,0,0,0,0,0,0,0,0,0,0,0,0,0,0~
)';
      BIDIRECTIONAL='TRUE';
      INPUT_LOAD='(-0.01,0.01)';
      OUTPUT_LOAD='(1.0,-1.0)';
      PINUSE='BI';
    'DDR1_DQ'<29>:
      PIN_NUMBER='(0,0,0,G74,0,0,0,0,0,0,0,0,0,0,0,0,0,0,0,0,0,0,0,0,0,0,0,0,0,0~
)';
      BIDIRECTIONAL='TRUE';
      INPUT_LOAD='(-0.01,0.01)';
      OUTPUT_LOAD='(1.0,-1.0)';
      PINUSE='BI';
    'DDR1_DQ'<28>:
      PIN_NUMBER='(0,0,0,F75,0,0,0,0,0,0,0,0,0,0,0,0,0,0,0,0,0,0,0,0,0,0,0,0,0,0~
)';
      BIDIRECTIONAL='TRUE';
      INPUT_LOAD='(-0.01,0.01)';
      OUTPUT_LOAD='(1.0,-1.0)';
      PINUSE='BI';
    'DDR1_DQ'<27>:
      PIN_NUMBER='(0,0,0,F71,0,0,0,0,0,0,0,0,0,0,0,0,0,0,0,0,0,0,0,0,0,0,0,0,0,0~
)';
      BIDIRECTIONAL='TRUE';
      INPUT_LOAD='(-0.01,0.01)';
      OUTPUT_LOAD='(1.0,-1.0)';
      PINUSE='BI';
    'DDR1_DQ'<26>:
      PIN_NUMBER='(0,0,0,D71,0,0,0,0,0,0,0,0,0,0,0,0,0,0,0,0,0,0,0,0,0,0,0,0,0,0~
)';
      BIDIRECTIONAL='TRUE';
      INPUT_LOAD='(-0.01,0.01)';
      OUTPUT_LOAD='(1.0,-1.0)';
      PINUSE='BI';
    'DDR1_DQ'<25>:
      PIN_NUMBER='(0,0,0,C74,0,0,0,0,0,0,0,0,0,0,0,0,0,0,0,0,0,0,0,0,0,0,0,0,0,0~
)';
      BIDIRECTIONAL='TRUE';
      INPUT_LOAD='(-0.01,0.01)';
      OUTPUT_LOAD='(1.0,-1.0)';
      PINUSE='BI';
    'DDR1_DQ'<24>:
      PIN_NUMBER='(0,0,0,D75,0,0,0,0,0,0,0,0,0,0,0,0,0,0,0,0,0,0,0,0,0,0,0,0,0,0~
)';
      BIDIRECTIONAL='TRUE';
      INPUT_LOAD='(-0.01,0.01)';
      OUTPUT_LOAD='(1.0,-1.0)';
      PINUSE='BI';
    'DDR1_DQ'<23>:
      PIN_NUMBER='(0,0,0,J78,0,0,0,0,0,0,0,0,0,0,0,0,0,0,0,0,0,0,0,0,0,0,0,0,0,0~
)';
      BIDIRECTIONAL='TRUE';
      INPUT_LOAD='(-0.01,0.01)';
      OUTPUT_LOAD='(1.0,-1.0)';
      PINUSE='BI';
    'DDR1_DQ'<22>:
      PIN_NUMBER='(0,0,0,E78,0,0,0,0,0,0,0,0,0,0,0,0,0,0,0,0,0,0,0,0,0,0,0,0,0,0~
)';
      BIDIRECTIONAL='TRUE';
      INPUT_LOAD='(-0.01,0.01)';
      OUTPUT_LOAD='(1.0,-1.0)';
      PINUSE='BI';
    'DDR1_DQ'<21>:
      PIN_NUMBER='(0,0,0,H81,0,0,0,0,0,0,0,0,0,0,0,0,0,0,0,0,0,0,0,0,0,0,0,0,0,0~
)';
      BIDIRECTIONAL='TRUE';
      INPUT_LOAD='(-0.01,0.01)';
      OUTPUT_LOAD='(1.0,-1.0)';
      PINUSE='BI';
    'DDR1_DQ'<20>:
      PIN_NUMBER='(0,0,0,F81,0,0,0,0,0,0,0,0,0,0,0,0,0,0,0,0,0,0,0,0,0,0,0,0,0,0~
)';
      BIDIRECTIONAL='TRUE';
      INPUT_LOAD='(-0.01,0.01)';
      OUTPUT_LOAD='(1.0,-1.0)';
      PINUSE='BI';
    'DDR1_DQ'<19>:
      PIN_NUMBER='(0,0,0,H77,0,0,0,0,0,0,0,0,0,0,0,0,0,0,0,0,0,0,0,0,0,0,0,0,0,0~
)';
      BIDIRECTIONAL='TRUE';
      INPUT_LOAD='(-0.01,0.01)';
      OUTPUT_LOAD='(1.0,-1.0)';
      PINUSE='BI';
    'DDR1_DQ'<18>:
      PIN_NUMBER='(0,0,0,F77,0,0,0,0,0,0,0,0,0,0,0,0,0,0,0,0,0,0,0,0,0,0,0,0,0,0~
)';
      BIDIRECTIONAL='TRUE';
      INPUT_LOAD='(-0.01,0.01)';
      OUTPUT_LOAD='(1.0,-1.0)';
      PINUSE='BI';
    'DDR1_DQ'<17>:
      PIN_NUMBER='(0,0,0,J80,0,0,0,0,0,0,0,0,0,0,0,0,0,0,0,0,0,0,0,0,0,0,0,0,0,0~
)';
      BIDIRECTIONAL='TRUE';
      INPUT_LOAD='(-0.01,0.01)';
      OUTPUT_LOAD='(1.0,-1.0)';
      PINUSE='BI';
    'DDR1_DQ'<16>:
      PIN_NUMBER='(0,0,0,E80,0,0,0,0,0,0,0,0,0,0,0,0,0,0,0,0,0,0,0,0,0,0,0,0,0,0~
)';
      BIDIRECTIONAL='TRUE';
      INPUT_LOAD='(-0.01,0.01)';
      OUTPUT_LOAD='(1.0,-1.0)';
      PINUSE='BI';
    'DDR1_DQ'<15>:
      PIN_NUMBER='(0,0,0,AC80,0,0,0,0,0,0,0,0,0,0,0,0,0,0,0,0,0,0,0,0,0,0,0,0,0,~
0)';
      BIDIRECTIONAL='TRUE';
      INPUT_LOAD='(-0.01,0.01)';
      OUTPUT_LOAD='(1.0,-1.0)';
      PINUSE='BI';
    'DDR1_DQ'<14>:
      PIN_NUMBER='(0,0,0,AE82,0,0,0,0,0,0,0,0,0,0,0,0,0,0,0,0,0,0,0,0,0,0,0,0,0,~
0)';
      BIDIRECTIONAL='TRUE';
      INPUT_LOAD='(-0.01,0.01)';
      OUTPUT_LOAD='(1.0,-1.0)';
      PINUSE='BI';
    'DDR1_DQ'<13>:
      PIN_NUMBER='(0,0,0,AH79,0,0,0,0,0,0,0,0,0,0,0,0,0,0,0,0,0,0,0,0,0,0,0,0,0,~
0)';
      BIDIRECTIONAL='TRUE';
      INPUT_LOAD='(-0.01,0.01)';
      OUTPUT_LOAD='(1.0,-1.0)';
      PINUSE='BI';
    'DDR1_DQ'<12>:
      PIN_NUMBER='(0,0,0,AJ80,0,0,0,0,0,0,0,0,0,0,0,0,0,0,0,0,0,0,0,0,0,0,0,0,0,~
0)';
      BIDIRECTIONAL='TRUE';
      INPUT_LOAD='(-0.01,0.01)';
      OUTPUT_LOAD='(1.0,-1.0)';
      PINUSE='BI';
    'DDR1_DQ'<11>:
      PIN_NUMBER='(0,0,0,AB81,0,0,0,0,0,0,0,0,0,0,0,0,0,0,0,0,0,0,0,0,0,0,0,0,0,~
0)';
      BIDIRECTIONAL='TRUE';
      INPUT_LOAD='(-0.01,0.01)';
      OUTPUT_LOAD='(1.0,-1.0)';
      PINUSE='BI';
    'DDR1_DQ'<10>:
      PIN_NUMBER='(0,0,0,AC82,0,0,0,0,0,0,0,0,0,0,0,0,0,0,0,0,0,0,0,0,0,0,0,0,0,~
0)';
      BIDIRECTIONAL='TRUE';
      INPUT_LOAD='(-0.01,0.01)';
      OUTPUT_LOAD='(1.0,-1.0)';
      PINUSE='BI';
    'DDR1_DQ'<9>:
      PIN_NUMBER='(0,0,0,AF79,0,0,0,0,0,0,0,0,0,0,0,0,0,0,0,0,0,0,0,0,0,0,0,0,0,~
0)';
      BIDIRECTIONAL='TRUE';
      INPUT_LOAD='(-0.01,0.01)';
      OUTPUT_LOAD='(1.0,-1.0)';
      PINUSE='BI';
    'DDR1_DQ'<8>:
      PIN_NUMBER='(0,0,0,AH81,0,0,0,0,0,0,0,0,0,0,0,0,0,0,0,0,0,0,0,0,0,0,0,0,0,~
0)';
      BIDIRECTIONAL='TRUE';
      INPUT_LOAD='(-0.01,0.01)';
      OUTPUT_LOAD='(1.0,-1.0)';
      PINUSE='BI';
    'DDR1_DQ'<7>:
      PIN_NUMBER='(0,0,0,AN80,0,0,0,0,0,0,0,0,0,0,0,0,0,0,0,0,0,0,0,0,0,0,0,0,0,~
0)';
      BIDIRECTIONAL='TRUE';
      INPUT_LOAD='(-0.01,0.01)';
      OUTPUT_LOAD='(1.0,-1.0)';
      PINUSE='BI';
    'DDR1_DQ'<6>:
      PIN_NUMBER='(0,0,0,AR82,0,0,0,0,0,0,0,0,0,0,0,0,0,0,0,0,0,0,0,0,0,0,0,0,0,~
0)';
      BIDIRECTIONAL='TRUE';
      INPUT_LOAD='(-0.01,0.01)';
      OUTPUT_LOAD='(1.0,-1.0)';
      PINUSE='BI';
    'DDR1_DQ'<5>:
      PIN_NUMBER='(0,0,0,AV79,0,0,0,0,0,0,0,0,0,0,0,0,0,0,0,0,0,0,0,0,0,0,0,0,0,~
0)';
      BIDIRECTIONAL='TRUE';
      INPUT_LOAD='(-0.01,0.01)';
      OUTPUT_LOAD='(1.0,-1.0)';
      PINUSE='BI';
    'DDR1_DQ'<4>:
      PIN_NUMBER='(0,0,0,AW80,0,0,0,0,0,0,0,0,0,0,0,0,0,0,0,0,0,0,0,0,0,0,0,0,0,~
0)';
      BIDIRECTIONAL='TRUE';
      INPUT_LOAD='(-0.01,0.01)';
      OUTPUT_LOAD='(1.0,-1.0)';
      PINUSE='BI';
    'DDR1_DQ'<3>:
      PIN_NUMBER='(0,0,0,AM81,0,0,0,0,0,0,0,0,0,0,0,0,0,0,0,0,0,0,0,0,0,0,0,0,0,~
0)';
      BIDIRECTIONAL='TRUE';
      INPUT_LOAD='(-0.01,0.01)';
      OUTPUT_LOAD='(1.0,-1.0)';
      PINUSE='BI';
    'DDR1_DQ'<2>:
      PIN_NUMBER='(0,0,0,AN82,0,0,0,0,0,0,0,0,0,0,0,0,0,0,0,0,0,0,0,0,0,0,0,0,0,~
0)';
      BIDIRECTIONAL='TRUE';
      INPUT_LOAD='(-0.01,0.01)';
      OUTPUT_LOAD='(1.0,-1.0)';
      PINUSE='BI';
    'DDR1_DQ'<1>:
      PIN_NUMBER='(0,0,0,AT79,0,0,0,0,0,0,0,0,0,0,0,0,0,0,0,0,0,0,0,0,0,0,0,0,0,~
0)';
      BIDIRECTIONAL='TRUE';
      INPUT_LOAD='(-0.01,0.01)';
      OUTPUT_LOAD='(1.0,-1.0)';
      PINUSE='BI';
    'DDR1_DQ'<0>:
      PIN_NUMBER='(0,0,0,AV81,0,0,0,0,0,0,0,0,0,0,0,0,0,0,0,0,0,0,0,0,0,0,0,0,0,~
0)';
      BIDIRECTIONAL='TRUE';
      INPUT_LOAD='(-0.01,0.01)';
      OUTPUT_LOAD='(1.0,-1.0)';
      PINUSE='BI';
    'DDR1_DQS_DN'<17>:
      PIN_NUMBER='(0,0,0,G68,0,0,0,0,0,0,0,0,0,0,0,0,0,0,0,0,0,0,0,0,0,0,0,0,0,0~
)';
      BIDIRECTIONAL='TRUE';
      INPUT_LOAD='(-0.01,0.01)';
      OUTPUT_LOAD='(1.0,-1.0)';
      PINUSE='BI';
    'DDR1_DQS_DN'<16>:
      PIN_NUMBER='(0,0,0,T27,0,0,0,0,0,0,0,0,0,0,0,0,0,0,0,0,0,0,0,0,0,0,0,0,0,0~
)';
      BIDIRECTIONAL='TRUE';
      INPUT_LOAD='(-0.01,0.01)';
      OUTPUT_LOAD='(1.0,-1.0)';
      PINUSE='BI';
    'DDR1_DQS_DN'<15>:
      PIN_NUMBER='(0,0,0,A28,0,0,0,0,0,0,0,0,0,0,0,0,0,0,0,0,0,0,0,0,0,0,0,0,0,0~
)';
      BIDIRECTIONAL='TRUE';
      INPUT_LOAD='(-0.01,0.01)';
      OUTPUT_LOAD='(1.0,-1.0)';
      PINUSE='BI';
    'DDR1_DQS_DN'<14>:
      PIN_NUMBER='(0,0,0,A34,0,0,0,0,0,0,0,0,0,0,0,0,0,0,0,0,0,0,0,0,0,0,0,0,0,0~
)';
      BIDIRECTIONAL='TRUE';
      INPUT_LOAD='(-0.01,0.01)';
      OUTPUT_LOAD='(1.0,-1.0)';
      PINUSE='BI';
    'DDR1_DQS_DN'<13>:
      PIN_NUMBER='(0,0,0,J42,0,0,0,0,0,0,0,0,0,0,0,0,0,0,0,0,0,0,0,0,0,0,0,0,0,0~
)';
      BIDIRECTIONAL='TRUE';
      INPUT_LOAD='(-0.01,0.01)';
      OUTPUT_LOAD='(1.0,-1.0)';
      PINUSE='BI';
    'DDR1_DQS_DN'<12>:
      PIN_NUMBER='(0,0,0,B73,0,0,0,0,0,0,0,0,0,0,0,0,0,0,0,0,0,0,0,0,0,0,0,0,0,0~
)';
      BIDIRECTIONAL='TRUE';
      INPUT_LOAD='(-0.01,0.01)';
      OUTPUT_LOAD='(1.0,-1.0)';
      PINUSE='BI';
    'DDR1_DQS_DN'<11>:
      PIN_NUMBER='(0,0,0,D79,0,0,0,0,0,0,0,0,0,0,0,0,0,0,0,0,0,0,0,0,0,0,0,0,0,0~
)';
      BIDIRECTIONAL='TRUE';
      INPUT_LOAD='(-0.01,0.01)';
      OUTPUT_LOAD='(1.0,-1.0)';
      PINUSE='BI';
    'DDR1_DQS_DN'<10>:
      PIN_NUMBER='(0,0,0,AG82,0,0,0,0,0,0,0,0,0,0,0,0,0,0,0,0,0,0,0,0,0,0,0,0,0,~
0)';
      BIDIRECTIONAL='TRUE';
      INPUT_LOAD='(-0.01,0.01)';
      OUTPUT_LOAD='(1.0,-1.0)';
      PINUSE='BI';
    'DDR1_DQS_DN'<9>:
      PIN_NUMBER='(0,0,0,AU82,0,0,0,0,0,0,0,0,0,0,0,0,0,0,0,0,0,0,0,0,0,0,0,0,0,~
0)';
      BIDIRECTIONAL='TRUE';
      INPUT_LOAD='(-0.01,0.01)';
      OUTPUT_LOAD='(1.0,-1.0)';
      PINUSE='BI';
    'DDR1_DQS_DN'<8>:
      PIN_NUMBER='(0,0,0,N68,0,0,0,0,0,0,0,0,0,0,0,0,0,0,0,0,0,0,0,0,0,0,0,0,0,0~
)';
      BIDIRECTIONAL='TRUE';
      INPUT_LOAD='(-0.01,0.01)';
      OUTPUT_LOAD='(1.0,-1.0)';
      PINUSE='BI';
    'DDR1_DQS_DN'<7>:
      PIN_NUMBER='(0,0,0,AB27,0,0,0,0,0,0,0,0,0,0,0,0,0,0,0,0,0,0,0,0,0,0,0,0,0,~
0)';
      BIDIRECTIONAL='TRUE';
      INPUT_LOAD='(-0.01,0.01)';
      OUTPUT_LOAD='(1.0,-1.0)';
      PINUSE='BI';
    'DDR1_DQS_DN'<6>:
      PIN_NUMBER='(0,0,0,G28,0,0,0,0,0,0,0,0,0,0,0,0,0,0,0,0,0,0,0,0,0,0,0,0,0,0~
)';
      BIDIRECTIONAL='TRUE';
      INPUT_LOAD='(-0.01,0.01)';
      OUTPUT_LOAD='(1.0,-1.0)';
      PINUSE='BI';
    'DDR1_DQS_DN'<5>:
      PIN_NUMBER='(0,0,0,G34,0,0,0,0,0,0,0,0,0,0,0,0,0,0,0,0,0,0,0,0,0,0,0,0,0,0~
)';
      BIDIRECTIONAL='TRUE';
      INPUT_LOAD='(-0.01,0.01)';
      OUTPUT_LOAD='(1.0,-1.0)';
      PINUSE='BI';
    'DDR1_DQS_DN'<4>:
      PIN_NUMBER='(0,0,0,N42,0,0,0,0,0,0,0,0,0,0,0,0,0,0,0,0,0,0,0,0,0,0,0,0,0,0~
)';
      BIDIRECTIONAL='TRUE';
      INPUT_LOAD='(-0.01,0.01)';
      OUTPUT_LOAD='(1.0,-1.0)';
      PINUSE='BI';
    'DDR1_DQS_DN'<3>:
      PIN_NUMBER='(0,0,0,H73,0,0,0,0,0,0,0,0,0,0,0,0,0,0,0,0,0,0,0,0,0,0,0,0,0,0~
)';
      BIDIRECTIONAL='TRUE';
      INPUT_LOAD='(-0.01,0.01)';
      OUTPUT_LOAD='(1.0,-1.0)';
      PINUSE='BI';
    'DDR1_DQS_DN'<2>:
      PIN_NUMBER='(0,0,0,K79,0,0,0,0,0,0,0,0,0,0,0,0,0,0,0,0,0,0,0,0,0,0,0,0,0,0~
)';
      BIDIRECTIONAL='TRUE';
      INPUT_LOAD='(-0.01,0.01)';
      OUTPUT_LOAD='(1.0,-1.0)';
      PINUSE='BI';
    'DDR1_DQS_DN'<1>:
      PIN_NUMBER='(0,0,0,AD79,0,0,0,0,0,0,0,0,0,0,0,0,0,0,0,0,0,0,0,0,0,0,0,0,0,~
0)';
      BIDIRECTIONAL='TRUE';
      INPUT_LOAD='(-0.01,0.01)';
      OUTPUT_LOAD='(1.0,-1.0)';
      PINUSE='BI';
    'DDR1_DQS_DN'<0>:
      PIN_NUMBER='(0,0,0,AP79,0,0,0,0,0,0,0,0,0,0,0,0,0,0,0,0,0,0,0,0,0,0,0,0,0,~
0)';
      BIDIRECTIONAL='TRUE';
      INPUT_LOAD='(-0.01,0.01)';
      OUTPUT_LOAD='(1.0,-1.0)';
      PINUSE='BI';
    'DDR1_DQS_DP'<17>:
      PIN_NUMBER='(0,0,0,J68,0,0,0,0,0,0,0,0,0,0,0,0,0,0,0,0,0,0,0,0,0,0,0,0,0,0~
)';
      BIDIRECTIONAL='TRUE';
      INPUT_LOAD='(-0.01,0.01)';
      OUTPUT_LOAD='(1.0,-1.0)';
      PINUSE='BI';
    'DDR1_DQS_DP'<16>:
      PIN_NUMBER='(0,0,0,V27,0,0,0,0,0,0,0,0,0,0,0,0,0,0,0,0,0,0,0,0,0,0,0,0,0,0~
)';
      BIDIRECTIONAL='TRUE';
      INPUT_LOAD='(-0.01,0.01)';
      OUTPUT_LOAD='(1.0,-1.0)';
      PINUSE='BI';
    'DDR1_DQS_DP'<15>:
      PIN_NUMBER='(0,0,0,C28,0,0,0,0,0,0,0,0,0,0,0,0,0,0,0,0,0,0,0,0,0,0,0,0,0,0~
)';
      BIDIRECTIONAL='TRUE';
      INPUT_LOAD='(-0.01,0.01)';
      OUTPUT_LOAD='(1.0,-1.0)';
      PINUSE='BI';
    'DDR1_DQS_DP'<14>:
      PIN_NUMBER='(0,0,0,C34,0,0,0,0,0,0,0,0,0,0,0,0,0,0,0,0,0,0,0,0,0,0,0,0,0,0~
)';
      BIDIRECTIONAL='TRUE';
      INPUT_LOAD='(-0.01,0.01)';
      OUTPUT_LOAD='(1.0,-1.0)';
      PINUSE='BI';
    'DDR1_DQS_DP'<13>:
      PIN_NUMBER='(0,0,0,L42,0,0,0,0,0,0,0,0,0,0,0,0,0,0,0,0,0,0,0,0,0,0,0,0,0,0~
)';
      BIDIRECTIONAL='TRUE';
      INPUT_LOAD='(-0.01,0.01)';
      OUTPUT_LOAD='(1.0,-1.0)';
      PINUSE='BI';
    'DDR1_DQS_DP'<12>:
      PIN_NUMBER='(0,0,0,D73,0,0,0,0,0,0,0,0,0,0,0,0,0,0,0,0,0,0,0,0,0,0,0,0,0,0~
)';
      BIDIRECTIONAL='TRUE';
      INPUT_LOAD='(-0.01,0.01)';
      OUTPUT_LOAD='(1.0,-1.0)';
      PINUSE='BI';
    'DDR1_DQS_DP'<11>:
      PIN_NUMBER='(0,0,0,F79,0,0,0,0,0,0,0,0,0,0,0,0,0,0,0,0,0,0,0,0,0,0,0,0,0,0~
)';
      BIDIRECTIONAL='TRUE';
      INPUT_LOAD='(-0.01,0.01)';
      OUTPUT_LOAD='(1.0,-1.0)';
      PINUSE='BI';
    'DDR1_DQS_DP'<10>:
      PIN_NUMBER='(0,0,0,AF81,0,0,0,0,0,0,0,0,0,0,0,0,0,0,0,0,0,0,0,0,0,0,0,0,0,~
0)';
      BIDIRECTIONAL='TRUE';
      INPUT_LOAD='(-0.01,0.01)';
      OUTPUT_LOAD='(1.0,-1.0)';
      PINUSE='BI';
    'DDR1_DQS_DP'<9>:
      PIN_NUMBER='(0,0,0,AT81,0,0,0,0,0,0,0,0,0,0,0,0,0,0,0,0,0,0,0,0,0,0,0,0,0,~
0)';
      BIDIRECTIONAL='TRUE';
      INPUT_LOAD='(-0.01,0.01)';
      OUTPUT_LOAD='(1.0,-1.0)';
      PINUSE='BI';
    'DDR1_DQS_DP'<8>:
      PIN_NUMBER='(0,0,0,L68,0,0,0,0,0,0,0,0,0,0,0,0,0,0,0,0,0,0,0,0,0,0,0,0,0,0~
)';
      BIDIRECTIONAL='TRUE';
      INPUT_LOAD='(-0.01,0.01)';
      OUTPUT_LOAD='(1.0,-1.0)';
      PINUSE='BI';
    'DDR1_DQS_DP'<7>:
      PIN_NUMBER='(0,0,0,Y27,0,0,0,0,0,0,0,0,0,0,0,0,0,0,0,0,0,0,0,0,0,0,0,0,0,0~
)';
      BIDIRECTIONAL='TRUE';
      INPUT_LOAD='(-0.01,0.01)';
      OUTPUT_LOAD='(1.0,-1.0)';
      PINUSE='BI';
    'DDR1_DQS_DP'<6>:
      PIN_NUMBER='(0,0,0,E28,0,0,0,0,0,0,0,0,0,0,0,0,0,0,0,0,0,0,0,0,0,0,0,0,0,0~
)';
      BIDIRECTIONAL='TRUE';
      INPUT_LOAD='(-0.01,0.01)';
      OUTPUT_LOAD='(1.0,-1.0)';
      PINUSE='BI';
    'DDR1_DQS_DP'<5>:
      PIN_NUMBER='(0,0,0,E34,0,0,0,0,0,0,0,0,0,0,0,0,0,0,0,0,0,0,0,0,0,0,0,0,0,0~
)';
      BIDIRECTIONAL='TRUE';
      INPUT_LOAD='(-0.01,0.01)';
      OUTPUT_LOAD='(1.0,-1.0)';
      PINUSE='BI';
    'DDR1_DQS_DP'<4>:
      PIN_NUMBER='(0,0,0,R42,0,0,0,0,0,0,0,0,0,0,0,0,0,0,0,0,0,0,0,0,0,0,0,0,0,0~
)';
      BIDIRECTIONAL='TRUE';
      INPUT_LOAD='(-0.01,0.01)';
      OUTPUT_LOAD='(1.0,-1.0)';
      PINUSE='BI';
    'DDR1_DQS_DP'<3>:
      PIN_NUMBER='(0,0,0,F73,0,0,0,0,0,0,0,0,0,0,0,0,0,0,0,0,0,0,0,0,0,0,0,0,0,0~
)';
      BIDIRECTIONAL='TRUE';
      INPUT_LOAD='(-0.01,0.01)';
      OUTPUT_LOAD='(1.0,-1.0)';
      PINUSE='BI';
    'DDR1_DQS_DP'<2>:
      PIN_NUMBER='(0,0,0,H79,0,0,0,0,0,0,0,0,0,0,0,0,0,0,0,0,0,0,0,0,0,0,0,0,0,0~
)';
      BIDIRECTIONAL='TRUE';
      INPUT_LOAD='(-0.01,0.01)';
      OUTPUT_LOAD='(1.0,-1.0)';
      PINUSE='BI';
    'DDR1_DQS_DP'<1>:
      PIN_NUMBER='(0,0,0,AE80,0,0,0,0,0,0,0,0,0,0,0,0,0,0,0,0,0,0,0,0,0,0,0,0,0,~
0)';
      BIDIRECTIONAL='TRUE';
      INPUT_LOAD='(-0.01,0.01)';
      OUTPUT_LOAD='(1.0,-1.0)';
      PINUSE='BI';
    'DDR1_DQS_DP'<0>:
      PIN_NUMBER='(0,0,0,AR80,0,0,0,0,0,0,0,0,0,0,0,0,0,0,0,0,0,0,0,0,0,0,0,0,0,~
0)';
      BIDIRECTIONAL='TRUE';
      INPUT_LOAD='(-0.01,0.01)';
      OUTPUT_LOAD='(1.0,-1.0)';
      PINUSE='BI';
    'DDR1_ECC'<7>:
      PIN_NUMBER='(0,0,0,M67,0,0,0,0,0,0,0,0,0,0,0,0,0,0,0,0,0,0,0,0,0,0,0,0,0,0~
)';
      BIDIRECTIONAL='TRUE';
      INPUT_LOAD='(-0.01,0.01)';
      OUTPUT_LOAD='(1.0,-1.0)';
      PINUSE='BI';
    'DDR1_ECC'<6>:
      PIN_NUMBER='(0,0,0,H67,0,0,0,0,0,0,0,0,0,0,0,0,0,0,0,0,0,0,0,0,0,0,0,0,0,0~
)';
      BIDIRECTIONAL='TRUE';
      INPUT_LOAD='(-0.01,0.01)';
      OUTPUT_LOAD='(1.0,-1.0)';
      PINUSE='BI';
    'DDR1_ECC'<5>:
      PIN_NUMBER='(0,0,0,M69,0,0,0,0,0,0,0,0,0,0,0,0,0,0,0,0,0,0,0,0,0,0,0,0,0,0~
)';
      BIDIRECTIONAL='TRUE';
      INPUT_LOAD='(-0.01,0.01)';
      OUTPUT_LOAD='(1.0,-1.0)';
      PINUSE='BI';
    'DDR1_ECC'<4>:
      PIN_NUMBER='(0,0,0,L70,0,0,0,0,0,0,0,0,0,0,0,0,0,0,0,0,0,0,0,0,0,0,0,0,0,0~
)';
      BIDIRECTIONAL='TRUE';
      INPUT_LOAD='(-0.01,0.01)';
      OUTPUT_LOAD='(1.0,-1.0)';
      PINUSE='BI';
    'DDR1_ECC'<3>:
      PIN_NUMBER='(0,0,0,L66,0,0,0,0,0,0,0,0,0,0,0,0,0,0,0,0,0,0,0,0,0,0,0,0,0,0~
)';
      BIDIRECTIONAL='TRUE';
      INPUT_LOAD='(-0.01,0.01)';
      OUTPUT_LOAD='(1.0,-1.0)';
      PINUSE='BI';
    'DDR1_ECC'<2>:
      PIN_NUMBER='(0,0,0,J66,0,0,0,0,0,0,0,0,0,0,0,0,0,0,0,0,0,0,0,0,0,0,0,0,0,0~
)';
      BIDIRECTIONAL='TRUE';
      INPUT_LOAD='(-0.01,0.01)';
      OUTPUT_LOAD='(1.0,-1.0)';
      PINUSE='BI';
    'DDR1_ECC'<1>:
      PIN_NUMBER='(0,0,0,H69,0,0,0,0,0,0,0,0,0,0,0,0,0,0,0,0,0,0,0,0,0,0,0,0,0,0~
)';
      BIDIRECTIONAL='TRUE';
      INPUT_LOAD='(-0.01,0.01)';
      OUTPUT_LOAD='(1.0,-1.0)';
      PINUSE='BI';
    'DDR1_ECC'<0>:
      PIN_NUMBER='(0,0,0,J70,0,0,0,0,0,0,0,0,0,0,0,0,0,0,0,0,0,0,0,0,0,0,0,0,0,0~
)';
      BIDIRECTIONAL='TRUE';
      INPUT_LOAD='(-0.01,0.01)';
      OUTPUT_LOAD='(1.0,-1.0)';
      PINUSE='BI';
    'DDR1_MA'<17>:
      PIN_NUMBER='(0,0,0,N48,0,0,0,0,0,0,0,0,0,0,0,0,0,0,0,0,0,0,0,0,0,0,0,0,0,0~
)';
      OUTPUT_LOAD='(1.0,-1.0)';
      PINUSE='OUT';
    'DDR1_MA'<16>:
      PIN_NUMBER='(0,0,0,R52,0,0,0,0,0,0,0,0,0,0,0,0,0,0,0,0,0,0,0,0,0,0,0,0,0,0~
)';
      OUTPUT_LOAD='(1.0,-1.0)';
      PINUSE='OUT';
    'DDR1_MA'<15>:
      PIN_NUMBER='(0,0,0,N52,0,0,0,0,0,0,0,0,0,0,0,0,0,0,0,0,0,0,0,0,0,0,0,0,0,0~
)';
      OUTPUT_LOAD='(1.0,-1.0)';
      PINUSE='OUT';
    'DDR1_MA'<14>:
      PIN_NUMBER='(0,0,0,T51,0,0,0,0,0,0,0,0,0,0,0,0,0,0,0,0,0,0,0,0,0,0,0,0,0,0~
)';
      OUTPUT_LOAD='(1.0,-1.0)';
      PINUSE='OUT';
    'DDR1_MA'<13>:
      PIN_NUMBER='(0,0,0,M51,0,0,0,0,0,0,0,0,0,0,0,0,0,0,0,0,0,0,0,0,0,0,0,0,0,0~
)';
      OUTPUT_LOAD='(1.0,-1.0)';
      PINUSE='OUT';
    'DDR1_MA'<12>:
      PIN_NUMBER='(0,0,0,T61,0,0,0,0,0,0,0,0,0,0,0,0,0,0,0,0,0,0,0,0,0,0,0,0,0,0~
)';
      OUTPUT_LOAD='(1.0,-1.0)';
      PINUSE='OUT';
    'DDR1_MA'<11>:
      PIN_NUMBER='(0,0,0,R60,0,0,0,0,0,0,0,0,0,0,0,0,0,0,0,0,0,0,0,0,0,0,0,0,0,0~
)';
      OUTPUT_LOAD='(1.0,-1.0)';
      PINUSE='OUT';
    'DDR1_MA'<10>:
      PIN_NUMBER='(0,0,0,M55,0,0,0,0,0,0,0,0,0,0,0,0,0,0,0,0,0,0,0,0,0,0,0,0,0,0~
)';
      OUTPUT_LOAD='(1.0,-1.0)';
      PINUSE='OUT';
    'DDR1_MA'<9>:
      PIN_NUMBER='(0,0,0,K59,0,0,0,0,0,0,0,0,0,0,0,0,0,0,0,0,0,0,0,0,0,0,0,0,0,0~
)';
      OUTPUT_LOAD='(1.0,-1.0)';
      PINUSE='OUT';
    'DDR1_MA'<8>:
      PIN_NUMBER='(0,0,0,W60,0,0,0,0,0,0,0,0,0,0,0,0,0,0,0,0,0,0,0,0,0,0,0,0,0,0~
)';
      OUTPUT_LOAD='(1.0,-1.0)';
      PINUSE='OUT';
    'DDR1_MA'<7>:
      PIN_NUMBER='(0,0,0,V61,0,0,0,0,0,0,0,0,0,0,0,0,0,0,0,0,0,0,0,0,0,0,0,0,0,0~
)';
      OUTPUT_LOAD='(1.0,-1.0)';
      PINUSE='OUT';
    'DDR1_MA'<6>:
      PIN_NUMBER='(0,0,0,T59,0,0,0,0,0,0,0,0,0,0,0,0,0,0,0,0,0,0,0,0,0,0,0,0,0,0~
)';
      OUTPUT_LOAD='(1.0,-1.0)';
      PINUSE='OUT';
    'DDR1_MA'<5>:
      PIN_NUMBER='(0,0,0,R58,0,0,0,0,0,0,0,0,0,0,0,0,0,0,0,0,0,0,0,0,0,0,0,0,0,0~
)';
      OUTPUT_LOAD='(1.0,-1.0)';
      PINUSE='OUT';
    'DDR1_MA'<4>:
      PIN_NUMBER='(0,0,0,M59,0,0,0,0,0,0,0,0,0,0,0,0,0,0,0,0,0,0,0,0,0,0,0,0,0,0~
)';
      OUTPUT_LOAD='(1.0,-1.0)';
      PINUSE='OUT';
    'DDR1_MA'<3>:
      PIN_NUMBER='(0,0,0,N58,0,0,0,0,0,0,0,0,0,0,0,0,0,0,0,0,0,0,0,0,0,0,0,0,0,0~
)';
      OUTPUT_LOAD='(1.0,-1.0)';
      PINUSE='OUT';
    'DDR1_MA'<2>:
      PIN_NUMBER='(0,0,0,K57,0,0,0,0,0,0,0,0,0,0,0,0,0,0,0,0,0,0,0,0,0,0,0,0,0,0~
)';
      OUTPUT_LOAD='(1.0,-1.0)';
      PINUSE='OUT';
    'DDR1_MA'<1>:
      PIN_NUMBER='(0,0,0,J58,0,0,0,0,0,0,0,0,0,0,0,0,0,0,0,0,0,0,0,0,0,0,0,0,0,0~
)';
      OUTPUT_LOAD='(1.0,-1.0)';
      PINUSE='OUT';
    'DDR1_MA'<0>:
      PIN_NUMBER='(0,0,0,J52,0,0,0,0,0,0,0,0,0,0,0,0,0,0,0,0,0,0,0,0,0,0,0,0,0,0~
)';
      OUTPUT_LOAD='(1.0,-1.0)';
      PINUSE='OUT';
    'DDR1_ODT'<3>:
      PIN_NUMBER='(0,0,0,T47,0,0,0,0,0,0,0,0,0,0,0,0,0,0,0,0,0,0,0,0,0,0,0,0,0,0~
)';
      OUTPUT_LOAD='(1.0,-1.0)';
      PINUSE='OUT';
    'DDR1_ODT'<2>:
      PIN_NUMBER='(0,0,0,M49,0,0,0,0,0,0,0,0,0,0,0,0,0,0,0,0,0,0,0,0,0,0,0,0,0,0~
)';
      OUTPUT_LOAD='(1.0,-1.0)';
      PINUSE='OUT';
    'DDR1_ODT'<1>:
      PIN_NUMBER='(0,0,0,R48,0,0,0,0,0,0,0,0,0,0,0,0,0,0,0,0,0,0,0,0,0,0,0,0,0,0~
)';
      OUTPUT_LOAD='(1.0,-1.0)';
      PINUSE='OUT';
    'DDR1_ODT'<0>:
      PIN_NUMBER='(0,0,0,N50,0,0,0,0,0,0,0,0,0,0,0,0,0,0,0,0,0,0,0,0,0,0,0,0,0,0~
)';
      OUTPUT_LOAD='(1.0,-1.0)';
      PINUSE='OUT';
    'DDR1_PAR':
      PIN_NUMBER='(0,0,0,K53,0,0,0,0,0,0,0,0,0,0,0,0,0,0,0,0,0,0,0,0,0,0,0,0,0,0~
)';
      OUTPUT_LOAD='(1.0,-1.0)';
      PINUSE='OUT';
    'DDR2_ACT_N':
      PIN_NUMBER='(0,0,0,0,AB61,0,0,0,0,0,0,0,0,0,0,0,0,0,0,0,0,0,0,0,0,0,0,0,0,~
0)';
      OUTPUT_LOAD='(1.0,-1.0)';
      PINUSE='OUT';
    'DDR2_ALERT_N':
      PIN_NUMBER='(0,0,0,0,AD61,0,0,0,0,0,0,0,0,0,0,0,0,0,0,0,0,0,0,0,0,0,0,0,0,~
0)';
      INPUT_LOAD='(-0.01,0.01)';
      PINUSE='IN';
    'DDR2_BA'<1>:
      PIN_NUMBER='(0,0,0,0,AE56,0,0,0,0,0,0,0,0,0,0,0,0,0,0,0,0,0,0,0,0,0,0,0,0,~
0)';
      OUTPUT_LOAD='(1.0,-1.0)';
      PINUSE='OUT';
    'DDR2_BA'<0>:
      PIN_NUMBER='(0,0,0,0,W52,0,0,0,0,0,0,0,0,0,0,0,0,0,0,0,0,0,0,0,0,0,0,0,0,0~
)';
      OUTPUT_LOAD='(1.0,-1.0)';
      PINUSE='OUT';
    'DDR2_BG'<1>:
      PIN_NUMBER='(0,0,0,0,AE62,0,0,0,0,0,0,0,0,0,0,0,0,0,0,0,0,0,0,0,0,0,0,0,0,~
0)';
      OUTPUT_LOAD='(1.0,-1.0)';
      PINUSE='OUT';
    'DDR2_BG'<0>:
      PIN_NUMBER='(0,0,0,0,AA60,0,0,0,0,0,0,0,0,0,0,0,0,0,0,0,0,0,0,0,0,0,0,0,0,~
0)';
      OUTPUT_LOAD='(1.0,-1.0)';
      PINUSE='OUT';
    'DDR2_CAVREF':
      PIN_NUMBER='(AH63,0,0,0,0,0,0,0,0,0,0,0,0,0,0,0,0,0,0,0,0,0,0,0,0,0,0,0,0,~
0)';
      OUTPUT_LOAD='(1.0,-1.0)';
      PINUSE='OUT';
    'DDR2_CID'<2>:
      PIN_NUMBER='(0,0,0,0,AB45,0,0,0,0,0,0,0,0,0,0,0,0,0,0,0,0,0,0,0,0,0,0,0,0,~
0)';
      OUTPUT_LOAD='(1.0,-1.0)';
      PINUSE='OUT';
    'DDR2_CKE'<3>:
      PIN_NUMBER='(0,0,0,0,AB63,0,0,0,0,0,0,0,0,0,0,0,0,0,0,0,0,0,0,0,0,0,0,0,0,~
0)';
      OUTPUT_LOAD='(1.0,-1.0)';
      PINUSE='OUT';
    'DDR2_CKE'<2>:
      PIN_NUMBER='(0,0,0,0,V63,0,0,0,0,0,0,0,0,0,0,0,0,0,0,0,0,0,0,0,0,0,0,0,0,0~
)';
      OUTPUT_LOAD='(1.0,-1.0)';
      PINUSE='OUT';
    'DDR2_CKE'<1>:
      PIN_NUMBER='(0,0,0,0,AD63,0,0,0,0,0,0,0,0,0,0,0,0,0,0,0,0,0,0,0,0,0,0,0,0,~
0)';
      OUTPUT_LOAD='(1.0,-1.0)';
      PINUSE='OUT';
    'DDR2_CKE'<0>:
      PIN_NUMBER='(0,0,0,0,AA62,0,0,0,0,0,0,0,0,0,0,0,0,0,0,0,0,0,0,0,0,0,0,0,0,~
0)';
      OUTPUT_LOAD='(1.0,-1.0)';
      PINUSE='OUT';
    'DDR2_CLK_DN'<3>:
      PIN_NUMBER='(0,0,0,0,W56,0,0,0,0,0,0,0,0,0,0,0,0,0,0,0,0,0,0,0,0,0,0,0,0,0~
)';
      OUTPUT_LOAD='(1.0,-1.0)';
      PINUSE='OUT';
    'DDR2_CLK_DN'<2>:
      PIN_NUMBER='(0,0,0,0,AA56,0,0,0,0,0,0,0,0,0,0,0,0,0,0,0,0,0,0,0,0,0,0,0,0,~
0)';
      OUTPUT_LOAD='(1.0,-1.0)';
      PINUSE='OUT';
    'DDR2_CLK_DN'<1>:
      PIN_NUMBER='(0,0,0,0,W54,0,0,0,0,0,0,0,0,0,0,0,0,0,0,0,0,0,0,0,0,0,0,0,0,0~
)';
      OUTPUT_LOAD='(1.0,-1.0)';
      PINUSE='OUT';
    'DDR2_CLK_DN'<0>:
      PIN_NUMBER='(0,0,0,0,AA54,0,0,0,0,0,0,0,0,0,0,0,0,0,0,0,0,0,0,0,0,0,0,0,0,~
0)';
      OUTPUT_LOAD='(1.0,-1.0)';
      PINUSE='OUT';
    'DDR2_CLK_DP'<3>:
      PIN_NUMBER='(0,0,0,0,V57,0,0,0,0,0,0,0,0,0,0,0,0,0,0,0,0,0,0,0,0,0,0,0,0,0~
)';
      OUTPUT_LOAD='(1.0,-1.0)';
      PINUSE='OUT';
    'DDR2_CLK_DP'<2>:
      PIN_NUMBER='(0,0,0,0,AB57,0,0,0,0,0,0,0,0,0,0,0,0,0,0,0,0,0,0,0,0,0,0,0,0,~
0)';
      OUTPUT_LOAD='(1.0,-1.0)';
      PINUSE='OUT';
    'DDR2_CLK_DP'<1>:
      PIN_NUMBER='(0,0,0,0,V55,0,0,0,0,0,0,0,0,0,0,0,0,0,0,0,0,0,0,0,0,0,0,0,0,0~
)';
      OUTPUT_LOAD='(1.0,-1.0)';
      PINUSE='OUT';
    'DDR2_CLK_DP'<0>:
      PIN_NUMBER='(0,0,0,0,AB55,0,0,0,0,0,0,0,0,0,0,0,0,0,0,0,0,0,0,0,0,0,0,0,0,~
0)';
      OUTPUT_LOAD='(1.0,-1.0)';
      PINUSE='OUT';
    'DDR2_CS_N'<7>:
      PIN_NUMBER='(0,0,0,0,V45,0,0,0,0,0,0,0,0,0,0,0,0,0,0,0,0,0,0,0,0,0,0,0,0,0~
)';
      OUTPUT_LOAD='(1.0,-1.0)';
      PINUSE='OUT';
    'DDR2_CS_N'<6>:
      PIN_NUMBER='(0,0,0,0,T45,0,0,0,0,0,0,0,0,0,0,0,0,0,0,0,0,0,0,0,0,0,0,0,0,0~
)';
      OUTPUT_LOAD='(1.0,-1.0)';
      PINUSE='OUT';
    'DDR2_CS_N'<5>:
      PIN_NUMBER='(0,0,0,0,W48,0,0,0,0,0,0,0,0,0,0,0,0,0,0,0,0,0,0,0,0,0,0,0,0,0~
)';
      OUTPUT_LOAD='(1.0,-1.0)';
      PINUSE='OUT';
    'DDR2_CS_N'<4>:
      PIN_NUMBER='(0,0,0,0,AB51,0,0,0,0,0,0,0,0,0,0,0,0,0,0,0,0,0,0,0,0,0,0,0,0,~
0)';
      OUTPUT_LOAD='(1.0,-1.0)';
      PINUSE='OUT';
    'DDR2_CS_N'<3>:
      PIN_NUMBER='(0,0,0,0,AA46,0,0,0,0,0,0,0,0,0,0,0,0,0,0,0,0,0,0,0,0,0,0,0,0,~
0)';
      OUTPUT_LOAD='(1.0,-1.0)';
      PINUSE='OUT';
    'DDR2_CS_N'<2>:
      PIN_NUMBER='(0,0,0,0,W46,0,0,0,0,0,0,0,0,0,0,0,0,0,0,0,0,0,0,0,0,0,0,0,0,0~
)';
      OUTPUT_LOAD='(1.0,-1.0)';
      PINUSE='OUT';
    'DDR2_CS_N'<1>:
      PIN_NUMBER='(0,0,0,0,AB49,0,0,0,0,0,0,0,0,0,0,0,0,0,0,0,0,0,0,0,0,0,0,0,0,~
0)';
      OUTPUT_LOAD='(1.0,-1.0)';
      PINUSE='OUT';
    'DDR2_CS_N'<0>:
      PIN_NUMBER='(0,0,0,0,V51,0,0,0,0,0,0,0,0,0,0,0,0,0,0,0,0,0,0,0,0,0,0,0,0,0~
)';
      OUTPUT_LOAD='(1.0,-1.0)';
      PINUSE='OUT';
    'DDR2_DQ'<63>:
      PIN_NUMBER='(0,0,0,0,AH23,0,0,0,0,0,0,0,0,0,0,0,0,0,0,0,0,0,0,0,0,0,0,0,0,~
0)';
      BIDIRECTIONAL='TRUE';
      INPUT_LOAD='(-0.01,0.01)';
      OUTPUT_LOAD='(1.0,-1.0)';
      PINUSE='BI';
    'DDR2_DQ'<62>:
      PIN_NUMBER='(0,0,0,0,AD23,0,0,0,0,0,0,0,0,0,0,0,0,0,0,0,0,0,0,0,0,0,0,0,0,~
0)';
      BIDIRECTIONAL='TRUE';
      INPUT_LOAD='(-0.01,0.01)';
      OUTPUT_LOAD='(1.0,-1.0)';
      PINUSE='BI';
    'DDR2_DQ'<61>:
      PIN_NUMBER='(0,0,0,0,AG26,0,0,0,0,0,0,0,0,0,0,0,0,0,0,0,0,0,0,0,0,0,0,0,0,~
0)';
      BIDIRECTIONAL='TRUE';
      INPUT_LOAD='(-0.01,0.01)';
      OUTPUT_LOAD='(1.0,-1.0)';
      PINUSE='BI';
    'DDR2_DQ'<60>:
      PIN_NUMBER='(0,0,0,0,AE26,0,0,0,0,0,0,0,0,0,0,0,0,0,0,0,0,0,0,0,0,0,0,0,0,~
0)';
      BIDIRECTIONAL='TRUE';
      INPUT_LOAD='(-0.01,0.01)';
      OUTPUT_LOAD='(1.0,-1.0)';
      PINUSE='BI';
    'DDR2_DQ'<59>:
      PIN_NUMBER='(0,0,0,0,AG22,0,0,0,0,0,0,0,0,0,0,0,0,0,0,0,0,0,0,0,0,0,0,0,0,~
0)';
      BIDIRECTIONAL='TRUE';
      INPUT_LOAD='(-0.01,0.01)';
      OUTPUT_LOAD='(1.0,-1.0)';
      PINUSE='BI';
    'DDR2_DQ'<58>:
      PIN_NUMBER='(0,0,0,0,AE22,0,0,0,0,0,0,0,0,0,0,0,0,0,0,0,0,0,0,0,0,0,0,0,0,~
0)';
      BIDIRECTIONAL='TRUE';
      INPUT_LOAD='(-0.01,0.01)';
      OUTPUT_LOAD='(1.0,-1.0)';
      PINUSE='BI';
    'DDR2_DQ'<57>:
      PIN_NUMBER='(0,0,0,0,AH25,0,0,0,0,0,0,0,0,0,0,0,0,0,0,0,0,0,0,0,0,0,0,0,0,~
0)';
      BIDIRECTIONAL='TRUE';
      INPUT_LOAD='(-0.01,0.01)';
      OUTPUT_LOAD='(1.0,-1.0)';
      PINUSE='BI';
    'DDR2_DQ'<56>:
      PIN_NUMBER='(0,0,0,0,AD25,0,0,0,0,0,0,0,0,0,0,0,0,0,0,0,0,0,0,0,0,0,0,0,0,~
0)';
      BIDIRECTIONAL='TRUE';
      INPUT_LOAD='(-0.01,0.01)';
      OUTPUT_LOAD='(1.0,-1.0)';
      PINUSE='BI';
    'DDR2_DQ'<55>:
      PIN_NUMBER='(0,0,0,0,AH29,0,0,0,0,0,0,0,0,0,0,0,0,0,0,0,0,0,0,0,0,0,0,0,0,~
0)';
      BIDIRECTIONAL='TRUE';
      INPUT_LOAD='(-0.01,0.01)';
      OUTPUT_LOAD='(1.0,-1.0)';
      PINUSE='BI';
    'DDR2_DQ'<54>:
      PIN_NUMBER='(0,0,0,0,AD29,0,0,0,0,0,0,0,0,0,0,0,0,0,0,0,0,0,0,0,0,0,0,0,0,~
0)';
      BIDIRECTIONAL='TRUE';
      INPUT_LOAD='(-0.01,0.01)';
      OUTPUT_LOAD='(1.0,-1.0)';
      PINUSE='BI';
    'DDR2_DQ'<53>:
      PIN_NUMBER='(0,0,0,0,AG32,0,0,0,0,0,0,0,0,0,0,0,0,0,0,0,0,0,0,0,0,0,0,0,0,~
0)';
      BIDIRECTIONAL='TRUE';
      INPUT_LOAD='(-0.01,0.01)';
      OUTPUT_LOAD='(1.0,-1.0)';
      PINUSE='BI';
    'DDR2_DQ'<52>:
      PIN_NUMBER='(0,0,0,0,AE32,0,0,0,0,0,0,0,0,0,0,0,0,0,0,0,0,0,0,0,0,0,0,0,0,~
0)';
      BIDIRECTIONAL='TRUE';
      INPUT_LOAD='(-0.01,0.01)';
      OUTPUT_LOAD='(1.0,-1.0)';
      PINUSE='BI';
    'DDR2_DQ'<51>:
      PIN_NUMBER='(0,0,0,0,AG28,0,0,0,0,0,0,0,0,0,0,0,0,0,0,0,0,0,0,0,0,0,0,0,0,~
0)';
      BIDIRECTIONAL='TRUE';
      INPUT_LOAD='(-0.01,0.01)';
      OUTPUT_LOAD='(1.0,-1.0)';
      PINUSE='BI';
    'DDR2_DQ'<50>:
      PIN_NUMBER='(0,0,0,0,AE28,0,0,0,0,0,0,0,0,0,0,0,0,0,0,0,0,0,0,0,0,0,0,0,0,~
0)';
      BIDIRECTIONAL='TRUE';
      INPUT_LOAD='(-0.01,0.01)';
      OUTPUT_LOAD='(1.0,-1.0)';
      PINUSE='BI';
    'DDR2_DQ'<49>:
      PIN_NUMBER='(0,0,0,0,AH31,0,0,0,0,0,0,0,0,0,0,0,0,0,0,0,0,0,0,0,0,0,0,0,0,~
0)';
      BIDIRECTIONAL='TRUE';
      INPUT_LOAD='(-0.01,0.01)';
      OUTPUT_LOAD='(1.0,-1.0)';
      PINUSE='BI';
    'DDR2_DQ'<48>:
      PIN_NUMBER='(0,0,0,0,AD31,0,0,0,0,0,0,0,0,0,0,0,0,0,0,0,0,0,0,0,0,0,0,0,0,~
0)';
      BIDIRECTIONAL='TRUE';
      INPUT_LOAD='(-0.01,0.01)';
      OUTPUT_LOAD='(1.0,-1.0)';
      PINUSE='BI';
    'DDR2_DQ'<47>:
      PIN_NUMBER='(0,0,0,0,AA32,0,0,0,0,0,0,0,0,0,0,0,0,0,0,0,0,0,0,0,0,0,0,0,0,~
0)';
      BIDIRECTIONAL='TRUE';
      INPUT_LOAD='(-0.01,0.01)';
      OUTPUT_LOAD='(1.0,-1.0)';
      PINUSE='BI';
    'DDR2_DQ'<46>:
      PIN_NUMBER='(0,0,0,0,U32,0,0,0,0,0,0,0,0,0,0,0,0,0,0,0,0,0,0,0,0,0,0,0,0,0~
)';
      BIDIRECTIONAL='TRUE';
      INPUT_LOAD='(-0.01,0.01)';
      OUTPUT_LOAD='(1.0,-1.0)';
      PINUSE='BI';
    'DDR2_DQ'<45>:
      PIN_NUMBER='(0,0,0,0,Y35,0,0,0,0,0,0,0,0,0,0,0,0,0,0,0,0,0,0,0,0,0,0,0,0,0~
)';
      BIDIRECTIONAL='TRUE';
      INPUT_LOAD='(-0.01,0.01)';
      OUTPUT_LOAD='(1.0,-1.0)';
      PINUSE='BI';
    'DDR2_DQ'<44>:
      PIN_NUMBER='(0,0,0,0,V35,0,0,0,0,0,0,0,0,0,0,0,0,0,0,0,0,0,0,0,0,0,0,0,0,0~
)';
      BIDIRECTIONAL='TRUE';
      INPUT_LOAD='(-0.01,0.01)';
      OUTPUT_LOAD='(1.0,-1.0)';
      PINUSE='BI';
    'DDR2_DQ'<43>:
      PIN_NUMBER='(0,0,0,0,Y31,0,0,0,0,0,0,0,0,0,0,0,0,0,0,0,0,0,0,0,0,0,0,0,0,0~
)';
      BIDIRECTIONAL='TRUE';
      INPUT_LOAD='(-0.01,0.01)';
      OUTPUT_LOAD='(1.0,-1.0)';
      PINUSE='BI';
    'DDR2_DQ'<42>:
      PIN_NUMBER='(0,0,0,0,V31,0,0,0,0,0,0,0,0,0,0,0,0,0,0,0,0,0,0,0,0,0,0,0,0,0~
)';
      BIDIRECTIONAL='TRUE';
      INPUT_LOAD='(-0.01,0.01)';
      OUTPUT_LOAD='(1.0,-1.0)';
      PINUSE='BI';
    'DDR2_DQ'<41>:
      PIN_NUMBER='(0,0,0,0,AA34,0,0,0,0,0,0,0,0,0,0,0,0,0,0,0,0,0,0,0,0,0,0,0,0,~
0)';
      BIDIRECTIONAL='TRUE';
      INPUT_LOAD='(-0.01,0.01)';
      OUTPUT_LOAD='(1.0,-1.0)';
      PINUSE='BI';
    'DDR2_DQ'<40>:
      PIN_NUMBER='(0,0,0,0,U34,0,0,0,0,0,0,0,0,0,0,0,0,0,0,0,0,0,0,0,0,0,0,0,0,0~
)';
      BIDIRECTIONAL='TRUE';
      INPUT_LOAD='(-0.01,0.01)';
      OUTPUT_LOAD='(1.0,-1.0)';
      PINUSE='BI';
    'DDR2_DQ'<39>:
      PIN_NUMBER='(0,0,0,0,AA38,0,0,0,0,0,0,0,0,0,0,0,0,0,0,0,0,0,0,0,0,0,0,0,0,~
0)';
      BIDIRECTIONAL='TRUE';
      INPUT_LOAD='(-0.01,0.01)';
      OUTPUT_LOAD='(1.0,-1.0)';
      PINUSE='BI';
    'DDR2_DQ'<38>:
      PIN_NUMBER='(0,0,0,0,U38,0,0,0,0,0,0,0,0,0,0,0,0,0,0,0,0,0,0,0,0,0,0,0,0,0~
)';
      BIDIRECTIONAL='TRUE';
      INPUT_LOAD='(-0.01,0.01)';
      OUTPUT_LOAD='(1.0,-1.0)';
      PINUSE='BI';
    'DDR2_DQ'<37>:
      PIN_NUMBER='(0,0,0,0,Y41,0,0,0,0,0,0,0,0,0,0,0,0,0,0,0,0,0,0,0,0,0,0,0,0,0~
)';
      BIDIRECTIONAL='TRUE';
      INPUT_LOAD='(-0.01,0.01)';
      OUTPUT_LOAD='(1.0,-1.0)';
      PINUSE='BI';
    'DDR2_DQ'<36>:
      PIN_NUMBER='(0,0,0,0,V41,0,0,0,0,0,0,0,0,0,0,0,0,0,0,0,0,0,0,0,0,0,0,0,0,0~
)';
      BIDIRECTIONAL='TRUE';
      INPUT_LOAD='(-0.01,0.01)';
      OUTPUT_LOAD='(1.0,-1.0)';
      PINUSE='BI';
    'DDR2_DQ'<35>:
      PIN_NUMBER='(0,0,0,0,Y37,0,0,0,0,0,0,0,0,0,0,0,0,0,0,0,0,0,0,0,0,0,0,0,0,0~
)';
      BIDIRECTIONAL='TRUE';
      INPUT_LOAD='(-0.01,0.01)';
      OUTPUT_LOAD='(1.0,-1.0)';
      PINUSE='BI';
    'DDR2_DQ'<34>:
      PIN_NUMBER='(0,0,0,0,V37,0,0,0,0,0,0,0,0,0,0,0,0,0,0,0,0,0,0,0,0,0,0,0,0,0~
)';
      BIDIRECTIONAL='TRUE';
      INPUT_LOAD='(-0.01,0.01)';
      OUTPUT_LOAD='(1.0,-1.0)';
      PINUSE='BI';
    'DDR2_DQ'<33>:
      PIN_NUMBER='(0,0,0,0,AA40,0,0,0,0,0,0,0,0,0,0,0,0,0,0,0,0,0,0,0,0,0,0,0,0,~
0)';
      BIDIRECTIONAL='TRUE';
      INPUT_LOAD='(-0.01,0.01)';
      OUTPUT_LOAD='(1.0,-1.0)';
      PINUSE='BI';
    'DDR2_DQ'<32>:
      PIN_NUMBER='(0,0,0,0,U40,0,0,0,0,0,0,0,0,0,0,0,0,0,0,0,0,0,0,0,0,0,0,0,0,0~
)';
      BIDIRECTIONAL='TRUE';
      INPUT_LOAD='(-0.01,0.01)';
      OUTPUT_LOAD='(1.0,-1.0)';
      PINUSE='BI';
    'DDR2_DQ'<31>:
      PIN_NUMBER='(0,0,0,0,AT65,0,0,0,0,0,0,0,0,0,0,0,0,0,0,0,0,0,0,0,0,0,0,0,0,~
0)';
      BIDIRECTIONAL='TRUE';
      INPUT_LOAD='(-0.01,0.01)';
      OUTPUT_LOAD='(1.0,-1.0)';
      PINUSE='BI';
    'DDR2_DQ'<30>:
      PIN_NUMBER='(0,0,0,0,AM65,0,0,0,0,0,0,0,0,0,0,0,0,0,0,0,0,0,0,0,0,0,0,0,0,~
0)';
      BIDIRECTIONAL='TRUE';
      INPUT_LOAD='(-0.01,0.01)';
      OUTPUT_LOAD='(1.0,-1.0)';
      PINUSE='BI';
    'DDR2_DQ'<29>:
      PIN_NUMBER='(0,0,0,0,AR68,0,0,0,0,0,0,0,0,0,0,0,0,0,0,0,0,0,0,0,0,0,0,0,0,~
0)';
      BIDIRECTIONAL='TRUE';
      INPUT_LOAD='(-0.01,0.01)';
      OUTPUT_LOAD='(1.0,-1.0)';
      PINUSE='BI';
    'DDR2_DQ'<28>:
      PIN_NUMBER='(0,0,0,0,AN68,0,0,0,0,0,0,0,0,0,0,0,0,0,0,0,0,0,0,0,0,0,0,0,0,~
0)';
      BIDIRECTIONAL='TRUE';
      INPUT_LOAD='(-0.01,0.01)';
      OUTPUT_LOAD='(1.0,-1.0)';
      PINUSE='BI';
    'DDR2_DQ'<27>:
      PIN_NUMBER='(0,0,0,0,AR64,0,0,0,0,0,0,0,0,0,0,0,0,0,0,0,0,0,0,0,0,0,0,0,0,~
0)';
      BIDIRECTIONAL='TRUE';
      INPUT_LOAD='(-0.01,0.01)';
      OUTPUT_LOAD='(1.0,-1.0)';
      PINUSE='BI';
    'DDR2_DQ'<26>:
      PIN_NUMBER='(0,0,0,0,AN64,0,0,0,0,0,0,0,0,0,0,0,0,0,0,0,0,0,0,0,0,0,0,0,0,~
0)';
      BIDIRECTIONAL='TRUE';
      INPUT_LOAD='(-0.01,0.01)';
      OUTPUT_LOAD='(1.0,-1.0)';
      PINUSE='BI';
    'DDR2_DQ'<25>:
      PIN_NUMBER='(0,0,0,0,AT67,0,0,0,0,0,0,0,0,0,0,0,0,0,0,0,0,0,0,0,0,0,0,0,0,~
0)';
      BIDIRECTIONAL='TRUE';
      INPUT_LOAD='(-0.01,0.01)';
      OUTPUT_LOAD='(1.0,-1.0)';
      PINUSE='BI';
    'DDR2_DQ'<24>:
      PIN_NUMBER='(0,0,0,0,AM67,0,0,0,0,0,0,0,0,0,0,0,0,0,0,0,0,0,0,0,0,0,0,0,0,~
0)';
      BIDIRECTIONAL='TRUE';
      INPUT_LOAD='(-0.01,0.01)';
      OUTPUT_LOAD='(1.0,-1.0)';
      PINUSE='BI';
    'DDR2_DQ'<23>:
      PIN_NUMBER='(0,0,0,0,V69,0,0,0,0,0,0,0,0,0,0,0,0,0,0,0,0,0,0,0,0,0,0,0,0,0~
)';
      BIDIRECTIONAL='TRUE';
      INPUT_LOAD='(-0.01,0.01)';
      OUTPUT_LOAD='(1.0,-1.0)';
      PINUSE='BI';
    'DDR2_DQ'<22>:
      PIN_NUMBER='(0,0,0,0,T71,0,0,0,0,0,0,0,0,0,0,0,0,0,0,0,0,0,0,0,0,0,0,0,0,0~
)';
      BIDIRECTIONAL='TRUE';
      INPUT_LOAD='(-0.01,0.01)';
      OUTPUT_LOAD='(1.0,-1.0)';
      PINUSE='BI';
    'DDR2_DQ'<21>:
      PIN_NUMBER='(0,0,0,0,AB71,0,0,0,0,0,0,0,0,0,0,0,0,0,0,0,0,0,0,0,0,0,0,0,0,~
0)';
      BIDIRECTIONAL='TRUE';
      INPUT_LOAD='(-0.01,0.01)';
      OUTPUT_LOAD='(1.0,-1.0)';
      PINUSE='BI';
    'DDR2_DQ'<20>:
      PIN_NUMBER='(0,0,0,0,AA72,0,0,0,0,0,0,0,0,0,0,0,0,0,0,0,0,0,0,0,0,0,0,0,0,~
0)';
      BIDIRECTIONAL='TRUE';
      INPUT_LOAD='(-0.01,0.01)';
      OUTPUT_LOAD='(1.0,-1.0)';
      PINUSE='BI';
    'DDR2_DQ'<19>:
      PIN_NUMBER='(0,0,0,0,T69,0,0,0,0,0,0,0,0,0,0,0,0,0,0,0,0,0,0,0,0,0,0,0,0,0~
)';
      BIDIRECTIONAL='TRUE';
      INPUT_LOAD='(-0.01,0.01)';
      OUTPUT_LOAD='(1.0,-1.0)';
      PINUSE='BI';
    'DDR2_DQ'<18>:
      PIN_NUMBER='(0,0,0,0,R70,0,0,0,0,0,0,0,0,0,0,0,0,0,0,0,0,0,0,0,0,0,0,0,0,0~
)';
      BIDIRECTIONAL='TRUE';
      INPUT_LOAD='(-0.01,0.01)';
      OUTPUT_LOAD='(1.0,-1.0)';
      PINUSE='BI';
    'DDR2_DQ'<17>:
      PIN_NUMBER='(0,0,0,0,AA70,0,0,0,0,0,0,0,0,0,0,0,0,0,0,0,0,0,0,0,0,0,0,0,0,~
0)';
      BIDIRECTIONAL='TRUE';
      INPUT_LOAD='(-0.01,0.01)';
      OUTPUT_LOAD='(1.0,-1.0)';
      PINUSE='BI';
    'DDR2_DQ'<16>:
      PIN_NUMBER='(0,0,0,0,W72,0,0,0,0,0,0,0,0,0,0,0,0,0,0,0,0,0,0,0,0,0,0,0,0,0~
)';
      BIDIRECTIONAL='TRUE';
      INPUT_LOAD='(-0.01,0.01)';
      OUTPUT_LOAD='(1.0,-1.0)';
      PINUSE='BI';
    'DDR2_DQ'<15>:
      PIN_NUMBER='(0,0,0,0,Y75,0,0,0,0,0,0,0,0,0,0,0,0,0,0,0,0,0,0,0,0,0,0,0,0,0~
)';
      BIDIRECTIONAL='TRUE';
      INPUT_LOAD='(-0.01,0.01)';
      OUTPUT_LOAD='(1.0,-1.0)';
      PINUSE='BI';
    'DDR2_DQ'<14>:
      PIN_NUMBER='(0,0,0,0,AB77,0,0,0,0,0,0,0,0,0,0,0,0,0,0,0,0,0,0,0,0,0,0,0,0,~
0)';
      BIDIRECTIONAL='TRUE';
      INPUT_LOAD='(-0.01,0.01)';
      OUTPUT_LOAD='(1.0,-1.0)';
      PINUSE='BI';
    'DDR2_DQ'<13>:
      PIN_NUMBER='(0,0,0,0,AE74,0,0,0,0,0,0,0,0,0,0,0,0,0,0,0,0,0,0,0,0,0,0,0,0,~
0)';
      BIDIRECTIONAL='TRUE';
      INPUT_LOAD='(-0.01,0.01)';
      OUTPUT_LOAD='(1.0,-1.0)';
      PINUSE='BI';
    'DDR2_DQ'<12>:
      PIN_NUMBER='(0,0,0,0,AF75,0,0,0,0,0,0,0,0,0,0,0,0,0,0,0,0,0,0,0,0,0,0,0,0,~
0)';
      BIDIRECTIONAL='TRUE';
      INPUT_LOAD='(-0.01,0.01)';
      OUTPUT_LOAD='(1.0,-1.0)';
      PINUSE='BI';
    'DDR2_DQ'<11>:
      PIN_NUMBER='(0,0,0,0,W76,0,0,0,0,0,0,0,0,0,0,0,0,0,0,0,0,0,0,0,0,0,0,0,0,0~
)';
      BIDIRECTIONAL='TRUE';
      INPUT_LOAD='(-0.01,0.01)';
      OUTPUT_LOAD='(1.0,-1.0)';
      PINUSE='BI';
    'DDR2_DQ'<10>:
      PIN_NUMBER='(0,0,0,0,Y77,0,0,0,0,0,0,0,0,0,0,0,0,0,0,0,0,0,0,0,0,0,0,0,0,0~
)';
      BIDIRECTIONAL='TRUE';
      INPUT_LOAD='(-0.01,0.01)';
      OUTPUT_LOAD='(1.0,-1.0)';
      PINUSE='BI';
    'DDR2_DQ'<9>:
      PIN_NUMBER='(0,0,0,0,AC74,0,0,0,0,0,0,0,0,0,0,0,0,0,0,0,0,0,0,0,0,0,0,0,0,~
0)';
      BIDIRECTIONAL='TRUE';
      INPUT_LOAD='(-0.01,0.01)';
      OUTPUT_LOAD='(1.0,-1.0)';
      PINUSE='BI';
    'DDR2_DQ'<8>:
      PIN_NUMBER='(0,0,0,0,AE76,0,0,0,0,0,0,0,0,0,0,0,0,0,0,0,0,0,0,0,0,0,0,0,0,~
0)';
      BIDIRECTIONAL='TRUE';
      INPUT_LOAD='(-0.01,0.01)';
      OUTPUT_LOAD='(1.0,-1.0)';
      PINUSE='BI';
    'DDR2_DQ'<7>:
      PIN_NUMBER='(0,0,0,0,AK75,0,0,0,0,0,0,0,0,0,0,0,0,0,0,0,0,0,0,0,0,0,0,0,0,~
0)';
      BIDIRECTIONAL='TRUE';
      INPUT_LOAD='(-0.01,0.01)';
      OUTPUT_LOAD='(1.0,-1.0)';
      PINUSE='BI';
    'DDR2_DQ'<6>:
      PIN_NUMBER='(0,0,0,0,AM77,0,0,0,0,0,0,0,0,0,0,0,0,0,0,0,0,0,0,0,0,0,0,0,0,~
0)';
      BIDIRECTIONAL='TRUE';
      INPUT_LOAD='(-0.01,0.01)';
      OUTPUT_LOAD='(1.0,-1.0)';
      PINUSE='BI';
    'DDR2_DQ'<5>:
      PIN_NUMBER='(0,0,0,0,AR74,0,0,0,0,0,0,0,0,0,0,0,0,0,0,0,0,0,0,0,0,0,0,0,0,~
0)';
      BIDIRECTIONAL='TRUE';
      INPUT_LOAD='(-0.01,0.01)';
      OUTPUT_LOAD='(1.0,-1.0)';
      PINUSE='BI';
    'DDR2_DQ'<4>:
      PIN_NUMBER='(0,0,0,0,AT75,0,0,0,0,0,0,0,0,0,0,0,0,0,0,0,0,0,0,0,0,0,0,0,0,~
0)';
      BIDIRECTIONAL='TRUE';
      INPUT_LOAD='(-0.01,0.01)';
      OUTPUT_LOAD='(1.0,-1.0)';
      PINUSE='BI';
    'DDR2_DQ'<3>:
      PIN_NUMBER='(0,0,0,0,AJ76,0,0,0,0,0,0,0,0,0,0,0,0,0,0,0,0,0,0,0,0,0,0,0,0,~
0)';
      BIDIRECTIONAL='TRUE';
      INPUT_LOAD='(-0.01,0.01)';
      OUTPUT_LOAD='(1.0,-1.0)';
      PINUSE='BI';
    'DDR2_DQ'<2>:
      PIN_NUMBER='(0,0,0,0,AK77,0,0,0,0,0,0,0,0,0,0,0,0,0,0,0,0,0,0,0,0,0,0,0,0,~
0)';
      BIDIRECTIONAL='TRUE';
      INPUT_LOAD='(-0.01,0.01)';
      OUTPUT_LOAD='(1.0,-1.0)';
      PINUSE='BI';
    'DDR2_DQ'<1>:
      PIN_NUMBER='(0,0,0,0,AN74,0,0,0,0,0,0,0,0,0,0,0,0,0,0,0,0,0,0,0,0,0,0,0,0,~
0)';
      BIDIRECTIONAL='TRUE';
      INPUT_LOAD='(-0.01,0.01)';
      OUTPUT_LOAD='(1.0,-1.0)';
      PINUSE='BI';
    'DDR2_DQ'<0>:
      PIN_NUMBER='(0,0,0,0,AR76,0,0,0,0,0,0,0,0,0,0,0,0,0,0,0,0,0,0,0,0,0,0,0,0,~
0)';
      BIDIRECTIONAL='TRUE';
      INPUT_LOAD='(-0.01,0.01)';
      OUTPUT_LOAD='(1.0,-1.0)';
      PINUSE='BI';
    'DDR2_DQS_DN'<17>:
      PIN_NUMBER='(0,0,0,0,AT71,0,0,0,0,0,0,0,0,0,0,0,0,0,0,0,0,0,0,0,0,0,0,0,0,~
0)';
      BIDIRECTIONAL='TRUE';
      INPUT_LOAD='(-0.01,0.01)';
      OUTPUT_LOAD='(1.0,-1.0)';
      PINUSE='BI';
    'DDR2_DQS_DN'<16>:
      PIN_NUMBER='(0,0,0,0,AC24,0,0,0,0,0,0,0,0,0,0,0,0,0,0,0,0,0,0,0,0,0,0,0,0,~
0)';
      BIDIRECTIONAL='TRUE';
      INPUT_LOAD='(-0.01,0.01)';
      OUTPUT_LOAD='(1.0,-1.0)';
      PINUSE='BI';
    'DDR2_DQS_DN'<15>:
      PIN_NUMBER='(0,0,0,0,AC30,0,0,0,0,0,0,0,0,0,0,0,0,0,0,0,0,0,0,0,0,0,0,0,0,~
0)';
      BIDIRECTIONAL='TRUE';
      INPUT_LOAD='(-0.01,0.01)';
      OUTPUT_LOAD='(1.0,-1.0)';
      PINUSE='BI';
    'DDR2_DQS_DN'<14>:
      PIN_NUMBER='(0,0,0,0,T33,0,0,0,0,0,0,0,0,0,0,0,0,0,0,0,0,0,0,0,0,0,0,0,0,0~
)';
      BIDIRECTIONAL='TRUE';
      INPUT_LOAD='(-0.01,0.01)';
      OUTPUT_LOAD='(1.0,-1.0)';
      PINUSE='BI';
    'DDR2_DQS_DN'<13>:
      PIN_NUMBER='(0,0,0,0,T39,0,0,0,0,0,0,0,0,0,0,0,0,0,0,0,0,0,0,0,0,0,0,0,0,0~
)';
      BIDIRECTIONAL='TRUE';
      INPUT_LOAD='(-0.01,0.01)';
      OUTPUT_LOAD='(1.0,-1.0)';
      PINUSE='BI';
    'DDR2_DQS_DN'<12>:
      PIN_NUMBER='(0,0,0,0,AL66,0,0,0,0,0,0,0,0,0,0,0,0,0,0,0,0,0,0,0,0,0,0,0,0,~
0)';
      BIDIRECTIONAL='TRUE';
      INPUT_LOAD='(-0.01,0.01)';
      OUTPUT_LOAD='(1.0,-1.0)';
      PINUSE='BI';
    'DDR2_DQS_DN'<11>:
      PIN_NUMBER='(0,0,0,0,U72,0,0,0,0,0,0,0,0,0,0,0,0,0,0,0,0,0,0,0,0,0,0,0,0,0~
)';
      BIDIRECTIONAL='TRUE';
      INPUT_LOAD='(-0.01,0.01)';
      OUTPUT_LOAD='(1.0,-1.0)';
      PINUSE='BI';
    'DDR2_DQS_DN'<10>:
      PIN_NUMBER='(0,0,0,0,AD77,0,0,0,0,0,0,0,0,0,0,0,0,0,0,0,0,0,0,0,0,0,0,0,0,~
0)';
      BIDIRECTIONAL='TRUE';
      INPUT_LOAD='(-0.01,0.01)';
      OUTPUT_LOAD='(1.0,-1.0)';
      PINUSE='BI';
    'DDR2_DQS_DN'<9>:
      PIN_NUMBER='(0,0,0,0,AP77,0,0,0,0,0,0,0,0,0,0,0,0,0,0,0,0,0,0,0,0,0,0,0,0,~
0)';
      BIDIRECTIONAL='TRUE';
      INPUT_LOAD='(-0.01,0.01)';
      OUTPUT_LOAD='(1.0,-1.0)';
      PINUSE='BI';
    'DDR2_DQS_DN'<8>:
      PIN_NUMBER='(0,0,0,0,BB71,0,0,0,0,0,0,0,0,0,0,0,0,0,0,0,0,0,0,0,0,0,0,0,0,~
0)';
      BIDIRECTIONAL='TRUE';
      INPUT_LOAD='(-0.01,0.01)';
      OUTPUT_LOAD='(1.0,-1.0)';
      PINUSE='BI';
    'DDR2_DQS_DN'<7>:
      PIN_NUMBER='(0,0,0,0,AJ24,0,0,0,0,0,0,0,0,0,0,0,0,0,0,0,0,0,0,0,0,0,0,0,0,~
0)';
      BIDIRECTIONAL='TRUE';
      INPUT_LOAD='(-0.01,0.01)';
      OUTPUT_LOAD='(1.0,-1.0)';
      PINUSE='BI';
    'DDR2_DQS_DN'<6>:
      PIN_NUMBER='(0,0,0,0,AJ30,0,0,0,0,0,0,0,0,0,0,0,0,0,0,0,0,0,0,0,0,0,0,0,0,~
0)';
      BIDIRECTIONAL='TRUE';
      INPUT_LOAD='(-0.01,0.01)';
      OUTPUT_LOAD='(1.0,-1.0)';
      PINUSE='BI';
    'DDR2_DQS_DN'<5>:
      PIN_NUMBER='(0,0,0,0,AB33,0,0,0,0,0,0,0,0,0,0,0,0,0,0,0,0,0,0,0,0,0,0,0,0,~
0)';
      BIDIRECTIONAL='TRUE';
      INPUT_LOAD='(-0.01,0.01)';
      OUTPUT_LOAD='(1.0,-1.0)';
      PINUSE='BI';
    'DDR2_DQS_DN'<4>:
      PIN_NUMBER='(0,0,0,0,AB39,0,0,0,0,0,0,0,0,0,0,0,0,0,0,0,0,0,0,0,0,0,0,0,0,~
0)';
      BIDIRECTIONAL='TRUE';
      INPUT_LOAD='(-0.01,0.01)';
      OUTPUT_LOAD='(1.0,-1.0)';
      PINUSE='BI';
    'DDR2_DQS_DN'<3>:
      PIN_NUMBER='(0,0,0,0,AU66,0,0,0,0,0,0,0,0,0,0,0,0,0,0,0,0,0,0,0,0,0,0,0,0,~
0)';
      BIDIRECTIONAL='TRUE';
      INPUT_LOAD='(-0.01,0.01)';
      OUTPUT_LOAD='(1.0,-1.0)';
      PINUSE='BI';
    'DDR2_DQS_DN'<2>:
      PIN_NUMBER='(0,0,0,0,Y69,0,0,0,0,0,0,0,0,0,0,0,0,0,0,0,0,0,0,0,0,0,0,0,0,0~
)';
      BIDIRECTIONAL='TRUE';
      INPUT_LOAD='(-0.01,0.01)';
      OUTPUT_LOAD='(1.0,-1.0)';
      PINUSE='BI';
    'DDR2_DQS_DN'<1>:
      PIN_NUMBER='(0,0,0,0,AA74,0,0,0,0,0,0,0,0,0,0,0,0,0,0,0,0,0,0,0,0,0,0,0,0,~
0)';
      BIDIRECTIONAL='TRUE';
      INPUT_LOAD='(-0.01,0.01)';
      OUTPUT_LOAD='(1.0,-1.0)';
      PINUSE='BI';
    'DDR2_DQS_DN'<0>:
      PIN_NUMBER='(0,0,0,0,AL74,0,0,0,0,0,0,0,0,0,0,0,0,0,0,0,0,0,0,0,0,0,0,0,0,~
0)';
      BIDIRECTIONAL='TRUE';
      INPUT_LOAD='(-0.01,0.01)';
      OUTPUT_LOAD='(1.0,-1.0)';
      PINUSE='BI';
    'DDR2_DQS_DP'<17>:
      PIN_NUMBER='(0,0,0,0,AV71,0,0,0,0,0,0,0,0,0,0,0,0,0,0,0,0,0,0,0,0,0,0,0,0,~
0)';
      BIDIRECTIONAL='TRUE';
      INPUT_LOAD='(-0.01,0.01)';
      OUTPUT_LOAD='(1.0,-1.0)';
      PINUSE='BI';
    'DDR2_DQS_DP'<16>:
      PIN_NUMBER='(0,0,0,0,AE24,0,0,0,0,0,0,0,0,0,0,0,0,0,0,0,0,0,0,0,0,0,0,0,0,~
0)';
      BIDIRECTIONAL='TRUE';
      INPUT_LOAD='(-0.01,0.01)';
      OUTPUT_LOAD='(1.0,-1.0)';
      PINUSE='BI';
    'DDR2_DQS_DP'<15>:
      PIN_NUMBER='(0,0,0,0,AE30,0,0,0,0,0,0,0,0,0,0,0,0,0,0,0,0,0,0,0,0,0,0,0,0,~
0)';
      BIDIRECTIONAL='TRUE';
      INPUT_LOAD='(-0.01,0.01)';
      OUTPUT_LOAD='(1.0,-1.0)';
      PINUSE='BI';
    'DDR2_DQS_DP'<14>:
      PIN_NUMBER='(0,0,0,0,V33,0,0,0,0,0,0,0,0,0,0,0,0,0,0,0,0,0,0,0,0,0,0,0,0,0~
)';
      BIDIRECTIONAL='TRUE';
      INPUT_LOAD='(-0.01,0.01)';
      OUTPUT_LOAD='(1.0,-1.0)';
      PINUSE='BI';
    'DDR2_DQS_DP'<13>:
      PIN_NUMBER='(0,0,0,0,V39,0,0,0,0,0,0,0,0,0,0,0,0,0,0,0,0,0,0,0,0,0,0,0,0,0~
)';
      BIDIRECTIONAL='TRUE';
      INPUT_LOAD='(-0.01,0.01)';
      OUTPUT_LOAD='(1.0,-1.0)';
      PINUSE='BI';
    'DDR2_DQS_DP'<12>:
      PIN_NUMBER='(0,0,0,0,AN66,0,0,0,0,0,0,0,0,0,0,0,0,0,0,0,0,0,0,0,0,0,0,0,0,~
0)';
      BIDIRECTIONAL='TRUE';
      INPUT_LOAD='(-0.01,0.01)';
      OUTPUT_LOAD='(1.0,-1.0)';
      PINUSE='BI';
    'DDR2_DQS_DP'<11>:
      PIN_NUMBER='(0,0,0,0,V71,0,0,0,0,0,0,0,0,0,0,0,0,0,0,0,0,0,0,0,0,0,0,0,0,0~
)';
      BIDIRECTIONAL='TRUE';
      INPUT_LOAD='(-0.01,0.01)';
      OUTPUT_LOAD='(1.0,-1.0)';
      PINUSE='BI';
    'DDR2_DQS_DP'<10>:
      PIN_NUMBER='(0,0,0,0,AC76,0,0,0,0,0,0,0,0,0,0,0,0,0,0,0,0,0,0,0,0,0,0,0,0,~
0)';
      BIDIRECTIONAL='TRUE';
      INPUT_LOAD='(-0.01,0.01)';
      OUTPUT_LOAD='(1.0,-1.0)';
      PINUSE='BI';
    'DDR2_DQS_DP'<9>:
      PIN_NUMBER='(0,0,0,0,AN76,0,0,0,0,0,0,0,0,0,0,0,0,0,0,0,0,0,0,0,0,0,0,0,0,~
0)';
      BIDIRECTIONAL='TRUE';
      INPUT_LOAD='(-0.01,0.01)';
      OUTPUT_LOAD='(1.0,-1.0)';
      PINUSE='BI';
    'DDR2_DQS_DP'<8>:
      PIN_NUMBER='(0,0,0,0,AY71,0,0,0,0,0,0,0,0,0,0,0,0,0,0,0,0,0,0,0,0,0,0,0,0,~
0)';
      BIDIRECTIONAL='TRUE';
      INPUT_LOAD='(-0.01,0.01)';
      OUTPUT_LOAD='(1.0,-1.0)';
      PINUSE='BI';
    'DDR2_DQS_DP'<7>:
      PIN_NUMBER='(0,0,0,0,AG24,0,0,0,0,0,0,0,0,0,0,0,0,0,0,0,0,0,0,0,0,0,0,0,0,~
0)';
      BIDIRECTIONAL='TRUE';
      INPUT_LOAD='(-0.01,0.01)';
      OUTPUT_LOAD='(1.0,-1.0)';
      PINUSE='BI';
    'DDR2_DQS_DP'<6>:
      PIN_NUMBER='(0,0,0,0,AG30,0,0,0,0,0,0,0,0,0,0,0,0,0,0,0,0,0,0,0,0,0,0,0,0,~
0)';
      BIDIRECTIONAL='TRUE';
      INPUT_LOAD='(-0.01,0.01)';
      OUTPUT_LOAD='(1.0,-1.0)';
      PINUSE='BI';
    'DDR2_DQS_DP'<5>:
      PIN_NUMBER='(0,0,0,0,Y33,0,0,0,0,0,0,0,0,0,0,0,0,0,0,0,0,0,0,0,0,0,0,0,0,0~
)';
      BIDIRECTIONAL='TRUE';
      INPUT_LOAD='(-0.01,0.01)';
      OUTPUT_LOAD='(1.0,-1.0)';
      PINUSE='BI';
    'DDR2_DQS_DP'<4>:
      PIN_NUMBER='(0,0,0,0,Y39,0,0,0,0,0,0,0,0,0,0,0,0,0,0,0,0,0,0,0,0,0,0,0,0,0~
)';
      BIDIRECTIONAL='TRUE';
      INPUT_LOAD='(-0.01,0.01)';
      OUTPUT_LOAD='(1.0,-1.0)';
      PINUSE='BI';
    'DDR2_DQS_DP'<3>:
      PIN_NUMBER='(0,0,0,0,AR66,0,0,0,0,0,0,0,0,0,0,0,0,0,0,0,0,0,0,0,0,0,0,0,0,~
0)';
      BIDIRECTIONAL='TRUE';
      INPUT_LOAD='(-0.01,0.01)';
      OUTPUT_LOAD='(1.0,-1.0)';
      PINUSE='BI';
    'DDR2_DQS_DP'<2>:
      PIN_NUMBER='(0,0,0,0,W70,0,0,0,0,0,0,0,0,0,0,0,0,0,0,0,0,0,0,0,0,0,0,0,0,0~
)';
      BIDIRECTIONAL='TRUE';
      INPUT_LOAD='(-0.01,0.01)';
      OUTPUT_LOAD='(1.0,-1.0)';
      PINUSE='BI';
    'DDR2_DQS_DP'<1>:
      PIN_NUMBER='(0,0,0,0,AB75,0,0,0,0,0,0,0,0,0,0,0,0,0,0,0,0,0,0,0,0,0,0,0,0,~
0)';
      BIDIRECTIONAL='TRUE';
      INPUT_LOAD='(-0.01,0.01)';
      OUTPUT_LOAD='(1.0,-1.0)';
      PINUSE='BI';
    'DDR2_DQS_DP'<0>:
      PIN_NUMBER='(0,0,0,0,AM75,0,0,0,0,0,0,0,0,0,0,0,0,0,0,0,0,0,0,0,0,0,0,0,0,~
0)';
      BIDIRECTIONAL='TRUE';
      INPUT_LOAD='(-0.01,0.01)';
      OUTPUT_LOAD='(1.0,-1.0)';
      PINUSE='BI';
    'DDR2_ECC'<7>:
      PIN_NUMBER='(0,0,0,0,BA70,0,0,0,0,0,0,0,0,0,0,0,0,0,0,0,0,0,0,0,0,0,0,0,0,~
0)';
      BIDIRECTIONAL='TRUE';
      INPUT_LOAD='(-0.01,0.01)';
      OUTPUT_LOAD='(1.0,-1.0)';
      PINUSE='BI';
    'DDR2_ECC'<6>:
      PIN_NUMBER='(0,0,0,0,AU70,0,0,0,0,0,0,0,0,0,0,0,0,0,0,0,0,0,0,0,0,0,0,0,0,~
0)';
      BIDIRECTIONAL='TRUE';
      INPUT_LOAD='(-0.01,0.01)';
      OUTPUT_LOAD='(1.0,-1.0)';
      PINUSE='BI';
    'DDR2_ECC'<5>:
      PIN_NUMBER='(0,0,0,0,AY73,0,0,0,0,0,0,0,0,0,0,0,0,0,0,0,0,0,0,0,0,0,0,0,0,~
0)';
      BIDIRECTIONAL='TRUE';
      INPUT_LOAD='(-0.01,0.01)';
      OUTPUT_LOAD='(1.0,-1.0)';
      PINUSE='BI';
    'DDR2_ECC'<4>:
      PIN_NUMBER='(0,0,0,0,AV73,0,0,0,0,0,0,0,0,0,0,0,0,0,0,0,0,0,0,0,0,0,0,0,0,~
0)';
      BIDIRECTIONAL='TRUE';
      INPUT_LOAD='(-0.01,0.01)';
      OUTPUT_LOAD='(1.0,-1.0)';
      PINUSE='BI';
    'DDR2_ECC'<3>:
      PIN_NUMBER='(0,0,0,0,AY69,0,0,0,0,0,0,0,0,0,0,0,0,0,0,0,0,0,0,0,0,0,0,0,0,~
0)';
      BIDIRECTIONAL='TRUE';
      INPUT_LOAD='(-0.01,0.01)';
      OUTPUT_LOAD='(1.0,-1.0)';
      PINUSE='BI';
    'DDR2_ECC'<2>:
      PIN_NUMBER='(0,0,0,0,AV69,0,0,0,0,0,0,0,0,0,0,0,0,0,0,0,0,0,0,0,0,0,0,0,0,~
0)';
      BIDIRECTIONAL='TRUE';
      INPUT_LOAD='(-0.01,0.01)';
      OUTPUT_LOAD='(1.0,-1.0)';
      PINUSE='BI';
    'DDR2_ECC'<1>:
      PIN_NUMBER='(0,0,0,0,BA72,0,0,0,0,0,0,0,0,0,0,0,0,0,0,0,0,0,0,0,0,0,0,0,0,~
0)';
      BIDIRECTIONAL='TRUE';
      INPUT_LOAD='(-0.01,0.01)';
      OUTPUT_LOAD='(1.0,-1.0)';
      PINUSE='BI';
    'DDR2_ECC'<0>:
      PIN_NUMBER='(0,0,0,0,AU72,0,0,0,0,0,0,0,0,0,0,0,0,0,0,0,0,0,0,0,0,0,0,0,0,~
0)';
      BIDIRECTIONAL='TRUE';
      INPUT_LOAD='(-0.01,0.01)';
      OUTPUT_LOAD='(1.0,-1.0)';
      PINUSE='BI';
    'DDR2_MA'<17>:
      PIN_NUMBER='(0,0,0,0,AC46,0,0,0,0,0,0,0,0,0,0,0,0,0,0,0,0,0,0,0,0,0,0,0,0,~
0)';
      OUTPUT_LOAD='(1.0,-1.0)';
      PINUSE='OUT';
    'DDR2_MA'<16>:
      PIN_NUMBER='(0,0,0,0,AA52,0,0,0,0,0,0,0,0,0,0,0,0,0,0,0,0,0,0,0,0,0,0,0,0,~
0)';
      OUTPUT_LOAD='(1.0,-1.0)';
      PINUSE='OUT';
    'DDR2_MA'<15>:
      PIN_NUMBER='(0,0,0,0,AE54,0,0,0,0,0,0,0,0,0,0,0,0,0,0,0,0,0,0,0,0,0,0,0,0,~
0)';
      OUTPUT_LOAD='(1.0,-1.0)';
      PINUSE='OUT';
    'DDR2_MA'<14>:
      PIN_NUMBER='(0,0,0,0,W50,0,0,0,0,0,0,0,0,0,0,0,0,0,0,0,0,0,0,0,0,0,0,0,0,0~
)';
      OUTPUT_LOAD='(1.0,-1.0)';
      PINUSE='OUT';
    'DDR2_MA'<13>:
      PIN_NUMBER='(0,0,0,0,AD53,0,0,0,0,0,0,0,0,0,0,0,0,0,0,0,0,0,0,0,0,0,0,0,0,~
0)';
      OUTPUT_LOAD='(1.0,-1.0)';
      PINUSE='OUT';
    'DDR2_MA'<12>:
      PIN_NUMBER='(0,0,0,0,AG62,0,0,0,0,0,0,0,0,0,0,0,0,0,0,0,0,0,0,0,0,0,0,0,0,~
0)';
      OUTPUT_LOAD='(1.0,-1.0)';
      PINUSE='OUT';
    'DDR2_MA'<11>:
      PIN_NUMBER='(0,0,0,0,AG60,0,0,0,0,0,0,0,0,0,0,0,0,0,0,0,0,0,0,0,0,0,0,0,0,~
0)';
      OUTPUT_LOAD='(1.0,-1.0)';
      PINUSE='OUT';
    'DDR2_MA'<10>:
      PIN_NUMBER='(0,0,0,0,AD55,0,0,0,0,0,0,0,0,0,0,0,0,0,0,0,0,0,0,0,0,0,0,0,0,~
0)';
      OUTPUT_LOAD='(1.0,-1.0)';
      PINUSE='OUT';
    'DDR2_MA'<9>:
      PIN_NUMBER='(0,0,0,0,AG58,0,0,0,0,0,0,0,0,0,0,0,0,0,0,0,0,0,0,0,0,0,0,0,0,~
0)';
      OUTPUT_LOAD='(1.0,-1.0)';
      PINUSE='OUT';
    'DDR2_MA'<8>:
      PIN_NUMBER='(0,0,0,0,AD59,0,0,0,0,0,0,0,0,0,0,0,0,0,0,0,0,0,0,0,0,0,0,0,0,~
0)';
      OUTPUT_LOAD='(1.0,-1.0)';
      PINUSE='OUT';
    'DDR2_MA'<7>:
      PIN_NUMBER='(0,0,0,0,AE60,0,0,0,0,0,0,0,0,0,0,0,0,0,0,0,0,0,0,0,0,0,0,0,0,~
0)';
      OUTPUT_LOAD='(1.0,-1.0)';
      PINUSE='OUT';
    'DDR2_MA'<6>:
      PIN_NUMBER='(0,0,0,0,AB59,0,0,0,0,0,0,0,0,0,0,0,0,0,0,0,0,0,0,0,0,0,0,0,0,~
0)';
      OUTPUT_LOAD='(1.0,-1.0)';
      PINUSE='OUT';
    'DDR2_MA'<5>:
      PIN_NUMBER='(0,0,0,0,V59,0,0,0,0,0,0,0,0,0,0,0,0,0,0,0,0,0,0,0,0,0,0,0,0,0~
)';
      OUTPUT_LOAD='(1.0,-1.0)';
      PINUSE='OUT';
    'DDR2_MA'<4>:
      PIN_NUMBER='(0,0,0,0,AA58,0,0,0,0,0,0,0,0,0,0,0,0,0,0,0,0,0,0,0,0,0,0,0,0,~
0)';
      OUTPUT_LOAD='(1.0,-1.0)';
      PINUSE='OUT';
    'DDR2_MA'<3>:
      PIN_NUMBER='(0,0,0,0,W58,0,0,0,0,0,0,0,0,0,0,0,0,0,0,0,0,0,0,0,0,0,0,0,0,0~
)';
      OUTPUT_LOAD='(1.0,-1.0)';
      PINUSE='OUT';
    'DDR2_MA'<2>:
      PIN_NUMBER='(0,0,0,0,AD57,0,0,0,0,0,0,0,0,0,0,0,0,0,0,0,0,0,0,0,0,0,0,0,0,~
0)';
      OUTPUT_LOAD='(1.0,-1.0)';
      PINUSE='OUT';
    'DDR2_MA'<1>:
      PIN_NUMBER='(0,0,0,0,AE58,0,0,0,0,0,0,0,0,0,0,0,0,0,0,0,0,0,0,0,0,0,0,0,0,~
0)';
      OUTPUT_LOAD='(1.0,-1.0)';
      PINUSE='OUT';
    'DDR2_MA'<0>:
      PIN_NUMBER='(0,0,0,0,AB53,0,0,0,0,0,0,0,0,0,0,0,0,0,0,0,0,0,0,0,0,0,0,0,0,~
0)';
      OUTPUT_LOAD='(1.0,-1.0)';
      PINUSE='OUT';
    'DDR2_ODT'<3>:
      PIN_NUMBER='(0,0,0,0,AB47,0,0,0,0,0,0,0,0,0,0,0,0,0,0,0,0,0,0,0,0,0,0,0,0,~
0)';
      OUTPUT_LOAD='(1.0,-1.0)';
      PINUSE='OUT';
    'DDR2_ODT'<2>:
      PIN_NUMBER='(0,0,0,0,V49,0,0,0,0,0,0,0,0,0,0,0,0,0,0,0,0,0,0,0,0,0,0,0,0,0~
)';
      OUTPUT_LOAD='(1.0,-1.0)';
      PINUSE='OUT';
    'DDR2_ODT'<1>:
      PIN_NUMBER='(0,0,0,0,AA48,0,0,0,0,0,0,0,0,0,0,0,0,0,0,0,0,0,0,0,0,0,0,0,0,~
0)';
      OUTPUT_LOAD='(1.0,-1.0)';
      PINUSE='OUT';
    'DDR2_ODT'<0>:
      PIN_NUMBER='(0,0,0,0,AA50,0,0,0,0,0,0,0,0,0,0,0,0,0,0,0,0,0,0,0,0,0,0,0,0,~
0)';
      OUTPUT_LOAD='(1.0,-1.0)';
      PINUSE='OUT';
    'DDR2_PAR':
      PIN_NUMBER='(0,0,0,0,V53,0,0,0,0,0,0,0,0,0,0,0,0,0,0,0,0,0,0,0,0,0,0,0,0,0~
)';
      OUTPUT_LOAD='(1.0,-1.0)';
      PINUSE='OUT';
    'DDR345_DRAM_PWR_OK':
      PIN_NUMBER='(CR28,0,0,0,0,0,0,0,0,0,0,0,0,0,0,0,0,0,0,0,0,0,0,0,0,0,0,0,0,~
0)';
      INPUT_LOAD='(-0.01,0.01)';
      PINUSE='IN';
    'DDR345_RCOMP'<2>:
      PIN_NUMBER='(DD49,0,0,0,0,0,0,0,0,0,0,0,0,0,0,0,0,0,0,0,0,0,0,0,0,0,0,0,0,~
0)';
      BIDIRECTIONAL='TRUE';
      INPUT_LOAD='(-0.01,0.01)';
      OUTPUT_LOAD='(1.0,-1.0)';
      PINUSE='BI';
    'DDR345_RCOMP'<1>:
      PIN_NUMBER='(DD47,0,0,0,0,0,0,0,0,0,0,0,0,0,0,0,0,0,0,0,0,0,0,0,0,0,0,0,0,~
0)';
      BIDIRECTIONAL='TRUE';
      INPUT_LOAD='(-0.01,0.01)';
      OUTPUT_LOAD='(1.0,-1.0)';
      PINUSE='BI';
    'DDR345_RCOMP'<0>:
      PIN_NUMBER='(DC48,0,0,0,0,0,0,0,0,0,0,0,0,0,0,0,0,0,0,0,0,0,0,0,0,0,0,0,0,~
0)';
      BIDIRECTIONAL='TRUE';
      INPUT_LOAD='(-0.01,0.01)';
      OUTPUT_LOAD='(1.0,-1.0)';
      PINUSE='BI';
    'DDR345_RESET_N':
      PIN_NUMBER='(DV63,0,0,0,0,0,0,0,0,0,0,0,0,0,0,0,0,0,0,0,0,0,0,0,0,0,0,0,0,~
0)';
      OUTPUT_LOAD='(1.0,-1.0)';
      PINUSE='OUT';
    'DDR345_SPDSCL':
      PIN_NUMBER='(AE18,0,0,0,0,0,0,0,0,0,0,0,0,0,0,0,0,0,0,0,0,0,0,0,0,0,0,0,0,~
0)';
      BIDIRECTIONAL='TRUE';
      INPUT_LOAD='(-0.01,0.01)';
      OUTPUT_LOAD='(1.0,-1.0)';
      PINUSE='BI';
    'DDR345_SPDSDA':
      PIN_NUMBER='(AD17,0,0,0,0,0,0,0,0,0,0,0,0,0,0,0,0,0,0,0,0,0,0,0,0,0,0,0,0,~
0)';
      BIDIRECTIONAL='TRUE';
      INPUT_LOAD='(-0.01,0.01)';
      OUTPUT_LOAD='(1.0,-1.0)';
      PINUSE='BI';
    'DDR3_ACT_N':
      PIN_NUMBER='(0,0,0,0,0,DW60,0,0,0,0,0,0,0,0,0,0,0,0,0,0,0,0,0,0,0,0,0,0,0,~
0)';
      OUTPUT_LOAD='(1.0,-1.0)';
      PINUSE='OUT';
    'DDR3_ALERT_N':
      PIN_NUMBER='(0,0,0,0,0,ED63,0,0,0,0,0,0,0,0,0,0,0,0,0,0,0,0,0,0,0,0,0,0,0,~
0)';
      INPUT_LOAD='(-0.01,0.01)';
      PINUSE='IN';
    'DDR3_BA'<1>:
      PIN_NUMBER='(0,0,0,0,0,EA54,0,0,0,0,0,0,0,0,0,0,0,0,0,0,0,0,0,0,0,0,0,0,0,~
0)';
      OUTPUT_LOAD='(1.0,-1.0)';
      PINUSE='OUT';
    'DDR3_BA'<0>:
      PIN_NUMBER='(0,0,0,0,0,EE52,0,0,0,0,0,0,0,0,0,0,0,0,0,0,0,0,0,0,0,0,0,0,0,~
0)';
      OUTPUT_LOAD='(1.0,-1.0)';
      PINUSE='OUT';
    'DDR3_BG'<1>:
      PIN_NUMBER='(0,0,0,0,0,DW62,0,0,0,0,0,0,0,0,0,0,0,0,0,0,0,0,0,0,0,0,0,0,0,~
0)';
      OUTPUT_LOAD='(1.0,-1.0)';
      PINUSE='OUT';
    'DDR3_BG'<0>:
      PIN_NUMBER='(0,0,0,0,0,ED61,0,0,0,0,0,0,0,0,0,0,0,0,0,0,0,0,0,0,0,0,0,0,0,~
0)';
      OUTPUT_LOAD='(1.0,-1.0)';
      PINUSE='OUT';
    'DDR3_CAVREF':
      PIN_NUMBER='(CP61,0,0,0,0,0,0,0,0,0,0,0,0,0,0,0,0,0,0,0,0,0,0,0,0,0,0,0,0,~
0)';
      OUTPUT_LOAD='(1.0,-1.0)';
      PINUSE='OUT';
    'DDR3_CID'<2>:
      PIN_NUMBER='(0,0,0,0,0,DV47,0,0,0,0,0,0,0,0,0,0,0,0,0,0,0,0,0,0,0,0,0,0,0,~
0)';
      OUTPUT_LOAD='(1.0,-1.0)';
      PINUSE='OUT';
    'DDR3_CKE'<3>:
      PIN_NUMBER='(0,0,0,0,0,EB63,0,0,0,0,0,0,0,0,0,0,0,0,0,0,0,0,0,0,0,0,0,0,0,~
0)';
      OUTPUT_LOAD='(1.0,-1.0)';
      PINUSE='OUT';
    'DDR3_CKE'<2>:
      PIN_NUMBER='(0,0,0,0,0,EA62,0,0,0,0,0,0,0,0,0,0,0,0,0,0,0,0,0,0,0,0,0,0,0,~
0)';
      OUTPUT_LOAD='(1.0,-1.0)';
      PINUSE='OUT';
    'DDR3_CKE'<1>:
      PIN_NUMBER='(0,0,0,0,0,EF63,0,0,0,0,0,0,0,0,0,0,0,0,0,0,0,0,0,0,0,0,0,0,0,~
0)';
      OUTPUT_LOAD='(1.0,-1.0)';
      PINUSE='OUT';
    'DDR3_CKE'<0>:
      PIN_NUMBER='(0,0,0,0,0,EE62,0,0,0,0,0,0,0,0,0,0,0,0,0,0,0,0,0,0,0,0,0,0,0,~
0)';
      OUTPUT_LOAD='(1.0,-1.0)';
      PINUSE='OUT';
    'DDR3_CLK_DN'<3>:
      PIN_NUMBER='(0,0,0,0,0,EF57,0,0,0,0,0,0,0,0,0,0,0,0,0,0,0,0,0,0,0,0,0,0,0,~
0)';
      OUTPUT_LOAD='(1.0,-1.0)';
      PINUSE='OUT';
    'DDR3_CLK_DN'<2>:
      PIN_NUMBER='(0,0,0,0,0,DW56,0,0,0,0,0,0,0,0,0,0,0,0,0,0,0,0,0,0,0,0,0,0,0,~
0)';
      OUTPUT_LOAD='(1.0,-1.0)';
      PINUSE='OUT';
    'DDR3_CLK_DN'<1>:
      PIN_NUMBER='(0,0,0,0,0,EF55,0,0,0,0,0,0,0,0,0,0,0,0,0,0,0,0,0,0,0,0,0,0,0,~
0)';
      OUTPUT_LOAD='(1.0,-1.0)';
      PINUSE='OUT';
    'DDR3_CLK_DN'<0>:
      PIN_NUMBER='(0,0,0,0,0,ED55,0,0,0,0,0,0,0,0,0,0,0,0,0,0,0,0,0,0,0,0,0,0,0,~
0)';
      OUTPUT_LOAD='(1.0,-1.0)';
      PINUSE='OUT';
    'DDR3_CLK_DP'<3>:
      PIN_NUMBER='(0,0,0,0,0,EE56,0,0,0,0,0,0,0,0,0,0,0,0,0,0,0,0,0,0,0,0,0,0,0,~
0)';
      OUTPUT_LOAD='(1.0,-1.0)';
      PINUSE='OUT';
    'DDR3_CLK_DP'<2>:
      PIN_NUMBER='(0,0,0,0,0,EA56,0,0,0,0,0,0,0,0,0,0,0,0,0,0,0,0,0,0,0,0,0,0,0,~
0)';
      OUTPUT_LOAD='(1.0,-1.0)';
      PINUSE='OUT';
    'DDR3_CLK_DP'<1>:
      PIN_NUMBER='(0,0,0,0,0,EE54,0,0,0,0,0,0,0,0,0,0,0,0,0,0,0,0,0,0,0,0,0,0,0,~
0)';
      OUTPUT_LOAD='(1.0,-1.0)';
      PINUSE='OUT';
    'DDR3_CLK_DP'<0>:
      PIN_NUMBER='(0,0,0,0,0,EB55,0,0,0,0,0,0,0,0,0,0,0,0,0,0,0,0,0,0,0,0,0,0,0,~
0)';
      OUTPUT_LOAD='(1.0,-1.0)';
      PINUSE='OUT';
    'DDR3_CS_N'<7>:
      PIN_NUMBER='(0,0,0,0,0,EB45,0,0,0,0,0,0,0,0,0,0,0,0,0,0,0,0,0,0,0,0,0,0,0,~
0)';
      OUTPUT_LOAD='(1.0,-1.0)';
      PINUSE='OUT';
    'DDR3_CS_N'<6>:
      PIN_NUMBER='(0,0,0,0,0,DV45,0,0,0,0,0,0,0,0,0,0,0,0,0,0,0,0,0,0,0,0,0,0,0,~
0)';
      OUTPUT_LOAD='(1.0,-1.0)';
      PINUSE='OUT';
    'DDR3_CS_N'<5>:
      PIN_NUMBER='(0,0,0,0,0,EB49,0,0,0,0,0,0,0,0,0,0,0,0,0,0,0,0,0,0,0,0,0,0,0,~
0)';
      OUTPUT_LOAD='(1.0,-1.0)';
      PINUSE='OUT';
    'DDR3_CS_N'<4>:
      PIN_NUMBER='(0,0,0,0,0,EB51,0,0,0,0,0,0,0,0,0,0,0,0,0,0,0,0,0,0,0,0,0,0,0,~
0)';
      OUTPUT_LOAD='(1.0,-1.0)';
      PINUSE='OUT';
    'DDR3_CS_N'<3>:
      PIN_NUMBER='(0,0,0,0,0,EB47,0,0,0,0,0,0,0,0,0,0,0,0,0,0,0,0,0,0,0,0,0,0,0,~
0)';
      OUTPUT_LOAD='(1.0,-1.0)';
      PINUSE='OUT';
    'DDR3_CS_N'<2>:
      PIN_NUMBER='(0,0,0,0,0,ED47,0,0,0,0,0,0,0,0,0,0,0,0,0,0,0,0,0,0,0,0,0,0,0,~
0)';
      OUTPUT_LOAD='(1.0,-1.0)';
      PINUSE='OUT';
    'DDR3_CS_N'<1>:
      PIN_NUMBER='(0,0,0,0,0,ED49,0,0,0,0,0,0,0,0,0,0,0,0,0,0,0,0,0,0,0,0,0,0,0,~
0)';
      OUTPUT_LOAD='(1.0,-1.0)';
      PINUSE='OUT';
    'DDR3_CS_N'<0>:
      PIN_NUMBER='(0,0,0,0,0,EF51,0,0,0,0,0,0,0,0,0,0,0,0,0,0,0,0,0,0,0,0,0,0,0,~
0)';
      OUTPUT_LOAD='(1.0,-1.0)';
      PINUSE='OUT';
    'DDR3_DQ'<63>:
      PIN_NUMBER='(0,0,0,0,0,DW22,0,0,0,0,0,0,0,0,0,0,0,0,0,0,0,0,0,0,0,0,0,0,0,~
0)';
      BIDIRECTIONAL='TRUE';
      INPUT_LOAD='(-0.01,0.01)';
      OUTPUT_LOAD='(1.0,-1.0)';
      PINUSE='BI';
    'DDR3_DQ'<62>:
      PIN_NUMBER='(0,0,0,0,0,EC22,0,0,0,0,0,0,0,0,0,0,0,0,0,0,0,0,0,0,0,0,0,0,0,~
0)';
      BIDIRECTIONAL='TRUE';
      INPUT_LOAD='(-0.01,0.01)';
      OUTPUT_LOAD='(1.0,-1.0)';
      PINUSE='BI';
    'DDR3_DQ'<61>:
      PIN_NUMBER='(0,0,0,0,0,DT25,0,0,0,0,0,0,0,0,0,0,0,0,0,0,0,0,0,0,0,0,0,0,0,~
0)';
      BIDIRECTIONAL='TRUE';
      INPUT_LOAD='(-0.01,0.01)';
      OUTPUT_LOAD='(1.0,-1.0)';
      PINUSE='BI';
    'DDR3_DQ'<60>:
      PIN_NUMBER='(0,0,0,0,0,DP25,0,0,0,0,0,0,0,0,0,0,0,0,0,0,0,0,0,0,0,0,0,0,0,~
0)';
      BIDIRECTIONAL='TRUE';
      INPUT_LOAD='(-0.01,0.01)';
      OUTPUT_LOAD='(1.0,-1.0)';
      PINUSE='BI';
    'DDR3_DQ'<59>:
      PIN_NUMBER='(0,0,0,0,0,EB21,0,0,0,0,0,0,0,0,0,0,0,0,0,0,0,0,0,0,0,0,0,0,0,~
0)';
      BIDIRECTIONAL='TRUE';
      INPUT_LOAD='(-0.01,0.01)';
      OUTPUT_LOAD='(1.0,-1.0)';
      PINUSE='BI';
    'DDR3_DQ'<58>:
      PIN_NUMBER='(0,0,0,0,0,DY21,0,0,0,0,0,0,0,0,0,0,0,0,0,0,0,0,0,0,0,0,0,0,0,~
0)';
      BIDIRECTIONAL='TRUE';
      INPUT_LOAD='(-0.01,0.01)';
      OUTPUT_LOAD='(1.0,-1.0)';
      PINUSE='BI';
    'DDR3_DQ'<57>:
      PIN_NUMBER='(0,0,0,0,0,DU24,0,0,0,0,0,0,0,0,0,0,0,0,0,0,0,0,0,0,0,0,0,0,0,~
0)';
      BIDIRECTIONAL='TRUE';
      INPUT_LOAD='(-0.01,0.01)';
      OUTPUT_LOAD='(1.0,-1.0)';
      PINUSE='BI';
    'DDR3_DQ'<56>:
      PIN_NUMBER='(0,0,0,0,0,DN24,0,0,0,0,0,0,0,0,0,0,0,0,0,0,0,0,0,0,0,0,0,0,0,~
0)';
      BIDIRECTIONAL='TRUE';
      INPUT_LOAD='(-0.01,0.01)';
      OUTPUT_LOAD='(1.0,-1.0)';
      PINUSE='BI';
    'DDR3_DQ'<55>:
      PIN_NUMBER='(0,0,0,0,0,DU28,0,0,0,0,0,0,0,0,0,0,0,0,0,0,0,0,0,0,0,0,0,0,0,~
0)';
      BIDIRECTIONAL='TRUE';
      INPUT_LOAD='(-0.01,0.01)';
      OUTPUT_LOAD='(1.0,-1.0)';
      PINUSE='BI';
    'DDR3_DQ'<54>:
      PIN_NUMBER='(0,0,0,0,0,DN28,0,0,0,0,0,0,0,0,0,0,0,0,0,0,0,0,0,0,0,0,0,0,0,~
0)';
      BIDIRECTIONAL='TRUE';
      INPUT_LOAD='(-0.01,0.01)';
      OUTPUT_LOAD='(1.0,-1.0)';
      PINUSE='BI';
    'DDR3_DQ'<53>:
      PIN_NUMBER='(0,0,0,0,0,DT31,0,0,0,0,0,0,0,0,0,0,0,0,0,0,0,0,0,0,0,0,0,0,0,~
0)';
      BIDIRECTIONAL='TRUE';
      INPUT_LOAD='(-0.01,0.01)';
      OUTPUT_LOAD='(1.0,-1.0)';
      PINUSE='BI';
    'DDR3_DQ'<52>:
      PIN_NUMBER='(0,0,0,0,0,DP31,0,0,0,0,0,0,0,0,0,0,0,0,0,0,0,0,0,0,0,0,0,0,0,~
0)';
      BIDIRECTIONAL='TRUE';
      INPUT_LOAD='(-0.01,0.01)';
      OUTPUT_LOAD='(1.0,-1.0)';
      PINUSE='BI';
    'DDR3_DQ'<51>:
      PIN_NUMBER='(0,0,0,0,0,DT27,0,0,0,0,0,0,0,0,0,0,0,0,0,0,0,0,0,0,0,0,0,0,0,~
0)';
      BIDIRECTIONAL='TRUE';
      INPUT_LOAD='(-0.01,0.01)';
      OUTPUT_LOAD='(1.0,-1.0)';
      PINUSE='BI';
    'DDR3_DQ'<50>:
      PIN_NUMBER='(0,0,0,0,0,DP27,0,0,0,0,0,0,0,0,0,0,0,0,0,0,0,0,0,0,0,0,0,0,0,~
0)';
      BIDIRECTIONAL='TRUE';
      INPUT_LOAD='(-0.01,0.01)';
      OUTPUT_LOAD='(1.0,-1.0)';
      PINUSE='BI';
    'DDR3_DQ'<49>:
      PIN_NUMBER='(0,0,0,0,0,DU30,0,0,0,0,0,0,0,0,0,0,0,0,0,0,0,0,0,0,0,0,0,0,0,~
0)';
      BIDIRECTIONAL='TRUE';
      INPUT_LOAD='(-0.01,0.01)';
      OUTPUT_LOAD='(1.0,-1.0)';
      PINUSE='BI';
    'DDR3_DQ'<48>:
      PIN_NUMBER='(0,0,0,0,0,DN30,0,0,0,0,0,0,0,0,0,0,0,0,0,0,0,0,0,0,0,0,0,0,0,~
0)';
      BIDIRECTIONAL='TRUE';
      INPUT_LOAD='(-0.01,0.01)';
      OUTPUT_LOAD='(1.0,-1.0)';
      PINUSE='BI';
    'DDR3_DQ'<47>:
      PIN_NUMBER='(0,0,0,0,0,DU34,0,0,0,0,0,0,0,0,0,0,0,0,0,0,0,0,0,0,0,0,0,0,0,~
0)';
      BIDIRECTIONAL='TRUE';
      INPUT_LOAD='(-0.01,0.01)';
      OUTPUT_LOAD='(1.0,-1.0)';
      PINUSE='BI';
    'DDR3_DQ'<46>:
      PIN_NUMBER='(0,0,0,0,0,DN34,0,0,0,0,0,0,0,0,0,0,0,0,0,0,0,0,0,0,0,0,0,0,0,~
0)';
      BIDIRECTIONAL='TRUE';
      INPUT_LOAD='(-0.01,0.01)';
      OUTPUT_LOAD='(1.0,-1.0)';
      PINUSE='BI';
    'DDR3_DQ'<45>:
      PIN_NUMBER='(0,0,0,0,0,DT37,0,0,0,0,0,0,0,0,0,0,0,0,0,0,0,0,0,0,0,0,0,0,0,~
0)';
      BIDIRECTIONAL='TRUE';
      INPUT_LOAD='(-0.01,0.01)';
      OUTPUT_LOAD='(1.0,-1.0)';
      PINUSE='BI';
    'DDR3_DQ'<44>:
      PIN_NUMBER='(0,0,0,0,0,DP37,0,0,0,0,0,0,0,0,0,0,0,0,0,0,0,0,0,0,0,0,0,0,0,~
0)';
      BIDIRECTIONAL='TRUE';
      INPUT_LOAD='(-0.01,0.01)';
      OUTPUT_LOAD='(1.0,-1.0)';
      PINUSE='BI';
    'DDR3_DQ'<43>:
      PIN_NUMBER='(0,0,0,0,0,DT33,0,0,0,0,0,0,0,0,0,0,0,0,0,0,0,0,0,0,0,0,0,0,0,~
0)';
      BIDIRECTIONAL='TRUE';
      INPUT_LOAD='(-0.01,0.01)';
      OUTPUT_LOAD='(1.0,-1.0)';
      PINUSE='BI';
    'DDR3_DQ'<42>:
      PIN_NUMBER='(0,0,0,0,0,DP33,0,0,0,0,0,0,0,0,0,0,0,0,0,0,0,0,0,0,0,0,0,0,0,~
0)';
      BIDIRECTIONAL='TRUE';
      INPUT_LOAD='(-0.01,0.01)';
      OUTPUT_LOAD='(1.0,-1.0)';
      PINUSE='BI';
    'DDR3_DQ'<41>:
      PIN_NUMBER='(0,0,0,0,0,DU36,0,0,0,0,0,0,0,0,0,0,0,0,0,0,0,0,0,0,0,0,0,0,0,~
0)';
      BIDIRECTIONAL='TRUE';
      INPUT_LOAD='(-0.01,0.01)';
      OUTPUT_LOAD='(1.0,-1.0)';
      PINUSE='BI';
    'DDR3_DQ'<40>:
      PIN_NUMBER='(0,0,0,0,0,DN36,0,0,0,0,0,0,0,0,0,0,0,0,0,0,0,0,0,0,0,0,0,0,0,~
0)';
      BIDIRECTIONAL='TRUE';
      INPUT_LOAD='(-0.01,0.01)';
      OUTPUT_LOAD='(1.0,-1.0)';
      PINUSE='BI';
    'DDR3_DQ'<39>:
      PIN_NUMBER='(0,0,0,0,0,ED37,0,0,0,0,0,0,0,0,0,0,0,0,0,0,0,0,0,0,0,0,0,0,0,~
0)';
      BIDIRECTIONAL='TRUE';
      INPUT_LOAD='(-0.01,0.01)';
      OUTPUT_LOAD='(1.0,-1.0)';
      PINUSE='BI';
    'DDR3_DQ'<38>:
      PIN_NUMBER='(0,0,0,0,0,DY37,0,0,0,0,0,0,0,0,0,0,0,0,0,0,0,0,0,0,0,0,0,0,0,~
0)';
      BIDIRECTIONAL='TRUE';
      INPUT_LOAD='(-0.01,0.01)';
      OUTPUT_LOAD='(1.0,-1.0)';
      PINUSE='BI';
    'DDR3_DQ'<37>:
      PIN_NUMBER='(0,0,0,0,0,EA40,0,0,0,0,0,0,0,0,0,0,0,0,0,0,0,0,0,0,0,0,0,0,0,~
0)';
      BIDIRECTIONAL='TRUE';
      INPUT_LOAD='(-0.01,0.01)';
      OUTPUT_LOAD='(1.0,-1.0)';
      PINUSE='BI';
    'DDR3_DQ'<36>:
      PIN_NUMBER='(0,0,0,0,0,DY39,0,0,0,0,0,0,0,0,0,0,0,0,0,0,0,0,0,0,0,0,0,0,0,~
0)';
      BIDIRECTIONAL='TRUE';
      INPUT_LOAD='(-0.01,0.01)';
      OUTPUT_LOAD='(1.0,-1.0)';
      PINUSE='BI';
    'DDR3_DQ'<35>:
      PIN_NUMBER='(0,0,0,0,0,EC36,0,0,0,0,0,0,0,0,0,0,0,0,0,0,0,0,0,0,0,0,0,0,0,~
0)';
      BIDIRECTIONAL='TRUE';
      INPUT_LOAD='(-0.01,0.01)';
      OUTPUT_LOAD='(1.0,-1.0)';
      PINUSE='BI';
    'DDR3_DQ'<34>:
      PIN_NUMBER='(0,0,0,0,0,EA36,0,0,0,0,0,0,0,0,0,0,0,0,0,0,0,0,0,0,0,0,0,0,0,~
0)';
      BIDIRECTIONAL='TRUE';
      INPUT_LOAD='(-0.01,0.01)';
      OUTPUT_LOAD='(1.0,-1.0)';
      PINUSE='BI';
    'DDR3_DQ'<33>:
      PIN_NUMBER='(0,0,0,0,0,ED39,0,0,0,0,0,0,0,0,0,0,0,0,0,0,0,0,0,0,0,0,0,0,0,~
0)';
      BIDIRECTIONAL='TRUE';
      INPUT_LOAD='(-0.01,0.01)';
      OUTPUT_LOAD='(1.0,-1.0)';
      PINUSE='BI';
    'DDR3_DQ'<32>:
      PIN_NUMBER='(0,0,0,0,0,EC40,0,0,0,0,0,0,0,0,0,0,0,0,0,0,0,0,0,0,0,0,0,0,0,~
0)';
      BIDIRECTIONAL='TRUE';
      INPUT_LOAD='(-0.01,0.01)';
      OUTPUT_LOAD='(1.0,-1.0)';
      PINUSE='BI';
    'DDR3_DQ'<31>:
      PIN_NUMBER='(0,0,0,0,0,DU74,0,0,0,0,0,0,0,0,0,0,0,0,0,0,0,0,0,0,0,0,0,0,0,~
0)';
      BIDIRECTIONAL='TRUE';
      INPUT_LOAD='(-0.01,0.01)';
      OUTPUT_LOAD='(1.0,-1.0)';
      PINUSE='BI';
    'DDR3_DQ'<30>:
      PIN_NUMBER='(0,0,0,0,0,DN74,0,0,0,0,0,0,0,0,0,0,0,0,0,0,0,0,0,0,0,0,0,0,0,~
0)';
      BIDIRECTIONAL='TRUE';
      INPUT_LOAD='(-0.01,0.01)';
      OUTPUT_LOAD='(1.0,-1.0)';
      PINUSE='BI';
    'DDR3_DQ'<29>:
      PIN_NUMBER='(0,0,0,0,0,DT77,0,0,0,0,0,0,0,0,0,0,0,0,0,0,0,0,0,0,0,0,0,0,0,~
0)';
      BIDIRECTIONAL='TRUE';
      INPUT_LOAD='(-0.01,0.01)';
      OUTPUT_LOAD='(1.0,-1.0)';
      PINUSE='BI';
    'DDR3_DQ'<28>:
      PIN_NUMBER='(0,0,0,0,0,DP77,0,0,0,0,0,0,0,0,0,0,0,0,0,0,0,0,0,0,0,0,0,0,0,~
0)';
      BIDIRECTIONAL='TRUE';
      INPUT_LOAD='(-0.01,0.01)';
      OUTPUT_LOAD='(1.0,-1.0)';
      PINUSE='BI';
    'DDR3_DQ'<27>:
      PIN_NUMBER='(0,0,0,0,0,DT73,0,0,0,0,0,0,0,0,0,0,0,0,0,0,0,0,0,0,0,0,0,0,0,~
0)';
      BIDIRECTIONAL='TRUE';
      INPUT_LOAD='(-0.01,0.01)';
      OUTPUT_LOAD='(1.0,-1.0)';
      PINUSE='BI';
    'DDR3_DQ'<26>:
      PIN_NUMBER='(0,0,0,0,0,DP73,0,0,0,0,0,0,0,0,0,0,0,0,0,0,0,0,0,0,0,0,0,0,0,~
0)';
      BIDIRECTIONAL='TRUE';
      INPUT_LOAD='(-0.01,0.01)';
      OUTPUT_LOAD='(1.0,-1.0)';
      PINUSE='BI';
    'DDR3_DQ'<25>:
      PIN_NUMBER='(0,0,0,0,0,DU76,0,0,0,0,0,0,0,0,0,0,0,0,0,0,0,0,0,0,0,0,0,0,0,~
0)';
      BIDIRECTIONAL='TRUE';
      INPUT_LOAD='(-0.01,0.01)';
      OUTPUT_LOAD='(1.0,-1.0)';
      PINUSE='BI';
    'DDR3_DQ'<24>:
      PIN_NUMBER='(0,0,0,0,0,DN76,0,0,0,0,0,0,0,0,0,0,0,0,0,0,0,0,0,0,0,0,0,0,0,~
0)';
      BIDIRECTIONAL='TRUE';
      INPUT_LOAD='(-0.01,0.01)';
      OUTPUT_LOAD='(1.0,-1.0)';
      PINUSE='BI';
    'DDR3_DQ'<23>:
      PIN_NUMBER='(0,0,0,0,0,DN82,0,0,0,0,0,0,0,0,0,0,0,0,0,0,0,0,0,0,0,0,0,0,0,~
0)';
      BIDIRECTIONAL='TRUE';
      INPUT_LOAD='(-0.01,0.01)';
      OUTPUT_LOAD='(1.0,-1.0)';
      PINUSE='BI';
    'DDR3_DQ'<22>:
      PIN_NUMBER='(0,0,0,0,0,DR80,0,0,0,0,0,0,0,0,0,0,0,0,0,0,0,0,0,0,0,0,0,0,0,~
0)';
      BIDIRECTIONAL='TRUE';
      INPUT_LOAD='(-0.01,0.01)';
      OUTPUT_LOAD='(1.0,-1.0)';
      PINUSE='BI';
    'DDR3_DQ'<21>:
      PIN_NUMBER='(0,0,0,0,0,DJ80,0,0,0,0,0,0,0,0,0,0,0,0,0,0,0,0,0,0,0,0,0,0,0,~
0)';
      BIDIRECTIONAL='TRUE';
      INPUT_LOAD='(-0.01,0.01)';
      OUTPUT_LOAD='(1.0,-1.0)';
      PINUSE='BI';
    'DDR3_DQ'<20>:
      PIN_NUMBER='(0,0,0,0,0,DK79,0,0,0,0,0,0,0,0,0,0,0,0,0,0,0,0,0,0,0,0,0,0,0,~
0)';
      BIDIRECTIONAL='TRUE';
      INPUT_LOAD='(-0.01,0.01)';
      OUTPUT_LOAD='(1.0,-1.0)';
      PINUSE='BI';
    'DDR3_DQ'<19>:
      PIN_NUMBER='(0,0,0,0,0,DR82,0,0,0,0,0,0,0,0,0,0,0,0,0,0,0,0,0,0,0,0,0,0,0,~
0)';
      BIDIRECTIONAL='TRUE';
      INPUT_LOAD='(-0.01,0.01)';
      OUTPUT_LOAD='(1.0,-1.0)';
      PINUSE='BI';
    'DDR3_DQ'<18>:
      PIN_NUMBER='(0,0,0,0,0,DT81,0,0,0,0,0,0,0,0,0,0,0,0,0,0,0,0,0,0,0,0,0,0,0,~
0)';
      BIDIRECTIONAL='TRUE';
      INPUT_LOAD='(-0.01,0.01)';
      OUTPUT_LOAD='(1.0,-1.0)';
      PINUSE='BI';
    'DDR3_DQ'<17>:
      PIN_NUMBER='(0,0,0,0,0,DK81,0,0,0,0,0,0,0,0,0,0,0,0,0,0,0,0,0,0,0,0,0,0,0,~
0)';
      BIDIRECTIONAL='TRUE';
      INPUT_LOAD='(-0.01,0.01)';
      OUTPUT_LOAD='(1.0,-1.0)';
      PINUSE='BI';
    'DDR3_DQ'<16>:
      PIN_NUMBER='(0,0,0,0,0,DM79,0,0,0,0,0,0,0,0,0,0,0,0,0,0,0,0,0,0,0,0,0,0,0,~
0)';
      BIDIRECTIONAL='TRUE';
      INPUT_LOAD='(-0.01,0.01)';
      OUTPUT_LOAD='(1.0,-1.0)';
      PINUSE='BI';
    'DDR3_DQ'<15>:
      PIN_NUMBER='(0,0,0,0,0,DV85,0,0,0,0,0,0,0,0,0,0,0,0,0,0,0,0,0,0,0,0,0,0,0,~
0)';
      BIDIRECTIONAL='TRUE';
      INPUT_LOAD='(-0.01,0.01)';
      OUTPUT_LOAD='(1.0,-1.0)';
      PINUSE='BI';
    'DDR3_DQ'<14>:
      PIN_NUMBER='(0,0,0,0,0,DR84,0,0,0,0,0,0,0,0,0,0,0,0,0,0,0,0,0,0,0,0,0,0,0,~
0)';
      BIDIRECTIONAL='TRUE';
      INPUT_LOAD='(-0.01,0.01)';
      OUTPUT_LOAD='(1.0,-1.0)';
      PINUSE='BI';
    'DDR3_DQ'<13>:
      PIN_NUMBER='(0,0,0,0,0,DE84,0,0,0,0,0,0,0,0,0,0,0,0,0,0,0,0,0,0,0,0,0,0,0,~
0)';
      BIDIRECTIONAL='TRUE';
      INPUT_LOAD='(-0.01,0.01)';
      OUTPUT_LOAD='(1.0,-1.0)';
      PINUSE='BI';
    'DDR3_DQ'<12>:
      PIN_NUMBER='(0,0,0,0,0,DD85,0,0,0,0,0,0,0,0,0,0,0,0,0,0,0,0,0,0,0,0,0,0,0,~
0)';
      BIDIRECTIONAL='TRUE';
      INPUT_LOAD='(-0.01,0.01)';
      OUTPUT_LOAD='(1.0,-1.0)';
      PINUSE='BI';
    'DDR3_DQ'<11>:
      PIN_NUMBER='(0,0,0,0,0,DY83,0,0,0,0,0,0,0,0,0,0,0,0,0,0,0,0,0,0,0,0,0,0,0,~
0)';
      BIDIRECTIONAL='TRUE';
      INPUT_LOAD='(-0.01,0.01)';
      OUTPUT_LOAD='(1.0,-1.0)';
      PINUSE='BI';
    'DDR3_DQ'<10>:
      PIN_NUMBER='(0,0,0,0,0,DV83,0,0,0,0,0,0,0,0,0,0,0,0,0,0,0,0,0,0,0,0,0,0,0,~
0)';
      BIDIRECTIONAL='TRUE';
      INPUT_LOAD='(-0.01,0.01)';
      OUTPUT_LOAD='(1.0,-1.0)';
      PINUSE='BI';
    'DDR3_DQ'<9>:
      PIN_NUMBER='(0,0,0,0,0,DH85,0,0,0,0,0,0,0,0,0,0,0,0,0,0,0,0,0,0,0,0,0,0,0,~
0)';
      BIDIRECTIONAL='TRUE';
      INPUT_LOAD='(-0.01,0.01)';
      OUTPUT_LOAD='(1.0,-1.0)';
      PINUSE='BI';
    'DDR3_DQ'<8>:
      PIN_NUMBER='(0,0,0,0,0,DG84,0,0,0,0,0,0,0,0,0,0,0,0,0,0,0,0,0,0,0,0,0,0,0,~
0)';
      BIDIRECTIONAL='TRUE';
      INPUT_LOAD='(-0.01,0.01)';
      OUTPUT_LOAD='(1.0,-1.0)';
      PINUSE='BI';
    'DDR3_DQ'<7>:
      PIN_NUMBER='(0,0,0,0,0,CW84,0,0,0,0,0,0,0,0,0,0,0,0,0,0,0,0,0,0,0,0,0,0,0,~
0)';
      BIDIRECTIONAL='TRUE';
      INPUT_LOAD='(-0.01,0.01)';
      OUTPUT_LOAD='(1.0,-1.0)';
      PINUSE='BI';
    'DDR3_DQ'<6>:
      PIN_NUMBER='(0,0,0,0,0,CW86,0,0,0,0,0,0,0,0,0,0,0,0,0,0,0,0,0,0,0,0,0,0,0,~
0)';
      BIDIRECTIONAL='TRUE';
      INPUT_LOAD='(-0.01,0.01)';
      OUTPUT_LOAD='(1.0,-1.0)';
      PINUSE='BI';
    'DDR3_DQ'<5>:
      PIN_NUMBER='(0,0,0,0,0,CL86,0,0,0,0,0,0,0,0,0,0,0,0,0,0,0,0,0,0,0,0,0,0,0,~
0)';
      BIDIRECTIONAL='TRUE';
      INPUT_LOAD='(-0.01,0.01)';
      OUTPUT_LOAD='(1.0,-1.0)';
      PINUSE='BI';
    'DDR3_DQ'<4>:
      PIN_NUMBER='(0,0,0,0,0,CL84,0,0,0,0,0,0,0,0,0,0,0,0,0,0,0,0,0,0,0,0,0,0,0,~
0)';
      BIDIRECTIONAL='TRUE';
      INPUT_LOAD='(-0.01,0.01)';
      OUTPUT_LOAD='(1.0,-1.0)';
      PINUSE='BI';
    'DDR3_DQ'<3>:
      PIN_NUMBER='(0,0,0,0,0,DA84,0,0,0,0,0,0,0,0,0,0,0,0,0,0,0,0,0,0,0,0,0,0,0,~
0)';
      BIDIRECTIONAL='TRUE';
      INPUT_LOAD='(-0.01,0.01)';
      OUTPUT_LOAD='(1.0,-1.0)';
      PINUSE='BI';
    'DDR3_DQ'<2>:
      PIN_NUMBER='(0,0,0,0,0,DA86,0,0,0,0,0,0,0,0,0,0,0,0,0,0,0,0,0,0,0,0,0,0,0,~
0)';
      BIDIRECTIONAL='TRUE';
      INPUT_LOAD='(-0.01,0.01)';
      OUTPUT_LOAD='(1.0,-1.0)';
      PINUSE='BI';
    'DDR3_DQ'<1>:
      PIN_NUMBER='(0,0,0,0,0,CN86,0,0,0,0,0,0,0,0,0,0,0,0,0,0,0,0,0,0,0,0,0,0,0,~
0)';
      BIDIRECTIONAL='TRUE';
      INPUT_LOAD='(-0.01,0.01)';
      OUTPUT_LOAD='(1.0,-1.0)';
      PINUSE='BI';
    'DDR3_DQ'<0>:
      PIN_NUMBER='(0,0,0,0,0,CN84,0,0,0,0,0,0,0,0,0,0,0,0,0,0,0,0,0,0,0,0,0,0,0,~
0)';
      BIDIRECTIONAL='TRUE';
      INPUT_LOAD='(-0.01,0.01)';
      OUTPUT_LOAD='(1.0,-1.0)';
      PINUSE='BI';
    'DDR3_DQS_DN'<17>:
      PIN_NUMBER='(0,0,0,0,0,DB67,0,0,0,0,0,0,0,0,0,0,0,0,0,0,0,0,0,0,0,0,0,0,0,~
0)';
      BIDIRECTIONAL='TRUE';
      INPUT_LOAD='(-0.01,0.01)';
      OUTPUT_LOAD='(1.0,-1.0)';
      PINUSE='BI';
    'DDR3_DQS_DN'<16>:
      PIN_NUMBER='(0,0,0,0,0,DM23,0,0,0,0,0,0,0,0,0,0,0,0,0,0,0,0,0,0,0,0,0,0,0,~
0)';
      BIDIRECTIONAL='TRUE';
      INPUT_LOAD='(-0.01,0.01)';
      OUTPUT_LOAD='(1.0,-1.0)';
      PINUSE='BI';
    'DDR3_DQS_DN'<15>:
      PIN_NUMBER='(0,0,0,0,0,DM29,0,0,0,0,0,0,0,0,0,0,0,0,0,0,0,0,0,0,0,0,0,0,0,~
0)';
      BIDIRECTIONAL='TRUE';
      INPUT_LOAD='(-0.01,0.01)';
      OUTPUT_LOAD='(1.0,-1.0)';
      PINUSE='BI';
    'DDR3_DQS_DN'<14>:
      PIN_NUMBER='(0,0,0,0,0,DP35,0,0,0,0,0,0,0,0,0,0,0,0,0,0,0,0,0,0,0,0,0,0,0,~
0)';
      BIDIRECTIONAL='TRUE';
      INPUT_LOAD='(-0.01,0.01)';
      OUTPUT_LOAD='(1.0,-1.0)';
      PINUSE='BI';
    'DDR3_DQS_DN'<13>:
      PIN_NUMBER='(0,0,0,0,0,EA38,0,0,0,0,0,0,0,0,0,0,0,0,0,0,0,0,0,0,0,0,0,0,0,~
0)';
      BIDIRECTIONAL='TRUE';
      INPUT_LOAD='(-0.01,0.01)';
      OUTPUT_LOAD='(1.0,-1.0)';
      PINUSE='BI';
    'DDR3_DQS_DN'<12>:
      PIN_NUMBER='(0,0,0,0,0,DP75,0,0,0,0,0,0,0,0,0,0,0,0,0,0,0,0,0,0,0,0,0,0,0,~
0)';
      BIDIRECTIONAL='TRUE';
      INPUT_LOAD='(-0.01,0.01)';
      OUTPUT_LOAD='(1.0,-1.0)';
      PINUSE='BI';
    'DDR3_DQS_DN'<11>:
      PIN_NUMBER='(0,0,0,0,0,DN80,0,0,0,0,0,0,0,0,0,0,0,0,0,0,0,0,0,0,0,0,0,0,0,~
0)';
      BIDIRECTIONAL='TRUE';
      INPUT_LOAD='(-0.01,0.01)';
      OUTPUT_LOAD='(1.0,-1.0)';
      PINUSE='BI';
    'DDR3_DQS_DN'<10>:
      PIN_NUMBER='(0,0,0,0,0,DM85,0,0,0,0,0,0,0,0,0,0,0,0,0,0,0,0,0,0,0,0,0,0,0,~
0)';
      BIDIRECTIONAL='TRUE';
      INPUT_LOAD='(-0.01,0.01)';
      OUTPUT_LOAD='(1.0,-1.0)';
      PINUSE='BI';
    'DDR3_DQS_DN'<9>:
      PIN_NUMBER='(0,0,0,0,0,CR84,0,0,0,0,0,0,0,0,0,0,0,0,0,0,0,0,0,0,0,0,0,0,0,~
0)';
      BIDIRECTIONAL='TRUE';
      INPUT_LOAD='(-0.01,0.01)';
      OUTPUT_LOAD='(1.0,-1.0)';
      PINUSE='BI';
    'DDR3_DQS_DN'<8>:
      PIN_NUMBER='(0,0,0,0,0,DF67,0,0,0,0,0,0,0,0,0,0,0,0,0,0,0,0,0,0,0,0,0,0,0,~
0)';
      BIDIRECTIONAL='TRUE';
      INPUT_LOAD='(-0.01,0.01)';
      OUTPUT_LOAD='(1.0,-1.0)';
      PINUSE='BI';
    'DDR3_DQS_DN'<7>:
      PIN_NUMBER='(0,0,0,0,0,DV23,0,0,0,0,0,0,0,0,0,0,0,0,0,0,0,0,0,0,0,0,0,0,0,~
0)';
      BIDIRECTIONAL='TRUE';
      INPUT_LOAD='(-0.01,0.01)';
      OUTPUT_LOAD='(1.0,-1.0)';
      PINUSE='BI';
    'DDR3_DQS_DN'<6>:
      PIN_NUMBER='(0,0,0,0,0,DV29,0,0,0,0,0,0,0,0,0,0,0,0,0,0,0,0,0,0,0,0,0,0,0,~
0)';
      BIDIRECTIONAL='TRUE';
      INPUT_LOAD='(-0.01,0.01)';
      OUTPUT_LOAD='(1.0,-1.0)';
      PINUSE='BI';
    'DDR3_DQS_DN'<5>:
      PIN_NUMBER='(0,0,0,0,0,DV35,0,0,0,0,0,0,0,0,0,0,0,0,0,0,0,0,0,0,0,0,0,0,0,~
0)';
      BIDIRECTIONAL='TRUE';
      INPUT_LOAD='(-0.01,0.01)';
      OUTPUT_LOAD='(1.0,-1.0)';
      PINUSE='BI';
    'DDR3_DQS_DN'<4>:
      PIN_NUMBER='(0,0,0,0,0,EE38,0,0,0,0,0,0,0,0,0,0,0,0,0,0,0,0,0,0,0,0,0,0,0,~
0)';
      BIDIRECTIONAL='TRUE';
      INPUT_LOAD='(-0.01,0.01)';
      OUTPUT_LOAD='(1.0,-1.0)';
      PINUSE='BI';
    'DDR3_DQS_DN'<3>:
      PIN_NUMBER='(0,0,0,0,0,DV75,0,0,0,0,0,0,0,0,0,0,0,0,0,0,0,0,0,0,0,0,0,0,0,~
0)';
      BIDIRECTIONAL='TRUE';
      INPUT_LOAD='(-0.01,0.01)';
      OUTPUT_LOAD='(1.0,-1.0)';
      PINUSE='BI';
    'DDR3_DQS_DN'<2>:
      PIN_NUMBER='(0,0,0,0,0,DL82,0,0,0,0,0,0,0,0,0,0,0,0,0,0,0,0,0,0,0,0,0,0,0,~
0)';
      BIDIRECTIONAL='TRUE';
      INPUT_LOAD='(-0.01,0.01)';
      OUTPUT_LOAD='(1.0,-1.0)';
      PINUSE='BI';
    'DDR3_DQS_DN'<1>:
      PIN_NUMBER='(0,0,0,0,0,DN84,0,0,0,0,0,0,0,0,0,0,0,0,0,0,0,0,0,0,0,0,0,0,0,~
0)';
      BIDIRECTIONAL='TRUE';
      INPUT_LOAD='(-0.01,0.01)';
      OUTPUT_LOAD='(1.0,-1.0)';
      PINUSE='BI';
    'DDR3_DQS_DN'<0>:
      PIN_NUMBER='(0,0,0,0,0,CU84,0,0,0,0,0,0,0,0,0,0,0,0,0,0,0,0,0,0,0,0,0,0,0,~
0)';
      BIDIRECTIONAL='TRUE';
      INPUT_LOAD='(-0.01,0.01)';
      OUTPUT_LOAD='(1.0,-1.0)';
      PINUSE='BI';
    'DDR3_DQS_DP'<17>:
      PIN_NUMBER='(0,0,0,0,0,CY67,0,0,0,0,0,0,0,0,0,0,0,0,0,0,0,0,0,0,0,0,0,0,0,~
0)';
      BIDIRECTIONAL='TRUE';
      INPUT_LOAD='(-0.01,0.01)';
      OUTPUT_LOAD='(1.0,-1.0)';
      PINUSE='BI';
    'DDR3_DQS_DP'<16>:
      PIN_NUMBER='(0,0,0,0,0,DP23,0,0,0,0,0,0,0,0,0,0,0,0,0,0,0,0,0,0,0,0,0,0,0,~
0)';
      BIDIRECTIONAL='TRUE';
      INPUT_LOAD='(-0.01,0.01)';
      OUTPUT_LOAD='(1.0,-1.0)';
      PINUSE='BI';
    'DDR3_DQS_DP'<15>:
      PIN_NUMBER='(0,0,0,0,0,DP29,0,0,0,0,0,0,0,0,0,0,0,0,0,0,0,0,0,0,0,0,0,0,0,~
0)';
      BIDIRECTIONAL='TRUE';
      INPUT_LOAD='(-0.01,0.01)';
      OUTPUT_LOAD='(1.0,-1.0)';
      PINUSE='BI';
    'DDR3_DQS_DP'<14>:
      PIN_NUMBER='(0,0,0,0,0,DM35,0,0,0,0,0,0,0,0,0,0,0,0,0,0,0,0,0,0,0,0,0,0,0,~
0)';
      BIDIRECTIONAL='TRUE';
      INPUT_LOAD='(-0.01,0.01)';
      OUTPUT_LOAD='(1.0,-1.0)';
      PINUSE='BI';
    'DDR3_DQS_DP'<13>:
      PIN_NUMBER='(0,0,0,0,0,DW38,0,0,0,0,0,0,0,0,0,0,0,0,0,0,0,0,0,0,0,0,0,0,0,~
0)';
      BIDIRECTIONAL='TRUE';
      INPUT_LOAD='(-0.01,0.01)';
      OUTPUT_LOAD='(1.0,-1.0)';
      PINUSE='BI';
    'DDR3_DQS_DP'<12>:
      PIN_NUMBER='(0,0,0,0,0,DM75,0,0,0,0,0,0,0,0,0,0,0,0,0,0,0,0,0,0,0,0,0,0,0,~
0)';
      BIDIRECTIONAL='TRUE';
      INPUT_LOAD='(-0.01,0.01)';
      OUTPUT_LOAD='(1.0,-1.0)';
      PINUSE='BI';
    'DDR3_DQS_DP'<11>:
      PIN_NUMBER='(0,0,0,0,0,DP79,0,0,0,0,0,0,0,0,0,0,0,0,0,0,0,0,0,0,0,0,0,0,0,~
0)';
      BIDIRECTIONAL='TRUE';
      INPUT_LOAD='(-0.01,0.01)';
      OUTPUT_LOAD='(1.0,-1.0)';
      PINUSE='BI';
    'DDR3_DQS_DP'<10>:
      PIN_NUMBER='(0,0,0,0,0,DL84,0,0,0,0,0,0,0,0,0,0,0,0,0,0,0,0,0,0,0,0,0,0,0,~
0)';
      BIDIRECTIONAL='TRUE';
      INPUT_LOAD='(-0.01,0.01)';
      OUTPUT_LOAD='(1.0,-1.0)';
      PINUSE='BI';
    'DDR3_DQS_DP'<9>:
      PIN_NUMBER='(0,0,0,0,0,CP85,0,0,0,0,0,0,0,0,0,0,0,0,0,0,0,0,0,0,0,0,0,0,0,~
0)';
      BIDIRECTIONAL='TRUE';
      INPUT_LOAD='(-0.01,0.01)';
      OUTPUT_LOAD='(1.0,-1.0)';
      PINUSE='BI';
    'DDR3_DQS_DP'<8>:
      PIN_NUMBER='(0,0,0,0,0,DD67,0,0,0,0,0,0,0,0,0,0,0,0,0,0,0,0,0,0,0,0,0,0,0,~
0)';
      BIDIRECTIONAL='TRUE';
      INPUT_LOAD='(-0.01,0.01)';
      OUTPUT_LOAD='(1.0,-1.0)';
      PINUSE='BI';
    'DDR3_DQS_DP'<7>:
      PIN_NUMBER='(0,0,0,0,0,DT23,0,0,0,0,0,0,0,0,0,0,0,0,0,0,0,0,0,0,0,0,0,0,0,~
0)';
      BIDIRECTIONAL='TRUE';
      INPUT_LOAD='(-0.01,0.01)';
      OUTPUT_LOAD='(1.0,-1.0)';
      PINUSE='BI';
    'DDR3_DQS_DP'<6>:
      PIN_NUMBER='(0,0,0,0,0,DT29,0,0,0,0,0,0,0,0,0,0,0,0,0,0,0,0,0,0,0,0,0,0,0,~
0)';
      BIDIRECTIONAL='TRUE';
      INPUT_LOAD='(-0.01,0.01)';
      OUTPUT_LOAD='(1.0,-1.0)';
      PINUSE='BI';
    'DDR3_DQS_DP'<5>:
      PIN_NUMBER='(0,0,0,0,0,DT35,0,0,0,0,0,0,0,0,0,0,0,0,0,0,0,0,0,0,0,0,0,0,0,~
0)';
      BIDIRECTIONAL='TRUE';
      INPUT_LOAD='(-0.01,0.01)';
      OUTPUT_LOAD='(1.0,-1.0)';
      PINUSE='BI';
    'DDR3_DQS_DP'<4>:
      PIN_NUMBER='(0,0,0,0,0,EC38,0,0,0,0,0,0,0,0,0,0,0,0,0,0,0,0,0,0,0,0,0,0,0,~
0)';
      BIDIRECTIONAL='TRUE';
      INPUT_LOAD='(-0.01,0.01)';
      OUTPUT_LOAD='(1.0,-1.0)';
      PINUSE='BI';
    'DDR3_DQS_DP'<3>:
      PIN_NUMBER='(0,0,0,0,0,DT75,0,0,0,0,0,0,0,0,0,0,0,0,0,0,0,0,0,0,0,0,0,0,0,~
0)';
      BIDIRECTIONAL='TRUE';
      INPUT_LOAD='(-0.01,0.01)';
      OUTPUT_LOAD='(1.0,-1.0)';
      PINUSE='BI';
    'DDR3_DQS_DP'<2>:
      PIN_NUMBER='(0,0,0,0,0,DM81,0,0,0,0,0,0,0,0,0,0,0,0,0,0,0,0,0,0,0,0,0,0,0,~
0)';
      BIDIRECTIONAL='TRUE';
      INPUT_LOAD='(-0.01,0.01)';
      OUTPUT_LOAD='(1.0,-1.0)';
      PINUSE='BI';
    'DDR3_DQS_DP'<1>:
      PIN_NUMBER='(0,0,0,0,0,DP85,0,0,0,0,0,0,0,0,0,0,0,0,0,0,0,0,0,0,0,0,0,0,0,~
0)';
      BIDIRECTIONAL='TRUE';
      INPUT_LOAD='(-0.01,0.01)';
      OUTPUT_LOAD='(1.0,-1.0)';
      PINUSE='BI';
    'DDR3_DQS_DP'<0>:
      PIN_NUMBER='(0,0,0,0,0,CV85,0,0,0,0,0,0,0,0,0,0,0,0,0,0,0,0,0,0,0,0,0,0,0,~
0)';
      BIDIRECTIONAL='TRUE';
      INPUT_LOAD='(-0.01,0.01)';
      OUTPUT_LOAD='(1.0,-1.0)';
      PINUSE='BI';
    'DDR3_ECC'<7>:
      PIN_NUMBER='(0,0,0,0,0,DE66,0,0,0,0,0,0,0,0,0,0,0,0,0,0,0,0,0,0,0,0,0,0,0,~
0)';
      BIDIRECTIONAL='TRUE';
      INPUT_LOAD='(-0.01,0.01)';
      OUTPUT_LOAD='(1.0,-1.0)';
      PINUSE='BI';
    'DDR3_ECC'<6>:
      PIN_NUMBER='(0,0,0,0,0,DA66,0,0,0,0,0,0,0,0,0,0,0,0,0,0,0,0,0,0,0,0,0,0,0,~
0)';
      BIDIRECTIONAL='TRUE';
      INPUT_LOAD='(-0.01,0.01)';
      OUTPUT_LOAD='(1.0,-1.0)';
      PINUSE='BI';
    'DDR3_ECC'<5>:
      PIN_NUMBER='(0,0,0,0,0,DD69,0,0,0,0,0,0,0,0,0,0,0,0,0,0,0,0,0,0,0,0,0,0,0,~
0)';
      BIDIRECTIONAL='TRUE';
      INPUT_LOAD='(-0.01,0.01)';
      OUTPUT_LOAD='(1.0,-1.0)';
      PINUSE='BI';
    'DDR3_ECC'<4>:
      PIN_NUMBER='(0,0,0,0,0,DB69,0,0,0,0,0,0,0,0,0,0,0,0,0,0,0,0,0,0,0,0,0,0,0,~
0)';
      BIDIRECTIONAL='TRUE';
      INPUT_LOAD='(-0.01,0.01)';
      OUTPUT_LOAD='(1.0,-1.0)';
      PINUSE='BI';
    'DDR3_ECC'<3>:
      PIN_NUMBER='(0,0,0,0,0,DD65,0,0,0,0,0,0,0,0,0,0,0,0,0,0,0,0,0,0,0,0,0,0,0,~
0)';
      BIDIRECTIONAL='TRUE';
      INPUT_LOAD='(-0.01,0.01)';
      OUTPUT_LOAD='(1.0,-1.0)';
      PINUSE='BI';
    'DDR3_ECC'<2>:
      PIN_NUMBER='(0,0,0,0,0,DB65,0,0,0,0,0,0,0,0,0,0,0,0,0,0,0,0,0,0,0,0,0,0,0,~
0)';
      BIDIRECTIONAL='TRUE';
      INPUT_LOAD='(-0.01,0.01)';
      OUTPUT_LOAD='(1.0,-1.0)';
      PINUSE='BI';
    'DDR3_ECC'<1>:
      PIN_NUMBER='(0,0,0,0,0,DE68,0,0,0,0,0,0,0,0,0,0,0,0,0,0,0,0,0,0,0,0,0,0,0,~
0)';
      BIDIRECTIONAL='TRUE';
      INPUT_LOAD='(-0.01,0.01)';
      OUTPUT_LOAD='(1.0,-1.0)';
      PINUSE='BI';
    'DDR3_ECC'<0>:
      PIN_NUMBER='(0,0,0,0,0,DA68,0,0,0,0,0,0,0,0,0,0,0,0,0,0,0,0,0,0,0,0,0,0,0,~
0)';
      BIDIRECTIONAL='TRUE';
      INPUT_LOAD='(-0.01,0.01)';
      OUTPUT_LOAD='(1.0,-1.0)';
      PINUSE='BI';
    'DDR3_MA'<17>:
      PIN_NUMBER='(0,0,0,0,0,EA46,0,0,0,0,0,0,0,0,0,0,0,0,0,0,0,0,0,0,0,0,0,0,0,~
0)';
      OUTPUT_LOAD='(1.0,-1.0)';
      PINUSE='OUT';
    'DDR3_MA'<16>:
      PIN_NUMBER='(0,0,0,0,0,EA52,0,0,0,0,0,0,0,0,0,0,0,0,0,0,0,0,0,0,0,0,0,0,0,~
0)';
      OUTPUT_LOAD='(1.0,-1.0)';
      PINUSE='OUT';
    'DDR3_MA'<15>:
      PIN_NUMBER='(0,0,0,0,0,DV49,0,0,0,0,0,0,0,0,0,0,0,0,0,0,0,0,0,0,0,0,0,0,0,~
0)';
      OUTPUT_LOAD='(1.0,-1.0)';
      PINUSE='OUT';
    'DDR3_MA'<14>:
      PIN_NUMBER='(0,0,0,0,0,ED51,0,0,0,0,0,0,0,0,0,0,0,0,0,0,0,0,0,0,0,0,0,0,0,~
0)';
      OUTPUT_LOAD='(1.0,-1.0)';
      PINUSE='OUT';
    'DDR3_MA'<13>:
      PIN_NUMBER='(0,0,0,0,0,DW48,0,0,0,0,0,0,0,0,0,0,0,0,0,0,0,0,0,0,0,0,0,0,0,~
0)';
      OUTPUT_LOAD='(1.0,-1.0)';
      PINUSE='OUT';
    'DDR3_MA'<12>:
      PIN_NUMBER='(0,0,0,0,0,DT63,0,0,0,0,0,0,0,0,0,0,0,0,0,0,0,0,0,0,0,0,0,0,0,~
0)';
      OUTPUT_LOAD='(1.0,-1.0)';
      PINUSE='OUT';
    'DDR3_MA'<11>:
      PIN_NUMBER='(0,0,0,0,0,EB61,0,0,0,0,0,0,0,0,0,0,0,0,0,0,0,0,0,0,0,0,0,0,0,~
0)';
      OUTPUT_LOAD='(1.0,-1.0)';
      PINUSE='OUT';
    'DDR3_MA'<10>:
      PIN_NUMBER='(0,0,0,0,0,DW54,0,0,0,0,0,0,0,0,0,0,0,0,0,0,0,0,0,0,0,0,0,0,0,~
0)';
      OUTPUT_LOAD='(1.0,-1.0)';
      PINUSE='OUT';
    'DDR3_MA'<9>:
      PIN_NUMBER='(0,0,0,0,0,EF61,0,0,0,0,0,0,0,0,0,0,0,0,0,0,0,0,0,0,0,0,0,0,0,~
0)';
      OUTPUT_LOAD='(1.0,-1.0)';
      PINUSE='OUT';
    'DDR3_MA'<8>:
      PIN_NUMBER='(0,0,0,0,0,EB59,0,0,0,0,0,0,0,0,0,0,0,0,0,0,0,0,0,0,0,0,0,0,0,~
0)';
      OUTPUT_LOAD='(1.0,-1.0)';
      PINUSE='OUT';
    'DDR3_MA'<7>:
      PIN_NUMBER='(0,0,0,0,0,EA60,0,0,0,0,0,0,0,0,0,0,0,0,0,0,0,0,0,0,0,0,0,0,0,~
0)';
      OUTPUT_LOAD='(1.0,-1.0)';
      PINUSE='OUT';
    'DDR3_MA'<6>:
      PIN_NUMBER='(0,0,0,0,0,EE60,0,0,0,0,0,0,0,0,0,0,0,0,0,0,0,0,0,0,0,0,0,0,0,~
0)';
      OUTPUT_LOAD='(1.0,-1.0)';
      PINUSE='OUT';
    'DDR3_MA'<5>:
      PIN_NUMBER='(0,0,0,0,0,EA58,0,0,0,0,0,0,0,0,0,0,0,0,0,0,0,0,0,0,0,0,0,0,0,~
0)';
      OUTPUT_LOAD='(1.0,-1.0)';
      PINUSE='OUT';
    'DDR3_MA'<4>:
      PIN_NUMBER='(0,0,0,0,0,ED59,0,0,0,0,0,0,0,0,0,0,0,0,0,0,0,0,0,0,0,0,0,0,0,~
0)';
      OUTPUT_LOAD='(1.0,-1.0)';
      PINUSE='OUT';
    'DDR3_MA'<3>:
      PIN_NUMBER='(0,0,0,0,0,EB57,0,0,0,0,0,0,0,0,0,0,0,0,0,0,0,0,0,0,0,0,0,0,0,~
0)';
      OUTPUT_LOAD='(1.0,-1.0)';
      PINUSE='OUT';
    'DDR3_MA'<2>:
      PIN_NUMBER='(0,0,0,0,0,EE58,0,0,0,0,0,0,0,0,0,0,0,0,0,0,0,0,0,0,0,0,0,0,0,~
0)';
      OUTPUT_LOAD='(1.0,-1.0)';
      PINUSE='OUT';
    'DDR3_MA'<1>:
      PIN_NUMBER='(0,0,0,0,0,ED57,0,0,0,0,0,0,0,0,0,0,0,0,0,0,0,0,0,0,0,0,0,0,0,~
0)';
      OUTPUT_LOAD='(1.0,-1.0)';
      PINUSE='OUT';
    'DDR3_MA'<0>:
      PIN_NUMBER='(0,0,0,0,0,EB53,0,0,0,0,0,0,0,0,0,0,0,0,0,0,0,0,0,0,0,0,0,0,0,~
0)';
      OUTPUT_LOAD='(1.0,-1.0)';
      PINUSE='OUT';
    'DDR3_ODT'<3>:
      PIN_NUMBER='(0,0,0,0,0,EA48,0,0,0,0,0,0,0,0,0,0,0,0,0,0,0,0,0,0,0,0,0,0,0,~
0)';
      OUTPUT_LOAD='(1.0,-1.0)';
      PINUSE='OUT';
    'DDR3_ODT'<2>:
      PIN_NUMBER='(0,0,0,0,0,EA50,0,0,0,0,0,0,0,0,0,0,0,0,0,0,0,0,0,0,0,0,0,0,0,~
0)';
      OUTPUT_LOAD='(1.0,-1.0)';
      PINUSE='OUT';
    'DDR3_ODT'<1>:
      PIN_NUMBER='(0,0,0,0,0,EE48,0,0,0,0,0,0,0,0,0,0,0,0,0,0,0,0,0,0,0,0,0,0,0,~
0)';
      OUTPUT_LOAD='(1.0,-1.0)';
      PINUSE='OUT';
    'DDR3_ODT'<0>:
      PIN_NUMBER='(0,0,0,0,0,EE50,0,0,0,0,0,0,0,0,0,0,0,0,0,0,0,0,0,0,0,0,0,0,0,~
0)';
      OUTPUT_LOAD='(1.0,-1.0)';
      PINUSE='OUT';
    'DDR3_PAR':
      PIN_NUMBER='(0,0,0,0,0,ED53,0,0,0,0,0,0,0,0,0,0,0,0,0,0,0,0,0,0,0,0,0,0,0,~
0)';
      OUTPUT_LOAD='(1.0,-1.0)';
      PINUSE='OUT';
    'DDR4_ACT_N':
      PIN_NUMBER='(0,0,0,0,0,0,DR62,0,0,0,0,0,0,0,0,0,0,0,0,0,0,0,0,0,0,0,0,0,0,~
0)';
      OUTPUT_LOAD='(1.0,-1.0)';
      PINUSE='OUT';
    'DDR4_ALERT_N':
      PIN_NUMBER='(0,0,0,0,0,0,DT61,0,0,0,0,0,0,0,0,0,0,0,0,0,0,0,0,0,0,0,0,0,0,~
0)';
      INPUT_LOAD='(-0.01,0.01)';
      PINUSE='IN';
    'DDR4_BA'<1>:
      PIN_NUMBER='(0,0,0,0,0,0,DV55,0,0,0,0,0,0,0,0,0,0,0,0,0,0,0,0,0,0,0,0,0,0,~
0)';
      OUTPUT_LOAD='(1.0,-1.0)';
      PINUSE='OUT';
    'DDR4_BA'<0>:
      PIN_NUMBER='(0,0,0,0,0,0,DM53,0,0,0,0,0,0,0,0,0,0,0,0,0,0,0,0,0,0,0,0,0,0,~
0)';
      OUTPUT_LOAD='(1.0,-1.0)';
      PINUSE='OUT';
    'DDR4_BG'<1>:
      PIN_NUMBER='(0,0,0,0,0,0,DM61,0,0,0,0,0,0,0,0,0,0,0,0,0,0,0,0,0,0,0,0,0,0,~
0)';
      OUTPUT_LOAD='(1.0,-1.0)';
      PINUSE='OUT';
    'DDR4_BG'<0>:
      PIN_NUMBER='(0,0,0,0,0,0,DJ62,0,0,0,0,0,0,0,0,0,0,0,0,0,0,0,0,0,0,0,0,0,0,~
0)';
      OUTPUT_LOAD='(1.0,-1.0)';
      PINUSE='OUT';
    'DDR4_CAVREF':
      PIN_NUMBER='(CT61,0,0,0,0,0,0,0,0,0,0,0,0,0,0,0,0,0,0,0,0,0,0,0,0,0,0,0,0,~
0)';
      OUTPUT_LOAD='(1.0,-1.0)';
      PINUSE='OUT';
    'DDR4_CID'<2>:
      PIN_NUMBER='(0,0,0,0,0,0,DT47,0,0,0,0,0,0,0,0,0,0,0,0,0,0,0,0,0,0,0,0,0,0,~
0)';
      OUTPUT_LOAD='(1.0,-1.0)';
      PINUSE='OUT';
    'DDR4_CKE'<3>:
      PIN_NUMBER='(0,0,0,0,0,0,DR64,0,0,0,0,0,0,0,0,0,0,0,0,0,0,0,0,0,0,0,0,0,0,~
0)';
      OUTPUT_LOAD='(1.0,-1.0)';
      PINUSE='OUT';
    'DDR4_CKE'<2>:
      PIN_NUMBER='(0,0,0,0,0,0,DL64,0,0,0,0,0,0,0,0,0,0,0,0,0,0,0,0,0,0,0,0,0,0,~
0)';
      OUTPUT_LOAD='(1.0,-1.0)';
      PINUSE='OUT';
    'DDR4_CKE'<1>:
      PIN_NUMBER='(0,0,0,0,0,0,DN64,0,0,0,0,0,0,0,0,0,0,0,0,0,0,0,0,0,0,0,0,0,0,~
0)';
      OUTPUT_LOAD='(1.0,-1.0)';
      PINUSE='OUT';
    'DDR4_CKE'<0>:
      PIN_NUMBER='(0,0,0,0,0,0,DM63,0,0,0,0,0,0,0,0,0,0,0,0,0,0,0,0,0,0,0,0,0,0,~
0)';
      OUTPUT_LOAD='(1.0,-1.0)';
      PINUSE='OUT';
    'DDR4_CLK_DN'<3>:
      PIN_NUMBER='(0,0,0,0,0,0,DT57,0,0,0,0,0,0,0,0,0,0,0,0,0,0,0,0,0,0,0,0,0,0,~
0)';
      OUTPUT_LOAD='(1.0,-1.0)';
      PINUSE='OUT';
    'DDR4_CLK_DN'<2>:
      PIN_NUMBER='(0,0,0,0,0,0,DM57,0,0,0,0,0,0,0,0,0,0,0,0,0,0,0,0,0,0,0,0,0,0,~
0)';
      OUTPUT_LOAD='(1.0,-1.0)';
      PINUSE='OUT';
    'DDR4_CLK_DN'<1>:
      PIN_NUMBER='(0,0,0,0,0,0,DR54,0,0,0,0,0,0,0,0,0,0,0,0,0,0,0,0,0,0,0,0,0,0,~
0)';
      OUTPUT_LOAD='(1.0,-1.0)';
      PINUSE='OUT';
    'DDR4_CLK_DN'<0>:
      PIN_NUMBER='(0,0,0,0,0,0,DM55,0,0,0,0,0,0,0,0,0,0,0,0,0,0,0,0,0,0,0,0,0,0,~
0)';
      OUTPUT_LOAD='(1.0,-1.0)';
      PINUSE='OUT';
    'DDR4_CLK_DP'<3>:
      PIN_NUMBER='(0,0,0,0,0,0,DR56,0,0,0,0,0,0,0,0,0,0,0,0,0,0,0,0,0,0,0,0,0,0,~
0)';
      OUTPUT_LOAD='(1.0,-1.0)';
      PINUSE='OUT';
    'DDR4_CLK_DP'<2>:
      PIN_NUMBER='(0,0,0,0,0,0,DN56,0,0,0,0,0,0,0,0,0,0,0,0,0,0,0,0,0,0,0,0,0,0,~
0)';
      OUTPUT_LOAD='(1.0,-1.0)';
      PINUSE='OUT';
    'DDR4_CLK_DP'<1>:
      PIN_NUMBER='(0,0,0,0,0,0,DT53,0,0,0,0,0,0,0,0,0,0,0,0,0,0,0,0,0,0,0,0,0,0,~
0)';
      OUTPUT_LOAD='(1.0,-1.0)';
      PINUSE='OUT';
    'DDR4_CLK_DP'<0>:
      PIN_NUMBER='(0,0,0,0,0,0,DN54,0,0,0,0,0,0,0,0,0,0,0,0,0,0,0,0,0,0,0,0,0,0,~
0)';
      OUTPUT_LOAD='(1.0,-1.0)';
      PINUSE='OUT';
    'DDR4_CS_N'<7>:
      PIN_NUMBER='(0,0,0,0,0,0,DN46,0,0,0,0,0,0,0,0,0,0,0,0,0,0,0,0,0,0,0,0,0,0,~
0)';
      OUTPUT_LOAD='(1.0,-1.0)';
      PINUSE='OUT';
    'DDR4_CS_N'<6>:
      PIN_NUMBER='(0,0,0,0,0,0,DT45,0,0,0,0,0,0,0,0,0,0,0,0,0,0,0,0,0,0,0,0,0,0,~
0)';
      OUTPUT_LOAD='(1.0,-1.0)';
      PINUSE='OUT';
    'DDR4_CS_N'<5>:
      PIN_NUMBER='(0,0,0,0,0,0,DM49,0,0,0,0,0,0,0,0,0,0,0,0,0,0,0,0,0,0,0,0,0,0,~
0)';
      OUTPUT_LOAD='(1.0,-1.0)';
      PINUSE='OUT';
    'DDR4_CS_N'<4>:
      PIN_NUMBER='(0,0,0,0,0,0,DW50,0,0,0,0,0,0,0,0,0,0,0,0,0,0,0,0,0,0,0,0,0,0,~
0)';
      OUTPUT_LOAD='(1.0,-1.0)';
      PINUSE='OUT';
    'DDR4_CS_N'<3>:
      PIN_NUMBER='(0,0,0,0,0,0,DK47,0,0,0,0,0,0,0,0,0,0,0,0,0,0,0,0,0,0,0,0,0,0,~
0)';
      OUTPUT_LOAD='(1.0,-1.0)';
      PINUSE='OUT';
    'DDR4_CS_N'<2>:
      PIN_NUMBER='(0,0,0,0,0,0,DR46,0,0,0,0,0,0,0,0,0,0,0,0,0,0,0,0,0,0,0,0,0,0,~
0)';
      OUTPUT_LOAD='(1.0,-1.0)';
      PINUSE='OUT';
    'DDR4_CS_N'<1>:
      PIN_NUMBER='(0,0,0,0,0,0,DN50,0,0,0,0,0,0,0,0,0,0,0,0,0,0,0,0,0,0,0,0,0,0,~
0)';
      OUTPUT_LOAD='(1.0,-1.0)';
      PINUSE='OUT';
    'DDR4_CS_N'<0>:
      PIN_NUMBER='(0,0,0,0,0,0,DV51,0,0,0,0,0,0,0,0,0,0,0,0,0,0,0,0,0,0,0,0,0,0,~
0)';
      OUTPUT_LOAD='(1.0,-1.0)';
      PINUSE='OUT';
    'DDR4_DQ'<63>:
      PIN_NUMBER='(0,0,0,0,0,0,DK25,0,0,0,0,0,0,0,0,0,0,0,0,0,0,0,0,0,0,0,0,0,0,~
0)';
      BIDIRECTIONAL='TRUE';
      INPUT_LOAD='(-0.01,0.01)';
      OUTPUT_LOAD='(1.0,-1.0)';
      PINUSE='BI';
    'DDR4_DQ'<62>:
      PIN_NUMBER='(0,0,0,0,0,0,DF25,0,0,0,0,0,0,0,0,0,0,0,0,0,0,0,0,0,0,0,0,0,0,~
0)';
      BIDIRECTIONAL='TRUE';
      INPUT_LOAD='(-0.01,0.01)';
      OUTPUT_LOAD='(1.0,-1.0)';
      PINUSE='BI';
    'DDR4_DQ'<61>:
      PIN_NUMBER='(0,0,0,0,0,0,DJ28,0,0,0,0,0,0,0,0,0,0,0,0,0,0,0,0,0,0,0,0,0,0,~
0)';
      BIDIRECTIONAL='TRUE';
      INPUT_LOAD='(-0.01,0.01)';
      OUTPUT_LOAD='(1.0,-1.0)';
      PINUSE='BI';
    'DDR4_DQ'<60>:
      PIN_NUMBER='(0,0,0,0,0,0,DG28,0,0,0,0,0,0,0,0,0,0,0,0,0,0,0,0,0,0,0,0,0,0,~
0)';
      BIDIRECTIONAL='TRUE';
      INPUT_LOAD='(-0.01,0.01)';
      OUTPUT_LOAD='(1.0,-1.0)';
      PINUSE='BI';
    'DDR4_DQ'<59>:
      PIN_NUMBER='(0,0,0,0,0,0,DJ24,0,0,0,0,0,0,0,0,0,0,0,0,0,0,0,0,0,0,0,0,0,0,~
0)';
      BIDIRECTIONAL='TRUE';
      INPUT_LOAD='(-0.01,0.01)';
      OUTPUT_LOAD='(1.0,-1.0)';
      PINUSE='BI';
    'DDR4_DQ'<58>:
      PIN_NUMBER='(0,0,0,0,0,0,DD25,0,0,0,0,0,0,0,0,0,0,0,0,0,0,0,0,0,0,0,0,0,0,~
0)';
      BIDIRECTIONAL='TRUE';
      INPUT_LOAD='(-0.01,0.01)';
      OUTPUT_LOAD='(1.0,-1.0)';
      PINUSE='BI';
    'DDR4_DQ'<57>:
      PIN_NUMBER='(0,0,0,0,0,0,DK27,0,0,0,0,0,0,0,0,0,0,0,0,0,0,0,0,0,0,0,0,0,0,~
0)';
      BIDIRECTIONAL='TRUE';
      INPUT_LOAD='(-0.01,0.01)';
      OUTPUT_LOAD='(1.0,-1.0)';
      PINUSE='BI';
    'DDR4_DQ'<56>:
      PIN_NUMBER='(0,0,0,0,0,0,DF27,0,0,0,0,0,0,0,0,0,0,0,0,0,0,0,0,0,0,0,0,0,0,~
0)';
      BIDIRECTIONAL='TRUE';
      INPUT_LOAD='(-0.01,0.01)';
      OUTPUT_LOAD='(1.0,-1.0)';
      PINUSE='BI';
    'DDR4_DQ'<55>:
      PIN_NUMBER='(0,0,0,0,0,0,ED25,0,0,0,0,0,0,0,0,0,0,0,0,0,0,0,0,0,0,0,0,0,0,~
0)';
      BIDIRECTIONAL='TRUE';
      INPUT_LOAD='(-0.01,0.01)';
      OUTPUT_LOAD='(1.0,-1.0)';
      PINUSE='BI';
    'DDR4_DQ'<54>:
      PIN_NUMBER='(0,0,0,0,0,0,DY25,0,0,0,0,0,0,0,0,0,0,0,0,0,0,0,0,0,0,0,0,0,0,~
0)';
      BIDIRECTIONAL='TRUE';
      INPUT_LOAD='(-0.01,0.01)';
      OUTPUT_LOAD='(1.0,-1.0)';
      PINUSE='BI';
    'DDR4_DQ'<53>:
      PIN_NUMBER='(0,0,0,0,0,0,EA28,0,0,0,0,0,0,0,0,0,0,0,0,0,0,0,0,0,0,0,0,0,0,~
0)';
      BIDIRECTIONAL='TRUE';
      INPUT_LOAD='(-0.01,0.01)';
      OUTPUT_LOAD='(1.0,-1.0)';
      PINUSE='BI';
    'DDR4_DQ'<52>:
      PIN_NUMBER='(0,0,0,0,0,0,DY27,0,0,0,0,0,0,0,0,0,0,0,0,0,0,0,0,0,0,0,0,0,0,~
0)';
      BIDIRECTIONAL='TRUE';
      INPUT_LOAD='(-0.01,0.01)';
      OUTPUT_LOAD='(1.0,-1.0)';
      PINUSE='BI';
    'DDR4_DQ'<51>:
      PIN_NUMBER='(0,0,0,0,0,0,EC24,0,0,0,0,0,0,0,0,0,0,0,0,0,0,0,0,0,0,0,0,0,0,~
0)';
      BIDIRECTIONAL='TRUE';
      INPUT_LOAD='(-0.01,0.01)';
      OUTPUT_LOAD='(1.0,-1.0)';
      PINUSE='BI';
    'DDR4_DQ'<50>:
      PIN_NUMBER='(0,0,0,0,0,0,EA24,0,0,0,0,0,0,0,0,0,0,0,0,0,0,0,0,0,0,0,0,0,0,~
0)';
      BIDIRECTIONAL='TRUE';
      INPUT_LOAD='(-0.01,0.01)';
      OUTPUT_LOAD='(1.0,-1.0)';
      PINUSE='BI';
    'DDR4_DQ'<49>:
      PIN_NUMBER='(0,0,0,0,0,0,ED27,0,0,0,0,0,0,0,0,0,0,0,0,0,0,0,0,0,0,0,0,0,0,~
0)';
      BIDIRECTIONAL='TRUE';
      INPUT_LOAD='(-0.01,0.01)';
      OUTPUT_LOAD='(1.0,-1.0)';
      PINUSE='BI';
    'DDR4_DQ'<48>:
      PIN_NUMBER='(0,0,0,0,0,0,EC28,0,0,0,0,0,0,0,0,0,0,0,0,0,0,0,0,0,0,0,0,0,0,~
0)';
      BIDIRECTIONAL='TRUE';
      INPUT_LOAD='(-0.01,0.01)';
      OUTPUT_LOAD='(1.0,-1.0)';
      PINUSE='BI';
    'DDR4_DQ'<47>:
      PIN_NUMBER='(0,0,0,0,0,0,ED31,0,0,0,0,0,0,0,0,0,0,0,0,0,0,0,0,0,0,0,0,0,0,~
0)';
      BIDIRECTIONAL='TRUE';
      INPUT_LOAD='(-0.01,0.01)';
      OUTPUT_LOAD='(1.0,-1.0)';
      PINUSE='BI';
    'DDR4_DQ'<46>:
      PIN_NUMBER='(0,0,0,0,0,0,DY31,0,0,0,0,0,0,0,0,0,0,0,0,0,0,0,0,0,0,0,0,0,0,~
0)';
      BIDIRECTIONAL='TRUE';
      INPUT_LOAD='(-0.01,0.01)';
      OUTPUT_LOAD='(1.0,-1.0)';
      PINUSE='BI';
    'DDR4_DQ'<45>:
      PIN_NUMBER='(0,0,0,0,0,0,EA34,0,0,0,0,0,0,0,0,0,0,0,0,0,0,0,0,0,0,0,0,0,0,~
0)';
      BIDIRECTIONAL='TRUE';
      INPUT_LOAD='(-0.01,0.01)';
      OUTPUT_LOAD='(1.0,-1.0)';
      PINUSE='BI';
    'DDR4_DQ'<44>:
      PIN_NUMBER='(0,0,0,0,0,0,DY33,0,0,0,0,0,0,0,0,0,0,0,0,0,0,0,0,0,0,0,0,0,0,~
0)';
      BIDIRECTIONAL='TRUE';
      INPUT_LOAD='(-0.01,0.01)';
      OUTPUT_LOAD='(1.0,-1.0)';
      PINUSE='BI';
    'DDR4_DQ'<43>:
      PIN_NUMBER='(0,0,0,0,0,0,EC30,0,0,0,0,0,0,0,0,0,0,0,0,0,0,0,0,0,0,0,0,0,0,~
0)';
      BIDIRECTIONAL='TRUE';
      INPUT_LOAD='(-0.01,0.01)';
      OUTPUT_LOAD='(1.0,-1.0)';
      PINUSE='BI';
    'DDR4_DQ'<42>:
      PIN_NUMBER='(0,0,0,0,0,0,EA30,0,0,0,0,0,0,0,0,0,0,0,0,0,0,0,0,0,0,0,0,0,0,~
0)';
      BIDIRECTIONAL='TRUE';
      INPUT_LOAD='(-0.01,0.01)';
      OUTPUT_LOAD='(1.0,-1.0)';
      PINUSE='BI';
    'DDR4_DQ'<41>:
      PIN_NUMBER='(0,0,0,0,0,0,ED33,0,0,0,0,0,0,0,0,0,0,0,0,0,0,0,0,0,0,0,0,0,0,~
0)';
      BIDIRECTIONAL='TRUE';
      INPUT_LOAD='(-0.01,0.01)';
      OUTPUT_LOAD='(1.0,-1.0)';
      PINUSE='BI';
    'DDR4_DQ'<40>:
      PIN_NUMBER='(0,0,0,0,0,0,EC34,0,0,0,0,0,0,0,0,0,0,0,0,0,0,0,0,0,0,0,0,0,0,~
0)';
      BIDIRECTIONAL='TRUE';
      INPUT_LOAD='(-0.01,0.01)';
      OUTPUT_LOAD='(1.0,-1.0)';
      PINUSE='BI';
    'DDR4_DQ'<39>:
      PIN_NUMBER='(0,0,0,0,0,0,DU40,0,0,0,0,0,0,0,0,0,0,0,0,0,0,0,0,0,0,0,0,0,0,~
0)';
      BIDIRECTIONAL='TRUE';
      INPUT_LOAD='(-0.01,0.01)';
      OUTPUT_LOAD='(1.0,-1.0)';
      PINUSE='BI';
    'DDR4_DQ'<38>:
      PIN_NUMBER='(0,0,0,0,0,0,DN40,0,0,0,0,0,0,0,0,0,0,0,0,0,0,0,0,0,0,0,0,0,0,~
0)';
      BIDIRECTIONAL='TRUE';
      INPUT_LOAD='(-0.01,0.01)';
      OUTPUT_LOAD='(1.0,-1.0)';
      PINUSE='BI';
    'DDR4_DQ'<37>:
      PIN_NUMBER='(0,0,0,0,0,0,DN42,0,0,0,0,0,0,0,0,0,0,0,0,0,0,0,0,0,0,0,0,0,0,~
0)';
      BIDIRECTIONAL='TRUE';
      INPUT_LOAD='(-0.01,0.01)';
      OUTPUT_LOAD='(1.0,-1.0)';
      PINUSE='BI';
    'DDR4_DQ'<36>:
      PIN_NUMBER='(0,0,0,0,0,0,DL42,0,0,0,0,0,0,0,0,0,0,0,0,0,0,0,0,0,0,0,0,0,0,~
0)';
      BIDIRECTIONAL='TRUE';
      INPUT_LOAD='(-0.01,0.01)';
      OUTPUT_LOAD='(1.0,-1.0)';
      PINUSE='BI';
    'DDR4_DQ'<35>:
      PIN_NUMBER='(0,0,0,0,0,0,DT39,0,0,0,0,0,0,0,0,0,0,0,0,0,0,0,0,0,0,0,0,0,0,~
0)';
      BIDIRECTIONAL='TRUE';
      INPUT_LOAD='(-0.01,0.01)';
      OUTPUT_LOAD='(1.0,-1.0)';
      PINUSE='BI';
    'DDR4_DQ'<34>:
      PIN_NUMBER='(0,0,0,0,0,0,DP39,0,0,0,0,0,0,0,0,0,0,0,0,0,0,0,0,0,0,0,0,0,0,~
0)';
      BIDIRECTIONAL='TRUE';
      INPUT_LOAD='(-0.01,0.01)';
      OUTPUT_LOAD='(1.0,-1.0)';
      PINUSE='BI';
    'DDR4_DQ'<33>:
      PIN_NUMBER='(0,0,0,0,0,0,DW42,0,0,0,0,0,0,0,0,0,0,0,0,0,0,0,0,0,0,0,0,0,0,~
0)';
      BIDIRECTIONAL='TRUE';
      INPUT_LOAD='(-0.01,0.01)';
      OUTPUT_LOAD='(1.0,-1.0)';
      PINUSE='BI';
    'DDR4_DQ'<32>:
      PIN_NUMBER='(0,0,0,0,0,0,DU42,0,0,0,0,0,0,0,0,0,0,0,0,0,0,0,0,0,0,0,0,0,0,~
0)';
      BIDIRECTIONAL='TRUE';
      INPUT_LOAD='(-0.01,0.01)';
      OUTPUT_LOAD='(1.0,-1.0)';
      PINUSE='BI';
    'DDR4_DQ'<31>:
      PIN_NUMBER='(0,0,0,0,0,0,EE72,0,0,0,0,0,0,0,0,0,0,0,0,0,0,0,0,0,0,0,0,0,0,~
0)';
      BIDIRECTIONAL='TRUE';
      INPUT_LOAD='(-0.01,0.01)';
      OUTPUT_LOAD='(1.0,-1.0)';
      PINUSE='BI';
    'DDR4_DQ'<30>:
      PIN_NUMBER='(0,0,0,0,0,0,EA72,0,0,0,0,0,0,0,0,0,0,0,0,0,0,0,0,0,0,0,0,0,0,~
0)';
      BIDIRECTIONAL='TRUE';
      INPUT_LOAD='(-0.01,0.01)';
      OUTPUT_LOAD='(1.0,-1.0)';
      PINUSE='BI';
    'DDR4_DQ'<29>:
      PIN_NUMBER='(0,0,0,0,0,0,EB75,0,0,0,0,0,0,0,0,0,0,0,0,0,0,0,0,0,0,0,0,0,0,~
0)';
      BIDIRECTIONAL='TRUE';
      INPUT_LOAD='(-0.01,0.01)';
      OUTPUT_LOAD='(1.0,-1.0)';
      PINUSE='BI';
    'DDR4_DQ'<28>:
      PIN_NUMBER='(0,0,0,0,0,0,EA74,0,0,0,0,0,0,0,0,0,0,0,0,0,0,0,0,0,0,0,0,0,0,~
0)';
      BIDIRECTIONAL='TRUE';
      INPUT_LOAD='(-0.01,0.01)';
      OUTPUT_LOAD='(1.0,-1.0)';
      PINUSE='BI';
    'DDR4_DQ'<27>:
      PIN_NUMBER='(0,0,0,0,0,0,ED71,0,0,0,0,0,0,0,0,0,0,0,0,0,0,0,0,0,0,0,0,0,0,~
0)';
      BIDIRECTIONAL='TRUE';
      INPUT_LOAD='(-0.01,0.01)';
      OUTPUT_LOAD='(1.0,-1.0)';
      PINUSE='BI';
    'DDR4_DQ'<26>:
      PIN_NUMBER='(0,0,0,0,0,0,EB71,0,0,0,0,0,0,0,0,0,0,0,0,0,0,0,0,0,0,0,0,0,0,~
0)';
      BIDIRECTIONAL='TRUE';
      INPUT_LOAD='(-0.01,0.01)';
      OUTPUT_LOAD='(1.0,-1.0)';
      PINUSE='BI';
    'DDR4_DQ'<25>:
      PIN_NUMBER='(0,0,0,0,0,0,EE74,0,0,0,0,0,0,0,0,0,0,0,0,0,0,0,0,0,0,0,0,0,0,~
0)';
      BIDIRECTIONAL='TRUE';
      INPUT_LOAD='(-0.01,0.01)';
      OUTPUT_LOAD='(1.0,-1.0)';
      PINUSE='BI';
    'DDR4_DQ'<24>:
      PIN_NUMBER='(0,0,0,0,0,0,ED75,0,0,0,0,0,0,0,0,0,0,0,0,0,0,0,0,0,0,0,0,0,0,~
0)';
      BIDIRECTIONAL='TRUE';
      INPUT_LOAD='(-0.01,0.01)';
      OUTPUT_LOAD='(1.0,-1.0)';
      PINUSE='BI';
    'DDR4_DQ'<23>:
      PIN_NUMBER='(0,0,0,0,0,0,EC78,0,0,0,0,0,0,0,0,0,0,0,0,0,0,0,0,0,0,0,0,0,0,~
0)';
      BIDIRECTIONAL='TRUE';
      INPUT_LOAD='(-0.01,0.01)';
      OUTPUT_LOAD='(1.0,-1.0)';
      PINUSE='BI';
    'DDR4_DQ'<22>:
      PIN_NUMBER='(0,0,0,0,0,0,DW78,0,0,0,0,0,0,0,0,0,0,0,0,0,0,0,0,0,0,0,0,0,0,~
0)';
      BIDIRECTIONAL='TRUE';
      INPUT_LOAD='(-0.01,0.01)';
      OUTPUT_LOAD='(1.0,-1.0)';
      PINUSE='BI';
    'DDR4_DQ'<21>:
      PIN_NUMBER='(0,0,0,0,0,0,EB81,0,0,0,0,0,0,0,0,0,0,0,0,0,0,0,0,0,0,0,0,0,0,~
0)';
      BIDIRECTIONAL='TRUE';
      INPUT_LOAD='(-0.01,0.01)';
      OUTPUT_LOAD='(1.0,-1.0)';
      PINUSE='BI';
    'DDR4_DQ'<20>:
      PIN_NUMBER='(0,0,0,0,0,0,DY81,0,0,0,0,0,0,0,0,0,0,0,0,0,0,0,0,0,0,0,0,0,0,~
0)';
      BIDIRECTIONAL='TRUE';
      INPUT_LOAD='(-0.01,0.01)';
      OUTPUT_LOAD='(1.0,-1.0)';
      PINUSE='BI';
    'DDR4_DQ'<19>:
      PIN_NUMBER='(0,0,0,0,0,0,EB77,0,0,0,0,0,0,0,0,0,0,0,0,0,0,0,0,0,0,0,0,0,0,~
0)';
      BIDIRECTIONAL='TRUE';
      INPUT_LOAD='(-0.01,0.01)';
      OUTPUT_LOAD='(1.0,-1.0)';
      PINUSE='BI';
    'DDR4_DQ'<18>:
      PIN_NUMBER='(0,0,0,0,0,0,DY77,0,0,0,0,0,0,0,0,0,0,0,0,0,0,0,0,0,0,0,0,0,0,~
0)';
      BIDIRECTIONAL='TRUE';
      INPUT_LOAD='(-0.01,0.01)';
      OUTPUT_LOAD='(1.0,-1.0)';
      PINUSE='BI';
    'DDR4_DQ'<17>:
      PIN_NUMBER='(0,0,0,0,0,0,EC80,0,0,0,0,0,0,0,0,0,0,0,0,0,0,0,0,0,0,0,0,0,0,~
0)';
      BIDIRECTIONAL='TRUE';
      INPUT_LOAD='(-0.01,0.01)';
      OUTPUT_LOAD='(1.0,-1.0)';
      PINUSE='BI';
    'DDR4_DQ'<16>:
      PIN_NUMBER='(0,0,0,0,0,0,DW80,0,0,0,0,0,0,0,0,0,0,0,0,0,0,0,0,0,0,0,0,0,0,~
0)';
      BIDIRECTIONAL='TRUE';
      INPUT_LOAD='(-0.01,0.01)';
      OUTPUT_LOAD='(1.0,-1.0)';
      PINUSE='BI';
    'DDR4_DQ'<15>:
      PIN_NUMBER='(0,0,0,0,0,0,DE82,0,0,0,0,0,0,0,0,0,0,0,0,0,0,0,0,0,0,0,0,0,0,~
0)';
      BIDIRECTIONAL='TRUE';
      INPUT_LOAD='(-0.01,0.01)';
      OUTPUT_LOAD='(1.0,-1.0)';
      PINUSE='BI';
    'DDR4_DQ'<14>:
      PIN_NUMBER='(0,0,0,0,0,0,DC82,0,0,0,0,0,0,0,0,0,0,0,0,0,0,0,0,0,0,0,0,0,0,~
0)';
      BIDIRECTIONAL='TRUE';
      INPUT_LOAD='(-0.01,0.01)';
      OUTPUT_LOAD='(1.0,-1.0)';
      PINUSE='BI';
    'DDR4_DQ'<13>:
      PIN_NUMBER='(0,0,0,0,0,0,CW80,0,0,0,0,0,0,0,0,0,0,0,0,0,0,0,0,0,0,0,0,0,0,~
0)';
      BIDIRECTIONAL='TRUE';
      INPUT_LOAD='(-0.01,0.01)';
      OUTPUT_LOAD='(1.0,-1.0)';
      PINUSE='BI';
    'DDR4_DQ'<12>:
      PIN_NUMBER='(0,0,0,0,0,0,CY79,0,0,0,0,0,0,0,0,0,0,0,0,0,0,0,0,0,0,0,0,0,0,~
0)';
      BIDIRECTIONAL='TRUE';
      INPUT_LOAD='(-0.01,0.01)';
      OUTPUT_LOAD='(1.0,-1.0)';
      PINUSE='BI';
    'DDR4_DQ'<11>:
      PIN_NUMBER='(0,0,0,0,0,0,DF81,0,0,0,0,0,0,0,0,0,0,0,0,0,0,0,0,0,0,0,0,0,0,~
0)';
      BIDIRECTIONAL='TRUE';
      INPUT_LOAD='(-0.01,0.01)';
      OUTPUT_LOAD='(1.0,-1.0)';
      PINUSE='BI';
    'DDR4_DQ'<10>:
      PIN_NUMBER='(0,0,0,0,0,0,DE80,0,0,0,0,0,0,0,0,0,0,0,0,0,0,0,0,0,0,0,0,0,0,~
0)';
      BIDIRECTIONAL='TRUE';
      INPUT_LOAD='(-0.01,0.01)';
      OUTPUT_LOAD='(1.0,-1.0)';
      PINUSE='BI';
    'DDR4_DQ'<9>:
      PIN_NUMBER='(0,0,0,0,0,0,CY81,0,0,0,0,0,0,0,0,0,0,0,0,0,0,0,0,0,0,0,0,0,0,~
0)';
      BIDIRECTIONAL='TRUE';
      INPUT_LOAD='(-0.01,0.01)';
      OUTPUT_LOAD='(1.0,-1.0)';
      PINUSE='BI';
    'DDR4_DQ'<8>:
      PIN_NUMBER='(0,0,0,0,0,0,DB79,0,0,0,0,0,0,0,0,0,0,0,0,0,0,0,0,0,0,0,0,0,0,~
0)';
      BIDIRECTIONAL='TRUE';
      INPUT_LOAD='(-0.01,0.01)';
      OUTPUT_LOAD='(1.0,-1.0)';
      PINUSE='BI';
    'DDR4_DQ'<7>:
      PIN_NUMBER='(0,0,0,0,0,0,CN82,0,0,0,0,0,0,0,0,0,0,0,0,0,0,0,0,0,0,0,0,0,0,~
0)';
      BIDIRECTIONAL='TRUE';
      INPUT_LOAD='(-0.01,0.01)';
      OUTPUT_LOAD='(1.0,-1.0)';
      PINUSE='BI';
    'DDR4_DQ'<6>:
      PIN_NUMBER='(0,0,0,0,0,0,CR80,0,0,0,0,0,0,0,0,0,0,0,0,0,0,0,0,0,0,0,0,0,0,~
0)';
      BIDIRECTIONAL='TRUE';
      INPUT_LOAD='(-0.01,0.01)';
      OUTPUT_LOAD='(1.0,-1.0)';
      PINUSE='BI';
    'DDR4_DQ'<5>:
      PIN_NUMBER='(0,0,0,0,0,0,CJ80,0,0,0,0,0,0,0,0,0,0,0,0,0,0,0,0,0,0,0,0,0,0,~
0)';
      BIDIRECTIONAL='TRUE';
      INPUT_LOAD='(-0.01,0.01)';
      OUTPUT_LOAD='(1.0,-1.0)';
      PINUSE='BI';
    'DDR4_DQ'<4>:
      PIN_NUMBER='(0,0,0,0,0,0,CK79,0,0,0,0,0,0,0,0,0,0,0,0,0,0,0,0,0,0,0,0,0,0,~
0)';
      BIDIRECTIONAL='TRUE';
      INPUT_LOAD='(-0.01,0.01)';
      OUTPUT_LOAD='(1.0,-1.0)';
      PINUSE='BI';
    'DDR4_DQ'<3>:
      PIN_NUMBER='(0,0,0,0,0,0,CR82,0,0,0,0,0,0,0,0,0,0,0,0,0,0,0,0,0,0,0,0,0,0,~
0)';
      BIDIRECTIONAL='TRUE';
      INPUT_LOAD='(-0.01,0.01)';
      OUTPUT_LOAD='(1.0,-1.0)';
      PINUSE='BI';
    'DDR4_DQ'<2>:
      PIN_NUMBER='(0,0,0,0,0,0,CT81,0,0,0,0,0,0,0,0,0,0,0,0,0,0,0,0,0,0,0,0,0,0,~
0)';
      BIDIRECTIONAL='TRUE';
      INPUT_LOAD='(-0.01,0.01)';
      OUTPUT_LOAD='(1.0,-1.0)';
      PINUSE='BI';
    'DDR4_DQ'<1>:
      PIN_NUMBER='(0,0,0,0,0,0,CK81,0,0,0,0,0,0,0,0,0,0,0,0,0,0,0,0,0,0,0,0,0,0,~
0)';
      BIDIRECTIONAL='TRUE';
      INPUT_LOAD='(-0.01,0.01)';
      OUTPUT_LOAD='(1.0,-1.0)';
      PINUSE='BI';
    'DDR4_DQ'<0>:
      PIN_NUMBER='(0,0,0,0,0,0,CM79,0,0,0,0,0,0,0,0,0,0,0,0,0,0,0,0,0,0,0,0,0,0,~
0)';
      BIDIRECTIONAL='TRUE';
      INPUT_LOAD='(-0.01,0.01)';
      OUTPUT_LOAD='(1.0,-1.0)';
      PINUSE='BI';
    'DDR4_DQS_DN'<17>:
      PIN_NUMBER='(0,0,0,0,0,0,DV67,0,0,0,0,0,0,0,0,0,0,0,0,0,0,0,0,0,0,0,0,0,0,~
0)';
      BIDIRECTIONAL='TRUE';
      INPUT_LOAD='(-0.01,0.01)';
      OUTPUT_LOAD='(1.0,-1.0)';
      PINUSE='BI';
    'DDR4_DQS_DN'<16>:
      PIN_NUMBER='(0,0,0,0,0,0,DG26,0,0,0,0,0,0,0,0,0,0,0,0,0,0,0,0,0,0,0,0,0,0,~
0)';
      BIDIRECTIONAL='TRUE';
      INPUT_LOAD='(-0.01,0.01)';
      OUTPUT_LOAD='(1.0,-1.0)';
      PINUSE='BI';
    'DDR4_DQS_DN'<15>:
      PIN_NUMBER='(0,0,0,0,0,0,EA26,0,0,0,0,0,0,0,0,0,0,0,0,0,0,0,0,0,0,0,0,0,0,~
0)';
      BIDIRECTIONAL='TRUE';
      INPUT_LOAD='(-0.01,0.01)';
      OUTPUT_LOAD='(1.0,-1.0)';
      PINUSE='BI';
    'DDR4_DQS_DN'<14>:
      PIN_NUMBER='(0,0,0,0,0,0,EA32,0,0,0,0,0,0,0,0,0,0,0,0,0,0,0,0,0,0,0,0,0,0,~
0)';
      BIDIRECTIONAL='TRUE';
      INPUT_LOAD='(-0.01,0.01)';
      OUTPUT_LOAD='(1.0,-1.0)';
      PINUSE='BI';
    'DDR4_DQS_DN'<13>:
      PIN_NUMBER='(0,0,0,0,0,0,DP41,0,0,0,0,0,0,0,0,0,0,0,0,0,0,0,0,0,0,0,0,0,0,~
0)';
      BIDIRECTIONAL='TRUE';
      INPUT_LOAD='(-0.01,0.01)';
      OUTPUT_LOAD='(1.0,-1.0)';
      PINUSE='BI';
    'DDR4_DQS_DN'<12>:
      PIN_NUMBER='(0,0,0,0,0,0,EB73,0,0,0,0,0,0,0,0,0,0,0,0,0,0,0,0,0,0,0,0,0,0,~
0)';
      BIDIRECTIONAL='TRUE';
      INPUT_LOAD='(-0.01,0.01)';
      OUTPUT_LOAD='(1.0,-1.0)';
      PINUSE='BI';
    'DDR4_DQS_DN'<11>:
      PIN_NUMBER='(0,0,0,0,0,0,DY79,0,0,0,0,0,0,0,0,0,0,0,0,0,0,0,0,0,0,0,0,0,0,~
0)';
      BIDIRECTIONAL='TRUE';
      INPUT_LOAD='(-0.01,0.01)';
      OUTPUT_LOAD='(1.0,-1.0)';
      PINUSE='BI';
    'DDR4_DQS_DN'<10>:
      PIN_NUMBER='(0,0,0,0,0,0,DC80,0,0,0,0,0,0,0,0,0,0,0,0,0,0,0,0,0,0,0,0,0,0,~
0)';
      BIDIRECTIONAL='TRUE';
      INPUT_LOAD='(-0.01,0.01)';
      OUTPUT_LOAD='(1.0,-1.0)';
      PINUSE='BI';
    'DDR4_DQS_DN'<9>:
      PIN_NUMBER='(0,0,0,0,0,0,CN80,0,0,0,0,0,0,0,0,0,0,0,0,0,0,0,0,0,0,0,0,0,0,~
0)';
      BIDIRECTIONAL='TRUE';
      INPUT_LOAD='(-0.01,0.01)';
      OUTPUT_LOAD='(1.0,-1.0)';
      PINUSE='BI';
    'DDR4_DQS_DN'<8>:
      PIN_NUMBER='(0,0,0,0,0,0,EB67,0,0,0,0,0,0,0,0,0,0,0,0,0,0,0,0,0,0,0,0,0,0,~
0)';
      BIDIRECTIONAL='TRUE';
      INPUT_LOAD='(-0.01,0.01)';
      OUTPUT_LOAD='(1.0,-1.0)';
      PINUSE='BI';
    'DDR4_DQS_DN'<7>:
      PIN_NUMBER='(0,0,0,0,0,0,DL26,0,0,0,0,0,0,0,0,0,0,0,0,0,0,0,0,0,0,0,0,0,0,~
0)';
      BIDIRECTIONAL='TRUE';
      INPUT_LOAD='(-0.01,0.01)';
      OUTPUT_LOAD='(1.0,-1.0)';
      PINUSE='BI';
    'DDR4_DQS_DN'<6>:
      PIN_NUMBER='(0,0,0,0,0,0,EE26,0,0,0,0,0,0,0,0,0,0,0,0,0,0,0,0,0,0,0,0,0,0,~
0)';
      BIDIRECTIONAL='TRUE';
      INPUT_LOAD='(-0.01,0.01)';
      OUTPUT_LOAD='(1.0,-1.0)';
      PINUSE='BI';
    'DDR4_DQS_DN'<5>:
      PIN_NUMBER='(0,0,0,0,0,0,EE32,0,0,0,0,0,0,0,0,0,0,0,0,0,0,0,0,0,0,0,0,0,0,~
0)';
      BIDIRECTIONAL='TRUE';
      INPUT_LOAD='(-0.01,0.01)';
      OUTPUT_LOAD='(1.0,-1.0)';
      PINUSE='BI';
    'DDR4_DQS_DN'<4>:
      PIN_NUMBER='(0,0,0,0,0,0,DV41,0,0,0,0,0,0,0,0,0,0,0,0,0,0,0,0,0,0,0,0,0,0,~
0)';
      BIDIRECTIONAL='TRUE';
      INPUT_LOAD='(-0.01,0.01)';
      OUTPUT_LOAD='(1.0,-1.0)';
      PINUSE='BI';
    'DDR4_DQS_DN'<3>:
      PIN_NUMBER='(0,0,0,0,0,0,EF73,0,0,0,0,0,0,0,0,0,0,0,0,0,0,0,0,0,0,0,0,0,0,~
0)';
      BIDIRECTIONAL='TRUE';
      INPUT_LOAD='(-0.01,0.01)';
      OUTPUT_LOAD='(1.0,-1.0)';
      PINUSE='BI';
    'DDR4_DQS_DN'<2>:
      PIN_NUMBER='(0,0,0,0,0,0,ED79,0,0,0,0,0,0,0,0,0,0,0,0,0,0,0,0,0,0,0,0,0,0,~
0)';
      BIDIRECTIONAL='TRUE';
      INPUT_LOAD='(-0.01,0.01)';
      OUTPUT_LOAD='(1.0,-1.0)';
      PINUSE='BI';
    'DDR4_DQS_DN'<1>:
      PIN_NUMBER='(0,0,0,0,0,0,DA82,0,0,0,0,0,0,0,0,0,0,0,0,0,0,0,0,0,0,0,0,0,0,~
0)';
      BIDIRECTIONAL='TRUE';
      INPUT_LOAD='(-0.01,0.01)';
      OUTPUT_LOAD='(1.0,-1.0)';
      PINUSE='BI';
    'DDR4_DQS_DN'<0>:
      PIN_NUMBER='(0,0,0,0,0,0,CL82,0,0,0,0,0,0,0,0,0,0,0,0,0,0,0,0,0,0,0,0,0,0,~
0)';
      BIDIRECTIONAL='TRUE';
      INPUT_LOAD='(-0.01,0.01)';
      OUTPUT_LOAD='(1.0,-1.0)';
      PINUSE='BI';
    'DDR4_DQS_DP'<17>:
      PIN_NUMBER='(0,0,0,0,0,0,DT67,0,0,0,0,0,0,0,0,0,0,0,0,0,0,0,0,0,0,0,0,0,0,~
0)';
      BIDIRECTIONAL='TRUE';
      INPUT_LOAD='(-0.01,0.01)';
      OUTPUT_LOAD='(1.0,-1.0)';
      PINUSE='BI';
    'DDR4_DQS_DP'<16>:
      PIN_NUMBER='(0,0,0,0,0,0,DE26,0,0,0,0,0,0,0,0,0,0,0,0,0,0,0,0,0,0,0,0,0,0,~
0)';
      BIDIRECTIONAL='TRUE';
      INPUT_LOAD='(-0.01,0.01)';
      OUTPUT_LOAD='(1.0,-1.0)';
      PINUSE='BI';
    'DDR4_DQS_DP'<15>:
      PIN_NUMBER='(0,0,0,0,0,0,DW26,0,0,0,0,0,0,0,0,0,0,0,0,0,0,0,0,0,0,0,0,0,0,~
0)';
      BIDIRECTIONAL='TRUE';
      INPUT_LOAD='(-0.01,0.01)';
      OUTPUT_LOAD='(1.0,-1.0)';
      PINUSE='BI';
    'DDR4_DQS_DP'<14>:
      PIN_NUMBER='(0,0,0,0,0,0,DW32,0,0,0,0,0,0,0,0,0,0,0,0,0,0,0,0,0,0,0,0,0,0,~
0)';
      BIDIRECTIONAL='TRUE';
      INPUT_LOAD='(-0.01,0.01)';
      OUTPUT_LOAD='(1.0,-1.0)';
      PINUSE='BI';
    'DDR4_DQS_DP'<13>:
      PIN_NUMBER='(0,0,0,0,0,0,DM41,0,0,0,0,0,0,0,0,0,0,0,0,0,0,0,0,0,0,0,0,0,0,~
0)';
      BIDIRECTIONAL='TRUE';
      INPUT_LOAD='(-0.01,0.01)';
      OUTPUT_LOAD='(1.0,-1.0)';
      PINUSE='BI';
    'DDR4_DQS_DP'<12>:
      PIN_NUMBER='(0,0,0,0,0,0,DY73,0,0,0,0,0,0,0,0,0,0,0,0,0,0,0,0,0,0,0,0,0,0,~
0)';
      BIDIRECTIONAL='TRUE';
      INPUT_LOAD='(-0.01,0.01)';
      OUTPUT_LOAD='(1.0,-1.0)';
      PINUSE='BI';
    'DDR4_DQS_DP'<11>:
      PIN_NUMBER='(0,0,0,0,0,0,DV79,0,0,0,0,0,0,0,0,0,0,0,0,0,0,0,0,0,0,0,0,0,0,~
0)';
      BIDIRECTIONAL='TRUE';
      INPUT_LOAD='(-0.01,0.01)';
      OUTPUT_LOAD='(1.0,-1.0)';
      PINUSE='BI';
    'DDR4_DQS_DP'<10>:
      PIN_NUMBER='(0,0,0,0,0,0,DD79,0,0,0,0,0,0,0,0,0,0,0,0,0,0,0,0,0,0,0,0,0,0,~
0)';
      BIDIRECTIONAL='TRUE';
      INPUT_LOAD='(-0.01,0.01)';
      OUTPUT_LOAD='(1.0,-1.0)';
      PINUSE='BI';
    'DDR4_DQS_DP'<9>:
      PIN_NUMBER='(0,0,0,0,0,0,CP79,0,0,0,0,0,0,0,0,0,0,0,0,0,0,0,0,0,0,0,0,0,0,~
0)';
      BIDIRECTIONAL='TRUE';
      INPUT_LOAD='(-0.01,0.01)';
      OUTPUT_LOAD='(1.0,-1.0)';
      PINUSE='BI';
    'DDR4_DQS_DP'<8>:
      PIN_NUMBER='(0,0,0,0,0,0,DY67,0,0,0,0,0,0,0,0,0,0,0,0,0,0,0,0,0,0,0,0,0,0,~
0)';
      BIDIRECTIONAL='TRUE';
      INPUT_LOAD='(-0.01,0.01)';
      OUTPUT_LOAD='(1.0,-1.0)';
      PINUSE='BI';
    'DDR4_DQS_DP'<7>:
      PIN_NUMBER='(0,0,0,0,0,0,DJ26,0,0,0,0,0,0,0,0,0,0,0,0,0,0,0,0,0,0,0,0,0,0,~
0)';
      BIDIRECTIONAL='TRUE';
      INPUT_LOAD='(-0.01,0.01)';
      OUTPUT_LOAD='(1.0,-1.0)';
      PINUSE='BI';
    'DDR4_DQS_DP'<6>:
      PIN_NUMBER='(0,0,0,0,0,0,EC26,0,0,0,0,0,0,0,0,0,0,0,0,0,0,0,0,0,0,0,0,0,0,~
0)';
      BIDIRECTIONAL='TRUE';
      INPUT_LOAD='(-0.01,0.01)';
      OUTPUT_LOAD='(1.0,-1.0)';
      PINUSE='BI';
    'DDR4_DQS_DP'<5>:
      PIN_NUMBER='(0,0,0,0,0,0,EC32,0,0,0,0,0,0,0,0,0,0,0,0,0,0,0,0,0,0,0,0,0,0,~
0)';
      BIDIRECTIONAL='TRUE';
      INPUT_LOAD='(-0.01,0.01)';
      OUTPUT_LOAD='(1.0,-1.0)';
      PINUSE='BI';
    'DDR4_DQS_DP'<4>:
      PIN_NUMBER='(0,0,0,0,0,0,DT41,0,0,0,0,0,0,0,0,0,0,0,0,0,0,0,0,0,0,0,0,0,0,~
0)';
      BIDIRECTIONAL='TRUE';
      INPUT_LOAD='(-0.01,0.01)';
      OUTPUT_LOAD='(1.0,-1.0)';
      PINUSE='BI';
    'DDR4_DQS_DP'<3>:
      PIN_NUMBER='(0,0,0,0,0,0,ED73,0,0,0,0,0,0,0,0,0,0,0,0,0,0,0,0,0,0,0,0,0,0,~
0)';
      BIDIRECTIONAL='TRUE';
      INPUT_LOAD='(-0.01,0.01)';
      OUTPUT_LOAD='(1.0,-1.0)';
      PINUSE='BI';
    'DDR4_DQS_DP'<2>:
      PIN_NUMBER='(0,0,0,0,0,0,EB79,0,0,0,0,0,0,0,0,0,0,0,0,0,0,0,0,0,0,0,0,0,0,~
0)';
      BIDIRECTIONAL='TRUE';
      INPUT_LOAD='(-0.01,0.01)';
      OUTPUT_LOAD='(1.0,-1.0)';
      PINUSE='BI';
    'DDR4_DQS_DP'<1>:
      PIN_NUMBER='(0,0,0,0,0,0,DB81,0,0,0,0,0,0,0,0,0,0,0,0,0,0,0,0,0,0,0,0,0,0,~
0)';
      BIDIRECTIONAL='TRUE';
      INPUT_LOAD='(-0.01,0.01)';
      OUTPUT_LOAD='(1.0,-1.0)';
      PINUSE='BI';
    'DDR4_DQS_DP'<0>:
      PIN_NUMBER='(0,0,0,0,0,0,CM81,0,0,0,0,0,0,0,0,0,0,0,0,0,0,0,0,0,0,0,0,0,0,~
0)';
      BIDIRECTIONAL='TRUE';
      INPUT_LOAD='(-0.01,0.01)';
      OUTPUT_LOAD='(1.0,-1.0)';
      PINUSE='BI';
    'DDR4_ECC'<7>:
      PIN_NUMBER='(0,0,0,0,0,0,EA66,0,0,0,0,0,0,0,0,0,0,0,0,0,0,0,0,0,0,0,0,0,0,~
0)';
      BIDIRECTIONAL='TRUE';
      INPUT_LOAD='(-0.01,0.01)';
      OUTPUT_LOAD='(1.0,-1.0)';
      PINUSE='BI';
    'DDR4_ECC'<6>:
      PIN_NUMBER='(0,0,0,0,0,0,DU66,0,0,0,0,0,0,0,0,0,0,0,0,0,0,0,0,0,0,0,0,0,0,~
0)';
      BIDIRECTIONAL='TRUE';
      INPUT_LOAD='(-0.01,0.01)';
      OUTPUT_LOAD='(1.0,-1.0)';
      PINUSE='BI';
    'DDR4_ECC'<5>:
      PIN_NUMBER='(0,0,0,0,0,0,DV69,0,0,0,0,0,0,0,0,0,0,0,0,0,0,0,0,0,0,0,0,0,0,~
0)';
      BIDIRECTIONAL='TRUE';
      INPUT_LOAD='(-0.01,0.01)';
      OUTPUT_LOAD='(1.0,-1.0)';
      PINUSE='BI';
    'DDR4_ECC'<4>:
      PIN_NUMBER='(0,0,0,0,0,0,DU68,0,0,0,0,0,0,0,0,0,0,0,0,0,0,0,0,0,0,0,0,0,0,~
0)';
      BIDIRECTIONAL='TRUE';
      INPUT_LOAD='(-0.01,0.01)';
      OUTPUT_LOAD='(1.0,-1.0)';
      PINUSE='BI';
    'DDR4_ECC'<3>:
      PIN_NUMBER='(0,0,0,0,0,0,DY65,0,0,0,0,0,0,0,0,0,0,0,0,0,0,0,0,0,0,0,0,0,0,~
0)';
      BIDIRECTIONAL='TRUE';
      INPUT_LOAD='(-0.01,0.01)';
      OUTPUT_LOAD='(1.0,-1.0)';
      PINUSE='BI';
    'DDR4_ECC'<2>:
      PIN_NUMBER='(0,0,0,0,0,0,DV65,0,0,0,0,0,0,0,0,0,0,0,0,0,0,0,0,0,0,0,0,0,0,~
0)';
      BIDIRECTIONAL='TRUE';
      INPUT_LOAD='(-0.01,0.01)';
      OUTPUT_LOAD='(1.0,-1.0)';
      PINUSE='BI';
    'DDR4_ECC'<1>:
      PIN_NUMBER='(0,0,0,0,0,0,EA68,0,0,0,0,0,0,0,0,0,0,0,0,0,0,0,0,0,0,0,0,0,0,~
0)';
      BIDIRECTIONAL='TRUE';
      INPUT_LOAD='(-0.01,0.01)';
      OUTPUT_LOAD='(1.0,-1.0)';
      PINUSE='BI';
    'DDR4_ECC'<0>:
      PIN_NUMBER='(0,0,0,0,0,0,DY69,0,0,0,0,0,0,0,0,0,0,0,0,0,0,0,0,0,0,0,0,0,0,~
0)';
      BIDIRECTIONAL='TRUE';
      INPUT_LOAD='(-0.01,0.01)';
      OUTPUT_LOAD='(1.0,-1.0)';
      PINUSE='BI';
    'DDR4_MA'<17>:
      PIN_NUMBER='(0,0,0,0,0,0,DR48,0,0,0,0,0,0,0,0,0,0,0,0,0,0,0,0,0,0,0,0,0,0,~
0)';
      OUTPUT_LOAD='(1.0,-1.0)';
      PINUSE='OUT';
    'DDR4_MA'<16>:
      PIN_NUMBER='(0,0,0,0,0,0,DN52,0,0,0,0,0,0,0,0,0,0,0,0,0,0,0,0,0,0,0,0,0,0,~
0)';
      OUTPUT_LOAD='(1.0,-1.0)';
      PINUSE='OUT';
    'DDR4_MA'<15>:
      PIN_NUMBER='(0,0,0,0,0,0,DR52,0,0,0,0,0,0,0,0,0,0,0,0,0,0,0,0,0,0,0,0,0,0,~
0)';
      OUTPUT_LOAD='(1.0,-1.0)';
      PINUSE='OUT';
    'DDR4_MA'<14>:
      PIN_NUMBER='(0,0,0,0,0,0,DM51,0,0,0,0,0,0,0,0,0,0,0,0,0,0,0,0,0,0,0,0,0,0,~
0)';
      OUTPUT_LOAD='(1.0,-1.0)';
      PINUSE='OUT';
    'DDR4_MA'<13>:
      PIN_NUMBER='(0,0,0,0,0,0,DT51,0,0,0,0,0,0,0,0,0,0,0,0,0,0,0,0,0,0,0,0,0,0,~
0)';
      OUTPUT_LOAD='(1.0,-1.0)';
      PINUSE='OUT';
    'DDR4_MA'<12>:
      PIN_NUMBER='(0,0,0,0,0,0,DN60,0,0,0,0,0,0,0,0,0,0,0,0,0,0,0,0,0,0,0,0,0,0,~
0)';
      OUTPUT_LOAD='(1.0,-1.0)';
      PINUSE='OUT';
    'DDR4_MA'<11>:
      PIN_NUMBER='(0,0,0,0,0,0,DR60,0,0,0,0,0,0,0,0,0,0,0,0,0,0,0,0,0,0,0,0,0,0,~
0)';
      OUTPUT_LOAD='(1.0,-1.0)';
      PINUSE='OUT';
    'DDR4_MA'<10>:
      PIN_NUMBER='(0,0,0,0,0,0,DT55,0,0,0,0,0,0,0,0,0,0,0,0,0,0,0,0,0,0,0,0,0,0,~
0)';
      OUTPUT_LOAD='(1.0,-1.0)';
      PINUSE='OUT';
    'DDR4_MA'<9>:
      PIN_NUMBER='(0,0,0,0,0,0,DV59,0,0,0,0,0,0,0,0,0,0,0,0,0,0,0,0,0,0,0,0,0,0,~
0)';
      OUTPUT_LOAD='(1.0,-1.0)';
      PINUSE='OUT';
    'DDR4_MA'<8>:
      PIN_NUMBER='(0,0,0,0,0,0,DJ60,0,0,0,0,0,0,0,0,0,0,0,0,0,0,0,0,0,0,0,0,0,0,~
0)';
      OUTPUT_LOAD='(1.0,-1.0)';
      PINUSE='OUT';
    'DDR4_MA'<7>:
      PIN_NUMBER='(0,0,0,0,0,0,DK61,0,0,0,0,0,0,0,0,0,0,0,0,0,0,0,0,0,0,0,0,0,0,~
0)';
      OUTPUT_LOAD='(1.0,-1.0)';
      PINUSE='OUT';
    'DDR4_MA'<6>:
      PIN_NUMBER='(0,0,0,0,0,0,DM59,0,0,0,0,0,0,0,0,0,0,0,0,0,0,0,0,0,0,0,0,0,0,~
0)';
      OUTPUT_LOAD='(1.0,-1.0)';
      PINUSE='OUT';
    'DDR4_MA'<5>:
      PIN_NUMBER='(0,0,0,0,0,0,DN58,0,0,0,0,0,0,0,0,0,0,0,0,0,0,0,0,0,0,0,0,0,0,~
0)';
      OUTPUT_LOAD='(1.0,-1.0)';
      PINUSE='OUT';
    'DDR4_MA'<4>:
      PIN_NUMBER='(0,0,0,0,0,0,DT59,0,0,0,0,0,0,0,0,0,0,0,0,0,0,0,0,0,0,0,0,0,0,~
0)';
      OUTPUT_LOAD='(1.0,-1.0)';
      PINUSE='OUT';
    'DDR4_MA'<3>:
      PIN_NUMBER='(0,0,0,0,0,0,DR58,0,0,0,0,0,0,0,0,0,0,0,0,0,0,0,0,0,0,0,0,0,0,~
0)';
      OUTPUT_LOAD='(1.0,-1.0)';
      PINUSE='OUT';
    'DDR4_MA'<2>:
      PIN_NUMBER='(0,0,0,0,0,0,DV57,0,0,0,0,0,0,0,0,0,0,0,0,0,0,0,0,0,0,0,0,0,0,~
0)';
      OUTPUT_LOAD='(1.0,-1.0)';
      PINUSE='OUT';
    'DDR4_MA'<1>:
      PIN_NUMBER='(0,0,0,0,0,0,DW58,0,0,0,0,0,0,0,0,0,0,0,0,0,0,0,0,0,0,0,0,0,0,~
0)';
      OUTPUT_LOAD='(1.0,-1.0)';
      PINUSE='OUT';
    'DDR4_MA'<0>:
      PIN_NUMBER='(0,0,0,0,0,0,DW52,0,0,0,0,0,0,0,0,0,0,0,0,0,0,0,0,0,0,0,0,0,0,~
0)';
      OUTPUT_LOAD='(1.0,-1.0)';
      PINUSE='OUT';
    'DDR4_ODT'<3>:
      PIN_NUMBER='(0,0,0,0,0,0,DM47,0,0,0,0,0,0,0,0,0,0,0,0,0,0,0,0,0,0,0,0,0,0,~
0)';
      OUTPUT_LOAD='(1.0,-1.0)';
      PINUSE='OUT';
    'DDR4_ODT'<2>:
      PIN_NUMBER='(0,0,0,0,0,0,DT49,0,0,0,0,0,0,0,0,0,0,0,0,0,0,0,0,0,0,0,0,0,0,~
0)';
      OUTPUT_LOAD='(1.0,-1.0)';
      PINUSE='OUT';
    'DDR4_ODT'<1>:
      PIN_NUMBER='(0,0,0,0,0,0,DN48,0,0,0,0,0,0,0,0,0,0,0,0,0,0,0,0,0,0,0,0,0,0,~
0)';
      OUTPUT_LOAD='(1.0,-1.0)';
      PINUSE='OUT';
    'DDR4_ODT'<0>:
      PIN_NUMBER='(0,0,0,0,0,0,DR50,0,0,0,0,0,0,0,0,0,0,0,0,0,0,0,0,0,0,0,0,0,0,~
0)';
      OUTPUT_LOAD='(1.0,-1.0)';
      PINUSE='OUT';
    'DDR4_PAR':
      PIN_NUMBER='(0,0,0,0,0,0,DV53,0,0,0,0,0,0,0,0,0,0,0,0,0,0,0,0,0,0,0,0,0,0,~
0)';
      OUTPUT_LOAD='(1.0,-1.0)';
      PINUSE='OUT';
    'DDR5_ACT_N':
      PIN_NUMBER='(0,0,0,0,0,0,0,DC62,0,0,0,0,0,0,0,0,0,0,0,0,0,0,0,0,0,0,0,0,0,~
0)';
      OUTPUT_LOAD='(1.0,-1.0)';
      PINUSE='OUT';
    'DDR5_ALERT_N':
      PIN_NUMBER='(0,0,0,0,0,0,0,DD61,0,0,0,0,0,0,0,0,0,0,0,0,0,0,0,0,0,0,0,0,0,~
0)';
      INPUT_LOAD='(-0.01,0.01)';
      PINUSE='IN';
    'DDR5_BA'<1>:
      PIN_NUMBER='(0,0,0,0,0,0,0,DC56,0,0,0,0,0,0,0,0,0,0,0,0,0,0,0,0,0,0,0,0,0,~
0)';
      OUTPUT_LOAD='(1.0,-1.0)';
      PINUSE='OUT';
    'DDR5_BA'<0>:
      PIN_NUMBER='(0,0,0,0,0,0,0,DJ52,0,0,0,0,0,0,0,0,0,0,0,0,0,0,0,0,0,0,0,0,0,~
0)';
      OUTPUT_LOAD='(1.0,-1.0)';
      PINUSE='OUT';
    'DDR5_BG'<1>:
      PIN_NUMBER='(0,0,0,0,0,0,0,DF61,0,0,0,0,0,0,0,0,0,0,0,0,0,0,0,0,0,0,0,0,0,~
0)';
      OUTPUT_LOAD='(1.0,-1.0)';
      PINUSE='OUT';
    'DDR5_BG'<0>:
      PIN_NUMBER='(0,0,0,0,0,0,0,DA62,0,0,0,0,0,0,0,0,0,0,0,0,0,0,0,0,0,0,0,0,0,~
0)';
      OUTPUT_LOAD='(1.0,-1.0)';
      PINUSE='OUT';
    'DDR5_CAVREF':
      PIN_NUMBER='(CV61,0,0,0,0,0,0,0,0,0,0,0,0,0,0,0,0,0,0,0,0,0,0,0,0,0,0,0,0,~
0)';
      OUTPUT_LOAD='(1.0,-1.0)';
      PINUSE='OUT';
    'DDR5_CID'<2>:
      PIN_NUMBER='(0,0,0,0,0,0,0,DF45,0,0,0,0,0,0,0,0,0,0,0,0,0,0,0,0,0,0,0,0,0,~
0)';
      OUTPUT_LOAD='(1.0,-1.0)';
      PINUSE='OUT';
    'DDR5_CKE'<3>:
      PIN_NUMBER='(0,0,0,0,0,0,0,DF63,0,0,0,0,0,0,0,0,0,0,0,0,0,0,0,0,0,0,0,0,0,~
0)';
      OUTPUT_LOAD='(1.0,-1.0)';
      PINUSE='OUT';
    'DDR5_CKE'<2>:
      PIN_NUMBER='(0,0,0,0,0,0,0,DK63,0,0,0,0,0,0,0,0,0,0,0,0,0,0,0,0,0,0,0,0,0,~
0)';
      OUTPUT_LOAD='(1.0,-1.0)';
      PINUSE='OUT';
    'DDR5_CKE'<1>:
      PIN_NUMBER='(0,0,0,0,0,0,0,DD63,0,0,0,0,0,0,0,0,0,0,0,0,0,0,0,0,0,0,0,0,0,~
0)';
      OUTPUT_LOAD='(1.0,-1.0)';
      PINUSE='OUT';
    'DDR5_CKE'<0>:
      PIN_NUMBER='(0,0,0,0,0,0,0,DG62,0,0,0,0,0,0,0,0,0,0,0,0,0,0,0,0,0,0,0,0,0,~
0)';
      OUTPUT_LOAD='(1.0,-1.0)';
      PINUSE='OUT';
    'DDR5_CLK_DN'<3>:
      PIN_NUMBER='(0,0,0,0,0,0,0,DF57,0,0,0,0,0,0,0,0,0,0,0,0,0,0,0,0,0,0,0,0,0,~
0)';
      OUTPUT_LOAD='(1.0,-1.0)';
      PINUSE='OUT';
    'DDR5_CLK_DN'<2>:
      PIN_NUMBER='(0,0,0,0,0,0,0,DK57,0,0,0,0,0,0,0,0,0,0,0,0,0,0,0,0,0,0,0,0,0,~
0)';
      OUTPUT_LOAD='(1.0,-1.0)';
      PINUSE='OUT';
    'DDR5_CLK_DN'<1>:
      PIN_NUMBER='(0,0,0,0,0,0,0,DF55,0,0,0,0,0,0,0,0,0,0,0,0,0,0,0,0,0,0,0,0,0,~
0)';
      OUTPUT_LOAD='(1.0,-1.0)';
      PINUSE='OUT';
    'DDR5_CLK_DN'<0>:
      PIN_NUMBER='(0,0,0,0,0,0,0,DK55,0,0,0,0,0,0,0,0,0,0,0,0,0,0,0,0,0,0,0,0,0,~
0)';
      OUTPUT_LOAD='(1.0,-1.0)';
      PINUSE='OUT';
    'DDR5_CLK_DP'<3>:
      PIN_NUMBER='(0,0,0,0,0,0,0,DG56,0,0,0,0,0,0,0,0,0,0,0,0,0,0,0,0,0,0,0,0,0,~
0)';
      OUTPUT_LOAD='(1.0,-1.0)';
      PINUSE='OUT';
    'DDR5_CLK_DP'<2>:
      PIN_NUMBER='(0,0,0,0,0,0,0,DJ56,0,0,0,0,0,0,0,0,0,0,0,0,0,0,0,0,0,0,0,0,0,~
0)';
      OUTPUT_LOAD='(1.0,-1.0)';
      PINUSE='OUT';
    'DDR5_CLK_DP'<1>:
      PIN_NUMBER='(0,0,0,0,0,0,0,DG54,0,0,0,0,0,0,0,0,0,0,0,0,0,0,0,0,0,0,0,0,0,~
0)';
      OUTPUT_LOAD='(1.0,-1.0)';
      PINUSE='OUT';
    'DDR5_CLK_DP'<0>:
      PIN_NUMBER='(0,0,0,0,0,0,0,DJ54,0,0,0,0,0,0,0,0,0,0,0,0,0,0,0,0,0,0,0,0,0,~
0)';
      OUTPUT_LOAD='(1.0,-1.0)';
      PINUSE='OUT';
    'DDR5_CS_N'<7>:
      PIN_NUMBER='(0,0,0,0,0,0,0,DK45,0,0,0,0,0,0,0,0,0,0,0,0,0,0,0,0,0,0,0,0,0,~
0)';
      OUTPUT_LOAD='(1.0,-1.0)';
      PINUSE='OUT';
    'DDR5_CS_N'<6>:
      PIN_NUMBER='(0,0,0,0,0,0,0,DM45,0,0,0,0,0,0,0,0,0,0,0,0,0,0,0,0,0,0,0,0,0,~
0)';
      OUTPUT_LOAD='(1.0,-1.0)';
      PINUSE='OUT';
    'DDR5_CS_N'<5>:
      PIN_NUMBER='(0,0,0,0,0,0,0,DJ48,0,0,0,0,0,0,0,0,0,0,0,0,0,0,0,0,0,0,0,0,0,~
0)';
      OUTPUT_LOAD='(1.0,-1.0)';
      PINUSE='OUT';
    'DDR5_CS_N'<4>:
      PIN_NUMBER='(0,0,0,0,0,0,0,DF51,0,0,0,0,0,0,0,0,0,0,0,0,0,0,0,0,0,0,0,0,0,~
0)';
      OUTPUT_LOAD='(1.0,-1.0)';
      PINUSE='OUT';
    'DDR5_CS_N'<3>:
      PIN_NUMBER='(0,0,0,0,0,0,0,DG46,0,0,0,0,0,0,0,0,0,0,0,0,0,0,0,0,0,0,0,0,0,~
0)';
      OUTPUT_LOAD='(1.0,-1.0)';
      PINUSE='OUT';
    'DDR5_CS_N'<2>:
      PIN_NUMBER='(0,0,0,0,0,0,0,DJ46,0,0,0,0,0,0,0,0,0,0,0,0,0,0,0,0,0,0,0,0,0,~
0)';
      OUTPUT_LOAD='(1.0,-1.0)';
      PINUSE='OUT';
    'DDR5_CS_N'<1>:
      PIN_NUMBER='(0,0,0,0,0,0,0,DF49,0,0,0,0,0,0,0,0,0,0,0,0,0,0,0,0,0,0,0,0,0,~
0)';
      OUTPUT_LOAD='(1.0,-1.0)';
      PINUSE='OUT';
    'DDR5_CS_N'<0>:
      PIN_NUMBER='(0,0,0,0,0,0,0,DK51,0,0,0,0,0,0,0,0,0,0,0,0,0,0,0,0,0,0,0,0,0,~
0)';
      OUTPUT_LOAD='(1.0,-1.0)';
      PINUSE='OUT';
    'DDR5_DQ'<63>:
      PIN_NUMBER='(0,0,0,0,0,0,0,DC28,0,0,0,0,0,0,0,0,0,0,0,0,0,0,0,0,0,0,0,0,0,~
0)';
      BIDIRECTIONAL='TRUE';
      INPUT_LOAD='(-0.01,0.01)';
      OUTPUT_LOAD='(1.0,-1.0)';
      PINUSE='BI';
    'DDR5_DQ'<62>:
      PIN_NUMBER='(0,0,0,0,0,0,0,CW28,0,0,0,0,0,0,0,0,0,0,0,0,0,0,0,0,0,0,0,0,0,~
0)';
      BIDIRECTIONAL='TRUE';
      INPUT_LOAD='(-0.01,0.01)';
      OUTPUT_LOAD='(1.0,-1.0)';
      PINUSE='BI';
    'DDR5_DQ'<61>:
      PIN_NUMBER='(0,0,0,0,0,0,0,DB31,0,0,0,0,0,0,0,0,0,0,0,0,0,0,0,0,0,0,0,0,0,~
0)';
      BIDIRECTIONAL='TRUE';
      INPUT_LOAD='(-0.01,0.01)';
      OUTPUT_LOAD='(1.0,-1.0)';
      PINUSE='BI';
    'DDR5_DQ'<60>:
      PIN_NUMBER='(0,0,0,0,0,0,0,CY31,0,0,0,0,0,0,0,0,0,0,0,0,0,0,0,0,0,0,0,0,0,~
0)';
      BIDIRECTIONAL='TRUE';
      INPUT_LOAD='(-0.01,0.01)';
      OUTPUT_LOAD='(1.0,-1.0)';
      PINUSE='BI';
    'DDR5_DQ'<59>:
      PIN_NUMBER='(0,0,0,0,0,0,0,DB27,0,0,0,0,0,0,0,0,0,0,0,0,0,0,0,0,0,0,0,0,0,~
0)';
      BIDIRECTIONAL='TRUE';
      INPUT_LOAD='(-0.01,0.01)';
      OUTPUT_LOAD='(1.0,-1.0)';
      PINUSE='BI';
    'DDR5_DQ'<58>:
      PIN_NUMBER='(0,0,0,0,0,0,0,CY27,0,0,0,0,0,0,0,0,0,0,0,0,0,0,0,0,0,0,0,0,0,~
0)';
      BIDIRECTIONAL='TRUE';
      INPUT_LOAD='(-0.01,0.01)';
      OUTPUT_LOAD='(1.0,-1.0)';
      PINUSE='BI';
    'DDR5_DQ'<57>:
      PIN_NUMBER='(0,0,0,0,0,0,0,DC30,0,0,0,0,0,0,0,0,0,0,0,0,0,0,0,0,0,0,0,0,0,~
0)';
      BIDIRECTIONAL='TRUE';
      INPUT_LOAD='(-0.01,0.01)';
      OUTPUT_LOAD='(1.0,-1.0)';
      PINUSE='BI';
    'DDR5_DQ'<56>:
      PIN_NUMBER='(0,0,0,0,0,0,0,CW30,0,0,0,0,0,0,0,0,0,0,0,0,0,0,0,0,0,0,0,0,0,~
0)';
      BIDIRECTIONAL='TRUE';
      INPUT_LOAD='(-0.01,0.01)';
      OUTPUT_LOAD='(1.0,-1.0)';
      PINUSE='BI';
    'DDR5_DQ'<55>:
      PIN_NUMBER='(0,0,0,0,0,0,0,DC34,0,0,0,0,0,0,0,0,0,0,0,0,0,0,0,0,0,0,0,0,0,~
0)';
      BIDIRECTIONAL='TRUE';
      INPUT_LOAD='(-0.01,0.01)';
      OUTPUT_LOAD='(1.0,-1.0)';
      PINUSE='BI';
    'DDR5_DQ'<54>:
      PIN_NUMBER='(0,0,0,0,0,0,0,CW34,0,0,0,0,0,0,0,0,0,0,0,0,0,0,0,0,0,0,0,0,0,~
0)';
      BIDIRECTIONAL='TRUE';
      INPUT_LOAD='(-0.01,0.01)';
      OUTPUT_LOAD='(1.0,-1.0)';
      PINUSE='BI';
    'DDR5_DQ'<53>:
      PIN_NUMBER='(0,0,0,0,0,0,0,DB37,0,0,0,0,0,0,0,0,0,0,0,0,0,0,0,0,0,0,0,0,0,~
0)';
      BIDIRECTIONAL='TRUE';
      INPUT_LOAD='(-0.01,0.01)';
      OUTPUT_LOAD='(1.0,-1.0)';
      PINUSE='BI';
    'DDR5_DQ'<52>:
      PIN_NUMBER='(0,0,0,0,0,0,0,CY37,0,0,0,0,0,0,0,0,0,0,0,0,0,0,0,0,0,0,0,0,0,~
0)';
      BIDIRECTIONAL='TRUE';
      INPUT_LOAD='(-0.01,0.01)';
      OUTPUT_LOAD='(1.0,-1.0)';
      PINUSE='BI';
    'DDR5_DQ'<51>:
      PIN_NUMBER='(0,0,0,0,0,0,0,DB33,0,0,0,0,0,0,0,0,0,0,0,0,0,0,0,0,0,0,0,0,0,~
0)';
      BIDIRECTIONAL='TRUE';
      INPUT_LOAD='(-0.01,0.01)';
      OUTPUT_LOAD='(1.0,-1.0)';
      PINUSE='BI';
    'DDR5_DQ'<50>:
      PIN_NUMBER='(0,0,0,0,0,0,0,CY33,0,0,0,0,0,0,0,0,0,0,0,0,0,0,0,0,0,0,0,0,0,~
0)';
      BIDIRECTIONAL='TRUE';
      INPUT_LOAD='(-0.01,0.01)';
      OUTPUT_LOAD='(1.0,-1.0)';
      PINUSE='BI';
    'DDR5_DQ'<49>:
      PIN_NUMBER='(0,0,0,0,0,0,0,DC36,0,0,0,0,0,0,0,0,0,0,0,0,0,0,0,0,0,0,0,0,0,~
0)';
      BIDIRECTIONAL='TRUE';
      INPUT_LOAD='(-0.01,0.01)';
      OUTPUT_LOAD='(1.0,-1.0)';
      PINUSE='BI';
    'DDR5_DQ'<48>:
      PIN_NUMBER='(0,0,0,0,0,0,0,CW36,0,0,0,0,0,0,0,0,0,0,0,0,0,0,0,0,0,0,0,0,0,~
0)';
      BIDIRECTIONAL='TRUE';
      INPUT_LOAD='(-0.01,0.01)';
      OUTPUT_LOAD='(1.0,-1.0)';
      PINUSE='BI';
    'DDR5_DQ'<47>:
      PIN_NUMBER='(0,0,0,0,0,0,0,DK31,0,0,0,0,0,0,0,0,0,0,0,0,0,0,0,0,0,0,0,0,0,~
0)';
      BIDIRECTIONAL='TRUE';
      INPUT_LOAD='(-0.01,0.01)';
      OUTPUT_LOAD='(1.0,-1.0)';
      PINUSE='BI';
    'DDR5_DQ'<46>:
      PIN_NUMBER='(0,0,0,0,0,0,0,DF31,0,0,0,0,0,0,0,0,0,0,0,0,0,0,0,0,0,0,0,0,0,~
0)';
      BIDIRECTIONAL='TRUE';
      INPUT_LOAD='(-0.01,0.01)';
      OUTPUT_LOAD='(1.0,-1.0)';
      PINUSE='BI';
    'DDR5_DQ'<45>:
      PIN_NUMBER='(0,0,0,0,0,0,0,DJ34,0,0,0,0,0,0,0,0,0,0,0,0,0,0,0,0,0,0,0,0,0,~
0)';
      BIDIRECTIONAL='TRUE';
      INPUT_LOAD='(-0.01,0.01)';
      OUTPUT_LOAD='(1.0,-1.0)';
      PINUSE='BI';
    'DDR5_DQ'<44>:
      PIN_NUMBER='(0,0,0,0,0,0,0,DG34,0,0,0,0,0,0,0,0,0,0,0,0,0,0,0,0,0,0,0,0,0,~
0)';
      BIDIRECTIONAL='TRUE';
      INPUT_LOAD='(-0.01,0.01)';
      OUTPUT_LOAD='(1.0,-1.0)';
      PINUSE='BI';
    'DDR5_DQ'<43>:
      PIN_NUMBER='(0,0,0,0,0,0,0,DJ30,0,0,0,0,0,0,0,0,0,0,0,0,0,0,0,0,0,0,0,0,0,~
0)';
      BIDIRECTIONAL='TRUE';
      INPUT_LOAD='(-0.01,0.01)';
      OUTPUT_LOAD='(1.0,-1.0)';
      PINUSE='BI';
    'DDR5_DQ'<42>:
      PIN_NUMBER='(0,0,0,0,0,0,0,DG30,0,0,0,0,0,0,0,0,0,0,0,0,0,0,0,0,0,0,0,0,0,~
0)';
      BIDIRECTIONAL='TRUE';
      INPUT_LOAD='(-0.01,0.01)';
      OUTPUT_LOAD='(1.0,-1.0)';
      PINUSE='BI';
    'DDR5_DQ'<41>:
      PIN_NUMBER='(0,0,0,0,0,0,0,DK33,0,0,0,0,0,0,0,0,0,0,0,0,0,0,0,0,0,0,0,0,0,~
0)';
      BIDIRECTIONAL='TRUE';
      INPUT_LOAD='(-0.01,0.01)';
      OUTPUT_LOAD='(1.0,-1.0)';
      PINUSE='BI';
    'DDR5_DQ'<40>:
      PIN_NUMBER='(0,0,0,0,0,0,0,DF33,0,0,0,0,0,0,0,0,0,0,0,0,0,0,0,0,0,0,0,0,0,~
0)';
      BIDIRECTIONAL='TRUE';
      INPUT_LOAD='(-0.01,0.01)';
      OUTPUT_LOAD='(1.0,-1.0)';
      PINUSE='BI';
    'DDR5_DQ'<39>:
      PIN_NUMBER='(0,0,0,0,0,0,0,DH39,0,0,0,0,0,0,0,0,0,0,0,0,0,0,0,0,0,0,0,0,0,~
0)';
      BIDIRECTIONAL='TRUE';
      INPUT_LOAD='(-0.01,0.01)';
      OUTPUT_LOAD='(1.0,-1.0)';
      PINUSE='BI';
    'DDR5_DQ'<38>:
      PIN_NUMBER='(0,0,0,0,0,0,0,DD39,0,0,0,0,0,0,0,0,0,0,0,0,0,0,0,0,0,0,0,0,0,~
0)';
      BIDIRECTIONAL='TRUE';
      INPUT_LOAD='(-0.01,0.01)';
      OUTPUT_LOAD='(1.0,-1.0)';
      PINUSE='BI';
    'DDR5_DQ'<37>:
      PIN_NUMBER='(0,0,0,0,0,0,0,DE42,0,0,0,0,0,0,0,0,0,0,0,0,0,0,0,0,0,0,0,0,0,~
0)';
      BIDIRECTIONAL='TRUE';
      INPUT_LOAD='(-0.01,0.01)';
      OUTPUT_LOAD='(1.0,-1.0)';
      PINUSE='BI';
    'DDR5_DQ'<36>:
      PIN_NUMBER='(0,0,0,0,0,0,0,DA42,0,0,0,0,0,0,0,0,0,0,0,0,0,0,0,0,0,0,0,0,0,~
0)';
      BIDIRECTIONAL='TRUE';
      INPUT_LOAD='(-0.01,0.01)';
      OUTPUT_LOAD='(1.0,-1.0)';
      PINUSE='BI';
    'DDR5_DQ'<35>:
      PIN_NUMBER='(0,0,0,0,0,0,0,DG38,0,0,0,0,0,0,0,0,0,0,0,0,0,0,0,0,0,0,0,0,0,~
0)';
      BIDIRECTIONAL='TRUE';
      INPUT_LOAD='(-0.01,0.01)';
      OUTPUT_LOAD='(1.0,-1.0)';
      PINUSE='BI';
    'DDR5_DQ'<34>:
      PIN_NUMBER='(0,0,0,0,0,0,0,DE38,0,0,0,0,0,0,0,0,0,0,0,0,0,0,0,0,0,0,0,0,0,~
0)';
      BIDIRECTIONAL='TRUE';
      INPUT_LOAD='(-0.01,0.01)';
      OUTPUT_LOAD='(1.0,-1.0)';
      PINUSE='BI';
    'DDR5_DQ'<33>:
      PIN_NUMBER='(0,0,0,0,0,0,0,DG42,0,0,0,0,0,0,0,0,0,0,0,0,0,0,0,0,0,0,0,0,0,~
0)';
      BIDIRECTIONAL='TRUE';
      INPUT_LOAD='(-0.01,0.01)';
      OUTPUT_LOAD='(1.0,-1.0)';
      PINUSE='BI';
    'DDR5_DQ'<32>:
      PIN_NUMBER='(0,0,0,0,0,0,0,DD41,0,0,0,0,0,0,0,0,0,0,0,0,0,0,0,0,0,0,0,0,0,~
0)';
      BIDIRECTIONAL='TRUE';
      INPUT_LOAD='(-0.01,0.01)';
      OUTPUT_LOAD='(1.0,-1.0)';
      PINUSE='BI';
    'DDR5_DQ'<31>:
      PIN_NUMBER='(0,0,0,0,0,0,0,CU64,0,0,0,0,0,0,0,0,0,0,0,0,0,0,0,0,0,0,0,0,0,~
0)';
      BIDIRECTIONAL='TRUE';
      INPUT_LOAD='(-0.01,0.01)';
      OUTPUT_LOAD='(1.0,-1.0)';
      PINUSE='BI';
    'DDR5_DQ'<30>:
      PIN_NUMBER='(0,0,0,0,0,0,0,CN64,0,0,0,0,0,0,0,0,0,0,0,0,0,0,0,0,0,0,0,0,0,~
0)';
      BIDIRECTIONAL='TRUE';
      INPUT_LOAD='(-0.01,0.01)';
      OUTPUT_LOAD='(1.0,-1.0)';
      PINUSE='BI';
    'DDR5_DQ'<29>:
      PIN_NUMBER='(0,0,0,0,0,0,0,CT67,0,0,0,0,0,0,0,0,0,0,0,0,0,0,0,0,0,0,0,0,0,~
0)';
      BIDIRECTIONAL='TRUE';
      INPUT_LOAD='(-0.01,0.01)';
      OUTPUT_LOAD='(1.0,-1.0)';
      PINUSE='BI';
    'DDR5_DQ'<28>:
      PIN_NUMBER='(0,0,0,0,0,0,0,CP67,0,0,0,0,0,0,0,0,0,0,0,0,0,0,0,0,0,0,0,0,0,~
0)';
      BIDIRECTIONAL='TRUE';
      INPUT_LOAD='(-0.01,0.01)';
      OUTPUT_LOAD='(1.0,-1.0)';
      PINUSE='BI';
    'DDR5_DQ'<27>:
      PIN_NUMBER='(0,0,0,0,0,0,0,CT63,0,0,0,0,0,0,0,0,0,0,0,0,0,0,0,0,0,0,0,0,0,~
0)';
      BIDIRECTIONAL='TRUE';
      INPUT_LOAD='(-0.01,0.01)';
      OUTPUT_LOAD='(1.0,-1.0)';
      PINUSE='BI';
    'DDR5_DQ'<26>:
      PIN_NUMBER='(0,0,0,0,0,0,0,CP63,0,0,0,0,0,0,0,0,0,0,0,0,0,0,0,0,0,0,0,0,0,~
0)';
      BIDIRECTIONAL='TRUE';
      INPUT_LOAD='(-0.01,0.01)';
      OUTPUT_LOAD='(1.0,-1.0)';
      PINUSE='BI';
    'DDR5_DQ'<25>:
      PIN_NUMBER='(0,0,0,0,0,0,0,CU66,0,0,0,0,0,0,0,0,0,0,0,0,0,0,0,0,0,0,0,0,0,~
0)';
      BIDIRECTIONAL='TRUE';
      INPUT_LOAD='(-0.01,0.01)';
      OUTPUT_LOAD='(1.0,-1.0)';
      PINUSE='BI';
    'DDR5_DQ'<24>:
      PIN_NUMBER='(0,0,0,0,0,0,0,CN66,0,0,0,0,0,0,0,0,0,0,0,0,0,0,0,0,0,0,0,0,0,~
0)';
      BIDIRECTIONAL='TRUE';
      INPUT_LOAD='(-0.01,0.01)';
      OUTPUT_LOAD='(1.0,-1.0)';
      PINUSE='BI';
    'DDR5_DQ'<23>:
      PIN_NUMBER='(0,0,0,0,0,0,0,DM71,0,0,0,0,0,0,0,0,0,0,0,0,0,0,0,0,0,0,0,0,0,~
0)';
      BIDIRECTIONAL='TRUE';
      INPUT_LOAD='(-0.01,0.01)';
      OUTPUT_LOAD='(1.0,-1.0)';
      PINUSE='BI';
    'DDR5_DQ'<22>:
      PIN_NUMBER='(0,0,0,0,0,0,0,DK69,0,0,0,0,0,0,0,0,0,0,0,0,0,0,0,0,0,0,0,0,0,~
0)';
      BIDIRECTIONAL='TRUE';
      INPUT_LOAD='(-0.01,0.01)';
      OUTPUT_LOAD='(1.0,-1.0)';
      PINUSE='BI';
    'DDR5_DQ'<21>:
      PIN_NUMBER='(0,0,0,0,0,0,0,DG72,0,0,0,0,0,0,0,0,0,0,0,0,0,0,0,0,0,0,0,0,0,~
0)';
      BIDIRECTIONAL='TRUE';
      INPUT_LOAD='(-0.01,0.01)';
      OUTPUT_LOAD='(1.0,-1.0)';
      PINUSE='BI';
    'DDR5_DQ'<20>:
      PIN_NUMBER='(0,0,0,0,0,0,0,DF71,0,0,0,0,0,0,0,0,0,0,0,0,0,0,0,0,0,0,0,0,0,~
0)';
      BIDIRECTIONAL='TRUE';
      INPUT_LOAD='(-0.01,0.01)';
      OUTPUT_LOAD='(1.0,-1.0)';
      PINUSE='BI';
    'DDR5_DQ'<19>:
      PIN_NUMBER='(0,0,0,0,0,0,0,DN70,0,0,0,0,0,0,0,0,0,0,0,0,0,0,0,0,0,0,0,0,0,~
0)';
      BIDIRECTIONAL='TRUE';
      INPUT_LOAD='(-0.01,0.01)';
      OUTPUT_LOAD='(1.0,-1.0)';
      PINUSE='BI';
    'DDR5_DQ'<18>:
      PIN_NUMBER='(0,0,0,0,0,0,0,DM69,0,0,0,0,0,0,0,0,0,0,0,0,0,0,0,0,0,0,0,0,0,~
0)';
      BIDIRECTIONAL='TRUE';
      INPUT_LOAD='(-0.01,0.01)';
      OUTPUT_LOAD='(1.0,-1.0)';
      PINUSE='BI';
    'DDR5_DQ'<17>:
      PIN_NUMBER='(0,0,0,0,0,0,0,DJ72,0,0,0,0,0,0,0,0,0,0,0,0,0,0,0,0,0,0,0,0,0,~
0)';
      BIDIRECTIONAL='TRUE';
      INPUT_LOAD='(-0.01,0.01)';
      OUTPUT_LOAD='(1.0,-1.0)';
      PINUSE='BI';
    'DDR5_DQ'<16>:
      PIN_NUMBER='(0,0,0,0,0,0,0,DG70,0,0,0,0,0,0,0,0,0,0,0,0,0,0,0,0,0,0,0,0,0,~
0)';
      BIDIRECTIONAL='TRUE';
      INPUT_LOAD='(-0.01,0.01)';
      OUTPUT_LOAD='(1.0,-1.0)';
      PINUSE='BI';
    'DDR5_DQ'<15>:
      PIN_NUMBER='(0,0,0,0,0,0,0,DH77,0,0,0,0,0,0,0,0,0,0,0,0,0,0,0,0,0,0,0,0,0,~
0)';
      BIDIRECTIONAL='TRUE';
      INPUT_LOAD='(-0.01,0.01)';
      OUTPUT_LOAD='(1.0,-1.0)';
      PINUSE='BI';
    'DDR5_DQ'<14>:
      PIN_NUMBER='(0,0,0,0,0,0,0,DF77,0,0,0,0,0,0,0,0,0,0,0,0,0,0,0,0,0,0,0,0,0,~
0)';
      BIDIRECTIONAL='TRUE';
      INPUT_LOAD='(-0.01,0.01)';
      OUTPUT_LOAD='(1.0,-1.0)';
      PINUSE='BI';
    'DDR5_DQ'<13>:
      PIN_NUMBER='(0,0,0,0,0,0,0,DB75,0,0,0,0,0,0,0,0,0,0,0,0,0,0,0,0,0,0,0,0,0,~
0)';
      BIDIRECTIONAL='TRUE';
      INPUT_LOAD='(-0.01,0.01)';
      OUTPUT_LOAD='(1.0,-1.0)';
      PINUSE='BI';
    'DDR5_DQ'<12>:
      PIN_NUMBER='(0,0,0,0,0,0,0,DC74,0,0,0,0,0,0,0,0,0,0,0,0,0,0,0,0,0,0,0,0,0,~
0)';
      BIDIRECTIONAL='TRUE';
      INPUT_LOAD='(-0.01,0.01)';
      OUTPUT_LOAD='(1.0,-1.0)';
      PINUSE='BI';
    'DDR5_DQ'<11>:
      PIN_NUMBER='(0,0,0,0,0,0,0,DJ76,0,0,0,0,0,0,0,0,0,0,0,0,0,0,0,0,0,0,0,0,0,~
0)';
      BIDIRECTIONAL='TRUE';
      INPUT_LOAD='(-0.01,0.01)';
      OUTPUT_LOAD='(1.0,-1.0)';
      PINUSE='BI';
    'DDR5_DQ'<10>:
      PIN_NUMBER='(0,0,0,0,0,0,0,DH75,0,0,0,0,0,0,0,0,0,0,0,0,0,0,0,0,0,0,0,0,0,~
0)';
      BIDIRECTIONAL='TRUE';
      INPUT_LOAD='(-0.01,0.01)';
      OUTPUT_LOAD='(1.0,-1.0)';
      PINUSE='BI';
    'DDR5_DQ'<9>:
      PIN_NUMBER='(0,0,0,0,0,0,0,DC76,0,0,0,0,0,0,0,0,0,0,0,0,0,0,0,0,0,0,0,0,0,~
0)';
      BIDIRECTIONAL='TRUE';
      INPUT_LOAD='(-0.01,0.01)';
      OUTPUT_LOAD='(1.0,-1.0)';
      PINUSE='BI';
    'DDR5_DQ'<8>:
      PIN_NUMBER='(0,0,0,0,0,0,0,DE74,0,0,0,0,0,0,0,0,0,0,0,0,0,0,0,0,0,0,0,0,0,~
0)';
      BIDIRECTIONAL='TRUE';
      INPUT_LOAD='(-0.01,0.01)';
      OUTPUT_LOAD='(1.0,-1.0)';
      PINUSE='BI';
    'DDR5_DQ'<7>:
      PIN_NUMBER='(0,0,0,0,0,0,0,CT77,0,0,0,0,0,0,0,0,0,0,0,0,0,0,0,0,0,0,0,0,0,~
0)';
      BIDIRECTIONAL='TRUE';
      INPUT_LOAD='(-0.01,0.01)';
      OUTPUT_LOAD='(1.0,-1.0)';
      PINUSE='BI';
    'DDR5_DQ'<6>:
      PIN_NUMBER='(0,0,0,0,0,0,0,CV75,0,0,0,0,0,0,0,0,0,0,0,0,0,0,0,0,0,0,0,0,0,~
0)';
      BIDIRECTIONAL='TRUE';
      INPUT_LOAD='(-0.01,0.01)';
      OUTPUT_LOAD='(1.0,-1.0)';
      PINUSE='BI';
    'DDR5_DQ'<5>:
      PIN_NUMBER='(0,0,0,0,0,0,0,CM75,0,0,0,0,0,0,0,0,0,0,0,0,0,0,0,0,0,0,0,0,0,~
0)';
      BIDIRECTIONAL='TRUE';
      INPUT_LOAD='(-0.01,0.01)';
      OUTPUT_LOAD='(1.0,-1.0)';
      PINUSE='BI';
    'DDR5_DQ'<4>:
      PIN_NUMBER='(0,0,0,0,0,0,0,CN74,0,0,0,0,0,0,0,0,0,0,0,0,0,0,0,0,0,0,0,0,0,~
0)';
      BIDIRECTIONAL='TRUE';
      INPUT_LOAD='(-0.01,0.01)';
      OUTPUT_LOAD='(1.0,-1.0)';
      PINUSE='BI';
    'DDR5_DQ'<3>:
      PIN_NUMBER='(0,0,0,0,0,0,0,CV77,0,0,0,0,0,0,0,0,0,0,0,0,0,0,0,0,0,0,0,0,0,~
0)';
      BIDIRECTIONAL='TRUE';
      INPUT_LOAD='(-0.01,0.01)';
      OUTPUT_LOAD='(1.0,-1.0)';
      PINUSE='BI';
    'DDR5_DQ'<2>:
      PIN_NUMBER='(0,0,0,0,0,0,0,CW76,0,0,0,0,0,0,0,0,0,0,0,0,0,0,0,0,0,0,0,0,0,~
0)';
      BIDIRECTIONAL='TRUE';
      INPUT_LOAD='(-0.01,0.01)';
      OUTPUT_LOAD='(1.0,-1.0)';
      PINUSE='BI';
    'DDR5_DQ'<1>:
      PIN_NUMBER='(0,0,0,0,0,0,0,CN76,0,0,0,0,0,0,0,0,0,0,0,0,0,0,0,0,0,0,0,0,0,~
0)';
      BIDIRECTIONAL='TRUE';
      INPUT_LOAD='(-0.01,0.01)';
      OUTPUT_LOAD='(1.0,-1.0)';
      PINUSE='BI';
    'DDR5_DQ'<0>:
      PIN_NUMBER='(0,0,0,0,0,0,0,CR74,0,0,0,0,0,0,0,0,0,0,0,0,0,0,0,0,0,0,0,0,0,~
0)';
      BIDIRECTIONAL='TRUE';
      INPUT_LOAD='(-0.01,0.01)';
      OUTPUT_LOAD='(1.0,-1.0)';
      PINUSE='BI';
    'DDR5_DQS_DN'<17>:
      PIN_NUMBER='(0,0,0,0,0,0,0,CJ70,0,0,0,0,0,0,0,0,0,0,0,0,0,0,0,0,0,0,0,0,0,~
0)';
      BIDIRECTIONAL='TRUE';
      INPUT_LOAD='(-0.01,0.01)';
      OUTPUT_LOAD='(1.0,-1.0)';
      PINUSE='BI';
    'DDR5_DQS_DN'<16>:
      PIN_NUMBER='(0,0,0,0,0,0,0,CY29,0,0,0,0,0,0,0,0,0,0,0,0,0,0,0,0,0,0,0,0,0,~
0)';
      BIDIRECTIONAL='TRUE';
      INPUT_LOAD='(-0.01,0.01)';
      OUTPUT_LOAD='(1.0,-1.0)';
      PINUSE='BI';
    'DDR5_DQS_DN'<15>:
      PIN_NUMBER='(0,0,0,0,0,0,0,CY35,0,0,0,0,0,0,0,0,0,0,0,0,0,0,0,0,0,0,0,0,0,~
0)';
      BIDIRECTIONAL='TRUE';
      INPUT_LOAD='(-0.01,0.01)';
      OUTPUT_LOAD='(1.0,-1.0)';
      PINUSE='BI';
    'DDR5_DQS_DN'<14>:
      PIN_NUMBER='(0,0,0,0,0,0,0,DG32,0,0,0,0,0,0,0,0,0,0,0,0,0,0,0,0,0,0,0,0,0,~
0)';
      BIDIRECTIONAL='TRUE';
      INPUT_LOAD='(-0.01,0.01)';
      OUTPUT_LOAD='(1.0,-1.0)';
      PINUSE='BI';
    'DDR5_DQS_DN'<13>:
      PIN_NUMBER='(0,0,0,0,0,0,0,DE40,0,0,0,0,0,0,0,0,0,0,0,0,0,0,0,0,0,0,0,0,0,~
0)';
      BIDIRECTIONAL='TRUE';
      INPUT_LOAD='(-0.01,0.01)';
      OUTPUT_LOAD='(1.0,-1.0)';
      PINUSE='BI';
    'DDR5_DQS_DN'<12>:
      PIN_NUMBER='(0,0,0,0,0,0,0,CP65,0,0,0,0,0,0,0,0,0,0,0,0,0,0,0,0,0,0,0,0,0,~
0)';
      BIDIRECTIONAL='TRUE';
      INPUT_LOAD='(-0.01,0.01)';
      OUTPUT_LOAD='(1.0,-1.0)';
      PINUSE='BI';
    'DDR5_DQS_DN'<11>:
      PIN_NUMBER='(0,0,0,0,0,0,0,DJ70,0,0,0,0,0,0,0,0,0,0,0,0,0,0,0,0,0,0,0,0,0,~
0)';
      BIDIRECTIONAL='TRUE';
      INPUT_LOAD='(-0.01,0.01)';
      OUTPUT_LOAD='(1.0,-1.0)';
      PINUSE='BI';
    'DDR5_DQS_DN'<10>:
      PIN_NUMBER='(0,0,0,0,0,0,0,DF75,0,0,0,0,0,0,0,0,0,0,0,0,0,0,0,0,0,0,0,0,0,~
0)';
      BIDIRECTIONAL='TRUE';
      INPUT_LOAD='(-0.01,0.01)';
      OUTPUT_LOAD='(1.0,-1.0)';
      PINUSE='BI';
    'DDR5_DQS_DN'<9>:
      PIN_NUMBER='(0,0,0,0,0,0,0,CT75,0,0,0,0,0,0,0,0,0,0,0,0,0,0,0,0,0,0,0,0,0,~
0)';
      BIDIRECTIONAL='TRUE';
      INPUT_LOAD='(-0.01,0.01)';
      OUTPUT_LOAD='(1.0,-1.0)';
      PINUSE='BI';
    'DDR5_DQS_DN'<8>:
      PIN_NUMBER='(0,0,0,0,0,0,0,CN70,0,0,0,0,0,0,0,0,0,0,0,0,0,0,0,0,0,0,0,0,0,~
0)';
      BIDIRECTIONAL='TRUE';
      INPUT_LOAD='(-0.01,0.01)';
      OUTPUT_LOAD='(1.0,-1.0)';
      PINUSE='BI';
    'DDR5_DQS_DN'<7>:
      PIN_NUMBER='(0,0,0,0,0,0,0,DD29,0,0,0,0,0,0,0,0,0,0,0,0,0,0,0,0,0,0,0,0,0,~
0)';
      BIDIRECTIONAL='TRUE';
      INPUT_LOAD='(-0.01,0.01)';
      OUTPUT_LOAD='(1.0,-1.0)';
      PINUSE='BI';
    'DDR5_DQS_DN'<6>:
      PIN_NUMBER='(0,0,0,0,0,0,0,DD35,0,0,0,0,0,0,0,0,0,0,0,0,0,0,0,0,0,0,0,0,0,~
0)';
      BIDIRECTIONAL='TRUE';
      INPUT_LOAD='(-0.01,0.01)';
      OUTPUT_LOAD='(1.0,-1.0)';
      PINUSE='BI';
    'DDR5_DQS_DN'<5>:
      PIN_NUMBER='(0,0,0,0,0,0,0,DL32,0,0,0,0,0,0,0,0,0,0,0,0,0,0,0,0,0,0,0,0,0,~
0)';
      BIDIRECTIONAL='TRUE';
      INPUT_LOAD='(-0.01,0.01)';
      OUTPUT_LOAD='(1.0,-1.0)';
      PINUSE='BI';
    'DDR5_DQS_DN'<4>:
      PIN_NUMBER='(0,0,0,0,0,0,0,DG40,0,0,0,0,0,0,0,0,0,0,0,0,0,0,0,0,0,0,0,0,0,~
0)';
      BIDIRECTIONAL='TRUE';
      INPUT_LOAD='(-0.01,0.01)';
      OUTPUT_LOAD='(1.0,-1.0)';
      PINUSE='BI';
    'DDR5_DQS_DN'<3>:
      PIN_NUMBER='(0,0,0,0,0,0,0,CV65,0,0,0,0,0,0,0,0,0,0,0,0,0,0,0,0,0,0,0,0,0,~
0)';
      BIDIRECTIONAL='TRUE';
      INPUT_LOAD='(-0.01,0.01)';
      OUTPUT_LOAD='(1.0,-1.0)';
      PINUSE='BI';
    'DDR5_DQS_DN'<2>:
      PIN_NUMBER='(0,0,0,0,0,0,0,DL72,0,0,0,0,0,0,0,0,0,0,0,0,0,0,0,0,0,0,0,0,0,~
0)';
      BIDIRECTIONAL='TRUE';
      INPUT_LOAD='(-0.01,0.01)';
      OUTPUT_LOAD='(1.0,-1.0)';
      PINUSE='BI';
    'DDR5_DQS_DN'<1>:
      PIN_NUMBER='(0,0,0,0,0,0,0,DD77,0,0,0,0,0,0,0,0,0,0,0,0,0,0,0,0,0,0,0,0,0,~
0)';
      BIDIRECTIONAL='TRUE';
      INPUT_LOAD='(-0.01,0.01)';
      OUTPUT_LOAD='(1.0,-1.0)';
      PINUSE='BI';
    'DDR5_DQS_DN'<0>:
      PIN_NUMBER='(0,0,0,0,0,0,0,CP77,0,0,0,0,0,0,0,0,0,0,0,0,0,0,0,0,0,0,0,0,0,~
0)';
      BIDIRECTIONAL='TRUE';
      INPUT_LOAD='(-0.01,0.01)';
      OUTPUT_LOAD='(1.0,-1.0)';
      PINUSE='BI';
    'DDR5_DQS_DP'<17>:
      PIN_NUMBER='(0,0,0,0,0,0,0,CG70,0,0,0,0,0,0,0,0,0,0,0,0,0,0,0,0,0,0,0,0,0,~
0)';
      BIDIRECTIONAL='TRUE';
      INPUT_LOAD='(-0.01,0.01)';
      OUTPUT_LOAD='(1.0,-1.0)';
      PINUSE='BI';
    'DDR5_DQS_DP'<16>:
      PIN_NUMBER='(0,0,0,0,0,0,0,CV29,0,0,0,0,0,0,0,0,0,0,0,0,0,0,0,0,0,0,0,0,0,~
0)';
      BIDIRECTIONAL='TRUE';
      INPUT_LOAD='(-0.01,0.01)';
      OUTPUT_LOAD='(1.0,-1.0)';
      PINUSE='BI';
    'DDR5_DQS_DP'<15>:
      PIN_NUMBER='(0,0,0,0,0,0,0,CV35,0,0,0,0,0,0,0,0,0,0,0,0,0,0,0,0,0,0,0,0,0,~
0)';
      BIDIRECTIONAL='TRUE';
      INPUT_LOAD='(-0.01,0.01)';
      OUTPUT_LOAD='(1.0,-1.0)';
      PINUSE='BI';
    'DDR5_DQS_DP'<14>:
      PIN_NUMBER='(0,0,0,0,0,0,0,DE32,0,0,0,0,0,0,0,0,0,0,0,0,0,0,0,0,0,0,0,0,0,~
0)';
      BIDIRECTIONAL='TRUE';
      INPUT_LOAD='(-0.01,0.01)';
      OUTPUT_LOAD='(1.0,-1.0)';
      PINUSE='BI';
    'DDR5_DQS_DP'<13>:
      PIN_NUMBER='(0,0,0,0,0,0,0,DC40,0,0,0,0,0,0,0,0,0,0,0,0,0,0,0,0,0,0,0,0,0,~
0)';
      BIDIRECTIONAL='TRUE';
      INPUT_LOAD='(-0.01,0.01)';
      OUTPUT_LOAD='(1.0,-1.0)';
      PINUSE='BI';
    'DDR5_DQS_DP'<12>:
      PIN_NUMBER='(0,0,0,0,0,0,0,CM65,0,0,0,0,0,0,0,0,0,0,0,0,0,0,0,0,0,0,0,0,0,~
0)';
      BIDIRECTIONAL='TRUE';
      INPUT_LOAD='(-0.01,0.01)';
      OUTPUT_LOAD='(1.0,-1.0)';
      PINUSE='BI';
    'DDR5_DQS_DP'<11>:
      PIN_NUMBER='(0,0,0,0,0,0,0,DH69,0,0,0,0,0,0,0,0,0,0,0,0,0,0,0,0,0,0,0,0,0,~
0)';
      BIDIRECTIONAL='TRUE';
      INPUT_LOAD='(-0.01,0.01)';
      OUTPUT_LOAD='(1.0,-1.0)';
      PINUSE='BI';
    'DDR5_DQS_DP'<10>:
      PIN_NUMBER='(0,0,0,0,0,0,0,DG74,0,0,0,0,0,0,0,0,0,0,0,0,0,0,0,0,0,0,0,0,0,~
0)';
      BIDIRECTIONAL='TRUE';
      INPUT_LOAD='(-0.01,0.01)';
      OUTPUT_LOAD='(1.0,-1.0)';
      PINUSE='BI';
    'DDR5_DQS_DP'<9>:
      PIN_NUMBER='(0,0,0,0,0,0,0,CU74,0,0,0,0,0,0,0,0,0,0,0,0,0,0,0,0,0,0,0,0,0,~
0)';
      BIDIRECTIONAL='TRUE';
      INPUT_LOAD='(-0.01,0.01)';
      OUTPUT_LOAD='(1.0,-1.0)';
      PINUSE='BI';
    'DDR5_DQS_DP'<8>:
      PIN_NUMBER='(0,0,0,0,0,0,0,CL70,0,0,0,0,0,0,0,0,0,0,0,0,0,0,0,0,0,0,0,0,0,~
0)';
      BIDIRECTIONAL='TRUE';
      INPUT_LOAD='(-0.01,0.01)';
      OUTPUT_LOAD='(1.0,-1.0)';
      PINUSE='BI';
    'DDR5_DQS_DP'<7>:
      PIN_NUMBER='(0,0,0,0,0,0,0,DB29,0,0,0,0,0,0,0,0,0,0,0,0,0,0,0,0,0,0,0,0,0,~
0)';
      BIDIRECTIONAL='TRUE';
      INPUT_LOAD='(-0.01,0.01)';
      OUTPUT_LOAD='(1.0,-1.0)';
      PINUSE='BI';
    'DDR5_DQS_DP'<6>:
      PIN_NUMBER='(0,0,0,0,0,0,0,DB35,0,0,0,0,0,0,0,0,0,0,0,0,0,0,0,0,0,0,0,0,0,~
0)';
      BIDIRECTIONAL='TRUE';
      INPUT_LOAD='(-0.01,0.01)';
      OUTPUT_LOAD='(1.0,-1.0)';
      PINUSE='BI';
    'DDR5_DQS_DP'<5>:
      PIN_NUMBER='(0,0,0,0,0,0,0,DJ32,0,0,0,0,0,0,0,0,0,0,0,0,0,0,0,0,0,0,0,0,0,~
0)';
      BIDIRECTIONAL='TRUE';
      INPUT_LOAD='(-0.01,0.01)';
      OUTPUT_LOAD='(1.0,-1.0)';
      PINUSE='BI';
    'DDR5_DQS_DP'<4>:
      PIN_NUMBER='(0,0,0,0,0,0,0,DJ40,0,0,0,0,0,0,0,0,0,0,0,0,0,0,0,0,0,0,0,0,0,~
0)';
      BIDIRECTIONAL='TRUE';
      INPUT_LOAD='(-0.01,0.01)';
      OUTPUT_LOAD='(1.0,-1.0)';
      PINUSE='BI';
    'DDR5_DQS_DP'<3>:
      PIN_NUMBER='(0,0,0,0,0,0,0,CT65,0,0,0,0,0,0,0,0,0,0,0,0,0,0,0,0,0,0,0,0,0,~
0)';
      BIDIRECTIONAL='TRUE';
      INPUT_LOAD='(-0.01,0.01)';
      OUTPUT_LOAD='(1.0,-1.0)';
      PINUSE='BI';
    'DDR5_DQS_DP'<2>:
      PIN_NUMBER='(0,0,0,0,0,0,0,DK71,0,0,0,0,0,0,0,0,0,0,0,0,0,0,0,0,0,0,0,0,0,~
0)';
      BIDIRECTIONAL='TRUE';
      INPUT_LOAD='(-0.01,0.01)';
      OUTPUT_LOAD='(1.0,-1.0)';
      PINUSE='BI';
    'DDR5_DQS_DP'<1>:
      PIN_NUMBER='(0,0,0,0,0,0,0,DE76,0,0,0,0,0,0,0,0,0,0,0,0,0,0,0,0,0,0,0,0,0,~
0)';
      BIDIRECTIONAL='TRUE';
      INPUT_LOAD='(-0.01,0.01)';
      OUTPUT_LOAD='(1.0,-1.0)';
      PINUSE='BI';
    'DDR5_DQS_DP'<0>:
      PIN_NUMBER='(0,0,0,0,0,0,0,CR76,0,0,0,0,0,0,0,0,0,0,0,0,0,0,0,0,0,0,0,0,0,~
0)';
      BIDIRECTIONAL='TRUE';
      INPUT_LOAD='(-0.01,0.01)';
      OUTPUT_LOAD='(1.0,-1.0)';
      PINUSE='BI';
    'DDR5_ECC'<7>:
      PIN_NUMBER='(0,0,0,0,0,0,0,CM69,0,0,0,0,0,0,0,0,0,0,0,0,0,0,0,0,0,0,0,0,0,~
0)';
      BIDIRECTIONAL='TRUE';
      INPUT_LOAD='(-0.01,0.01)';
      OUTPUT_LOAD='(1.0,-1.0)';
      PINUSE='BI';
    'DDR5_ECC'<6>:
      PIN_NUMBER='(0,0,0,0,0,0,0,CH69,0,0,0,0,0,0,0,0,0,0,0,0,0,0,0,0,0,0,0,0,0,~
0)';
      BIDIRECTIONAL='TRUE';
      INPUT_LOAD='(-0.01,0.01)';
      OUTPUT_LOAD='(1.0,-1.0)';
      PINUSE='BI';
    'DDR5_ECC'<5>:
      PIN_NUMBER='(0,0,0,0,0,0,0,CL72,0,0,0,0,0,0,0,0,0,0,0,0,0,0,0,0,0,0,0,0,0,~
0)';
      BIDIRECTIONAL='TRUE';
      INPUT_LOAD='(-0.01,0.01)';
      OUTPUT_LOAD='(1.0,-1.0)';
      PINUSE='BI';
    'DDR5_ECC'<4>:
      PIN_NUMBER='(0,0,0,0,0,0,0,CJ72,0,0,0,0,0,0,0,0,0,0,0,0,0,0,0,0,0,0,0,0,0,~
0)';
      BIDIRECTIONAL='TRUE';
      INPUT_LOAD='(-0.01,0.01)';
      OUTPUT_LOAD='(1.0,-1.0)';
      PINUSE='BI';
    'DDR5_ECC'<3>:
      PIN_NUMBER='(0,0,0,0,0,0,0,CL68,0,0,0,0,0,0,0,0,0,0,0,0,0,0,0,0,0,0,0,0,0,~
0)';
      BIDIRECTIONAL='TRUE';
      INPUT_LOAD='(-0.01,0.01)';
      OUTPUT_LOAD='(1.0,-1.0)';
      PINUSE='BI';
    'DDR5_ECC'<2>:
      PIN_NUMBER='(0,0,0,0,0,0,0,CJ68,0,0,0,0,0,0,0,0,0,0,0,0,0,0,0,0,0,0,0,0,0,~
0)';
      BIDIRECTIONAL='TRUE';
      INPUT_LOAD='(-0.01,0.01)';
      OUTPUT_LOAD='(1.0,-1.0)';
      PINUSE='BI';
    'DDR5_ECC'<1>:
      PIN_NUMBER='(0,0,0,0,0,0,0,CM71,0,0,0,0,0,0,0,0,0,0,0,0,0,0,0,0,0,0,0,0,0,~
0)';
      BIDIRECTIONAL='TRUE';
      INPUT_LOAD='(-0.01,0.01)';
      OUTPUT_LOAD='(1.0,-1.0)';
      PINUSE='BI';
    'DDR5_ECC'<0>:
      PIN_NUMBER='(0,0,0,0,0,0,0,CH71,0,0,0,0,0,0,0,0,0,0,0,0,0,0,0,0,0,0,0,0,0,~
0)';
      BIDIRECTIONAL='TRUE';
      INPUT_LOAD='(-0.01,0.01)';
      OUTPUT_LOAD='(1.0,-1.0)';
      PINUSE='BI';
    'DDR5_MA'<17>:
      PIN_NUMBER='(0,0,0,0,0,0,0,DE46,0,0,0,0,0,0,0,0,0,0,0,0,0,0,0,0,0,0,0,0,0,~
0)';
      OUTPUT_LOAD='(1.0,-1.0)';
      PINUSE='OUT';
    'DDR5_MA'<16>:
      PIN_NUMBER='(0,0,0,0,0,0,0,DG52,0,0,0,0,0,0,0,0,0,0,0,0,0,0,0,0,0,0,0,0,0,~
0)';
      OUTPUT_LOAD='(1.0,-1.0)';
      PINUSE='OUT';
    'DDR5_MA'<15>:
      PIN_NUMBER='(0,0,0,0,0,0,0,DC54,0,0,0,0,0,0,0,0,0,0,0,0,0,0,0,0,0,0,0,0,0,~
0)';
      OUTPUT_LOAD='(1.0,-1.0)';
      PINUSE='OUT';
    'DDR5_MA'<14>:
      PIN_NUMBER='(0,0,0,0,0,0,0,DJ50,0,0,0,0,0,0,0,0,0,0,0,0,0,0,0,0,0,0,0,0,0,~
0)';
      OUTPUT_LOAD='(1.0,-1.0)';
      PINUSE='OUT';
    'DDR5_MA'<13>:
      PIN_NUMBER='(0,0,0,0,0,0,0,DD53,0,0,0,0,0,0,0,0,0,0,0,0,0,0,0,0,0,0,0,0,0,~
0)';
      OUTPUT_LOAD='(1.0,-1.0)';
      PINUSE='OUT';
    'DDR5_MA'<12>:
      PIN_NUMBER='(0,0,0,0,0,0,0,DG60,0,0,0,0,0,0,0,0,0,0,0,0,0,0,0,0,0,0,0,0,0,~
0)';
      OUTPUT_LOAD='(1.0,-1.0)';
      PINUSE='OUT';
    'DDR5_MA'<11>:
      PIN_NUMBER='(0,0,0,0,0,0,0,DA60,0,0,0,0,0,0,0,0,0,0,0,0,0,0,0,0,0,0,0,0,0,~
0)';
      OUTPUT_LOAD='(1.0,-1.0)';
      PINUSE='OUT';
    'DDR5_MA'<10>:
      PIN_NUMBER='(0,0,0,0,0,0,0,DD55,0,0,0,0,0,0,0,0,0,0,0,0,0,0,0,0,0,0,0,0,0,~
0)';
      OUTPUT_LOAD='(1.0,-1.0)';
      PINUSE='OUT';
    'DDR5_MA'<9>:
      PIN_NUMBER='(0,0,0,0,0,0,0,DA58,0,0,0,0,0,0,0,0,0,0,0,0,0,0,0,0,0,0,0,0,0,~
0)';
      OUTPUT_LOAD='(1.0,-1.0)';
      PINUSE='OUT';
    'DDR5_MA'<8>:
      PIN_NUMBER='(0,0,0,0,0,0,0,DD59,0,0,0,0,0,0,0,0,0,0,0,0,0,0,0,0,0,0,0,0,0,~
0)';
      OUTPUT_LOAD='(1.0,-1.0)';
      PINUSE='OUT';
    'DDR5_MA'<7>:
      PIN_NUMBER='(0,0,0,0,0,0,0,DC60,0,0,0,0,0,0,0,0,0,0,0,0,0,0,0,0,0,0,0,0,0,~
0)';
      OUTPUT_LOAD='(1.0,-1.0)';
      PINUSE='OUT';
    'DDR5_MA'<6>:
      PIN_NUMBER='(0,0,0,0,0,0,0,DK59,0,0,0,0,0,0,0,0,0,0,0,0,0,0,0,0,0,0,0,0,0,~
0)';
      OUTPUT_LOAD='(1.0,-1.0)';
      PINUSE='OUT';
    'DDR5_MA'<5>:
      PIN_NUMBER='(0,0,0,0,0,0,0,DF59,0,0,0,0,0,0,0,0,0,0,0,0,0,0,0,0,0,0,0,0,0,~
0)';
      OUTPUT_LOAD='(1.0,-1.0)';
      PINUSE='OUT';
    'DDR5_MA'<4>:
      PIN_NUMBER='(0,0,0,0,0,0,0,DJ58,0,0,0,0,0,0,0,0,0,0,0,0,0,0,0,0,0,0,0,0,0,~
0)';
      OUTPUT_LOAD='(1.0,-1.0)';
      PINUSE='OUT';
    'DDR5_MA'<3>:
      PIN_NUMBER='(0,0,0,0,0,0,0,DG58,0,0,0,0,0,0,0,0,0,0,0,0,0,0,0,0,0,0,0,0,0,~
0)';
      OUTPUT_LOAD='(1.0,-1.0)';
      PINUSE='OUT';
    'DDR5_MA'<2>:
      PIN_NUMBER='(0,0,0,0,0,0,0,DD57,0,0,0,0,0,0,0,0,0,0,0,0,0,0,0,0,0,0,0,0,0,~
0)';
      OUTPUT_LOAD='(1.0,-1.0)';
      PINUSE='OUT';
    'DDR5_MA'<1>:
      PIN_NUMBER='(0,0,0,0,0,0,0,DC58,0,0,0,0,0,0,0,0,0,0,0,0,0,0,0,0,0,0,0,0,0,~
0)';
      OUTPUT_LOAD='(1.0,-1.0)';
      PINUSE='OUT';
    'DDR5_MA'<0>:
      PIN_NUMBER='(0,0,0,0,0,0,0,DF53,0,0,0,0,0,0,0,0,0,0,0,0,0,0,0,0,0,0,0,0,0,~
0)';
      OUTPUT_LOAD='(1.0,-1.0)';
      PINUSE='OUT';
    'DDR5_ODT'<3>:
      PIN_NUMBER='(0,0,0,0,0,0,0,DF47,0,0,0,0,0,0,0,0,0,0,0,0,0,0,0,0,0,0,0,0,0,~
0)';
      OUTPUT_LOAD='(1.0,-1.0)';
      PINUSE='OUT';
    'DDR5_ODT'<2>:
      PIN_NUMBER='(0,0,0,0,0,0,0,DK49,0,0,0,0,0,0,0,0,0,0,0,0,0,0,0,0,0,0,0,0,0,~
0)';
      OUTPUT_LOAD='(1.0,-1.0)';
      PINUSE='OUT';
    'DDR5_ODT'<1>:
      PIN_NUMBER='(0,0,0,0,0,0,0,DG48,0,0,0,0,0,0,0,0,0,0,0,0,0,0,0,0,0,0,0,0,0,~
0)';
      OUTPUT_LOAD='(1.0,-1.0)';
      PINUSE='OUT';
    'DDR5_ODT'<0>:
      PIN_NUMBER='(0,0,0,0,0,0,0,DG50,0,0,0,0,0,0,0,0,0,0,0,0,0,0,0,0,0,0,0,0,0,~
0)';
      OUTPUT_LOAD='(1.0,-1.0)';
      PINUSE='OUT';
    'DDR5_PAR':
      PIN_NUMBER='(0,0,0,0,0,0,0,DK53,0,0,0,0,0,0,0,0,0,0,0,0,0,0,0,0,0,0,0,0,0,~
0)';
      OUTPUT_LOAD='(1.0,-1.0)';
      PINUSE='OUT';
    'DEBUG_EN_N':
      PIN_NUMBER='(0,AV21,0,0,0,0,0,0,0,0,0,0,0,0,0,0,0,0,0,0,0,0,0,0,0,0,0,0,0,~
0)';
      BIDIRECTIONAL='TRUE';
      INPUT_LOAD='(-0.01,0.01)';
      OUTPUT_LOAD='(1.0,-1.0)';
      PINUSE='BI';
    'DMIMODE_OVERRIDE':
      PIN_NUMBER='(0,AW12,0,0,0,0,0,0,0,0,0,0,0,0,0,0,0,0,0,0,0,0,0,0,0,0,0,0,0,~
0)';
      BIDIRECTIONAL='TRUE';
      INPUT_LOAD='(-0.01,0.01)';
      OUTPUT_LOAD='(1.0,-1.0)';
      PINUSE='BI';
    'DMI_RX_DN'<3>:
      PIN_NUMBER='(0,0,0,0,0,0,0,0,CT11,0,0,0,0,0,0,0,0,0,0,0,0,0,0,0,0,0,0,0,0,~
0)';
      INPUT_LOAD='(-0.01,0.01)';
      PINUSE='IN';
    'DMI_RX_DN'<2>:
      PIN_NUMBER='(0,0,0,0,0,0,0,0,CR12,0,0,0,0,0,0,0,0,0,0,0,0,0,0,0,0,0,0,0,0,~
0)';
      INPUT_LOAD='(-0.01,0.01)';
      PINUSE='IN';
    'DMI_RX_DN'<1>:
      PIN_NUMBER='(0,0,0,0,0,0,0,0,CM11,0,0,0,0,0,0,0,0,0,0,0,0,0,0,0,0,0,0,0,0,~
0)';
      INPUT_LOAD='(-0.01,0.01)';
      PINUSE='IN';
    'DMI_RX_DN'<0>:
      PIN_NUMBER='(0,0,0,0,0,0,0,0,CK9,0,0,0,0,0,0,0,0,0,0,0,0,0,0,0,0,0,0,0,0,0~
)';
      INPUT_LOAD='(-0.01,0.01)';
      PINUSE='IN';
    'DMI_RX_DP'<3>:
      PIN_NUMBER='(0,0,0,0,0,0,0,0,CV11,0,0,0,0,0,0,0,0,0,0,0,0,0,0,0,0,0,0,0,0,~
0)';
      INPUT_LOAD='(-0.01,0.01)';
      PINUSE='IN';
    'DMI_RX_DP'<2>:
      PIN_NUMBER='(0,0,0,0,0,0,0,0,CP11,0,0,0,0,0,0,0,0,0,0,0,0,0,0,0,0,0,0,0,0,~
0)';
      INPUT_LOAD='(-0.01,0.01)';
      PINUSE='IN';
    'DMI_RX_DP'<1>:
      PIN_NUMBER='(0,0,0,0,0,0,0,0,CN10,0,0,0,0,0,0,0,0,0,0,0,0,0,0,0,0,0,0,0,0,~
0)';
      INPUT_LOAD='(-0.01,0.01)';
      PINUSE='IN';
    'DMI_RX_DP'<0>:
      PIN_NUMBER='(0,0,0,0,0,0,0,0,CL10,0,0,0,0,0,0,0,0,0,0,0,0,0,0,0,0,0,0,0,0,~
0)';
      INPUT_LOAD='(-0.01,0.01)';
      PINUSE='IN';
    'DMI_TX_DN'<3>:
      PIN_NUMBER='(0,0,0,0,0,0,0,0,CP5,0,0,0,0,0,0,0,0,0,0,0,0,0,0,0,0,0,0,0,0,0~
)';
      OUTPUT_LOAD='(1.0,-1.0)';
      PINUSE='OUT';
    'DMI_TX_DN'<2>:
      PIN_NUMBER='(0,0,0,0,0,0,0,0,CN4,0,0,0,0,0,0,0,0,0,0,0,0,0,0,0,0,0,0,0,0,0~
)';
      OUTPUT_LOAD='(1.0,-1.0)';
      PINUSE='OUT';
    'DMI_TX_DN'<1>:
      PIN_NUMBER='(0,0,0,0,0,0,0,0,CJ4,0,0,0,0,0,0,0,0,0,0,0,0,0,0,0,0,0,0,0,0,0~
)';
      OUTPUT_LOAD='(1.0,-1.0)';
      PINUSE='OUT';
    'DMI_TX_DN'<0>:
      PIN_NUMBER='(0,0,0,0,0,0,0,0,CG4,0,0,0,0,0,0,0,0,0,0,0,0,0,0,0,0,0,0,0,0,0~
)';
      OUTPUT_LOAD='(1.0,-1.0)';
      PINUSE='OUT';
    'DMI_TX_DP'<3>:
      PIN_NUMBER='(0,0,0,0,0,0,0,0,CR4,0,0,0,0,0,0,0,0,0,0,0,0,0,0,0,0,0,0,0,0,0~
)';
      OUTPUT_LOAD='(1.0,-1.0)';
      PINUSE='OUT';
    'DMI_TX_DP'<2>:
      PIN_NUMBER='(0,0,0,0,0,0,0,0,CM3,0,0,0,0,0,0,0,0,0,0,0,0,0,0,0,0,0,0,0,0,0~
)';
      OUTPUT_LOAD='(1.0,-1.0)';
      PINUSE='OUT';
    'DMI_TX_DP'<1>:
      PIN_NUMBER='(0,0,0,0,0,0,0,0,CL4,0,0,0,0,0,0,0,0,0,0,0,0,0,0,0,0,0,0,0,0,0~
)';
      OUTPUT_LOAD='(1.0,-1.0)';
      PINUSE='OUT';
    'DMI_TX_DP'<0>:
      PIN_NUMBER='(0,0,0,0,0,0,0,0,CH5,0,0,0,0,0,0,0,0,0,0,0,0,0,0,0,0,0,0,0,0,0~
)';
      OUTPUT_LOAD='(1.0,-1.0)';
      PINUSE='OUT';
    'EAR_N':
      PIN_NUMBER='(AJ14,0,0,0,0,0,0,0,0,0,0,0,0,0,0,0,0,0,0,0,0,0,0,0,0,0,0,0,0,~
0)';
      INPUT_LOAD='(-0.01,0.01)';
      PINUSE='IN';
    'ERROR_N'<2>:
      PIN_NUMBER='(AL12,0,0,0,0,0,0,0,0,0,0,0,0,0,0,0,0,0,0,0,0,0,0,0,0,0,0,0,0,~
0)';
      OUTPUT_LOAD='(1.0,-1.0)';
      PINUSE='OUT';
    'ERROR_N'<1>:
      PIN_NUMBER='(AK11,0,0,0,0,0,0,0,0,0,0,0,0,0,0,0,0,0,0,0,0,0,0,0,0,0,0,0,0,~
0)';
      OUTPUT_LOAD='(1.0,-1.0)';
      PINUSE='OUT';
    'ERROR_N'<0>:
      PIN_NUMBER='(AJ12,0,0,0,0,0,0,0,0,0,0,0,0,0,0,0,0,0,0,0,0,0,0,0,0,0,0,0,0,~
0)';
      OUTPUT_LOAD='(1.0,-1.0)';
      PINUSE='OUT';
    'FIVR_FAULT':
      PIN_NUMBER='(0,AU14,0,0,0,0,0,0,0,0,0,0,0,0,0,0,0,0,0,0,0,0,0,0,0,0,0,0,0,~
0)';
      OUTPUT_LOAD='(1.0,-1.0)';
      PINUSE='OUT';
    'FRMAGENT':
      PIN_NUMBER='(AV17,0,0,0,0,0,0,0,0,0,0,0,0,0,0,0,0,0,0,0,0,0,0,0,0,0,0,0,0,~
0)';
      INPUT_LOAD='(-0.01,0.01)';
      PINUSE='IN';
    'LEGACY_SKT':
      PIN_NUMBER='(AE20,0,0,0,0,0,0,0,0,0,0,0,0,0,0,0,0,0,0,0,0,0,0,0,0,0,0,0,0,~
0)';
      INPUT_LOAD='(-0.01,0.01)';
      PINUSE='IN';
    'MCP01_RBIAS'<1>:
      PIN_NUMBER='(CT31,0,0,0,0,0,0,0,0,0,0,0,0,0,0,0,0,0,0,0,0,0,0,0,0,0,0,0,0,~
0)';
      BIDIRECTIONAL='TRUE';
      INPUT_LOAD='(-0.01,0.01)';
      OUTPUT_LOAD='(1.0,-1.0)';
      PINUSE='BI';
    'MCP01_RBIAS'<0>:
      PIN_NUMBER='(CU32,0,0,0,0,0,0,0,0,0,0,0,0,0,0,0,0,0,0,0,0,0,0,0,0,0,0,0,0,~
0)';
      BIDIRECTIONAL='TRUE';
      INPUT_LOAD='(-0.01,0.01)';
      OUTPUT_LOAD='(1.0,-1.0)';
      PINUSE='BI';
    'MEM_HOT_C012_N':
      PIN_NUMBER='(AH13,0,0,0,0,0,0,0,0,0,0,0,0,0,0,0,0,0,0,0,0,0,0,0,0,0,0,0,0,~
0)';
      BIDIRECTIONAL='TRUE';
      INPUT_LOAD='(-0.01,0.01)';
      OUTPUT_LOAD='(1.0,-1.0)';
      PINUSE='BI';
    'MEM_HOT_C345_N':
      PIN_NUMBER='(AF13,0,0,0,0,0,0,0,0,0,0,0,0,0,0,0,0,0,0,0,0,0,0,0,0,0,0,0,0,~
0)';
      BIDIRECTIONAL='TRUE';
      INPUT_LOAD='(-0.01,0.01)';
      OUTPUT_LOAD='(1.0,-1.0)';
      PINUSE='BI';
    'MSMI_N':
      PIN_NUMBER='(AN20,0,0,0,0,0,0,0,0,0,0,0,0,0,0,0,0,0,0,0,0,0,0,0,0,0,0,0,0,~
0)';
      BIDIRECTIONAL='TRUE';
      INPUT_LOAD='(-0.01,0.01)';
      OUTPUT_LOAD='(1.0,-1.0)';
      PINUSE='BI';
    'NMI':
      PIN_NUMBER='(AP11,0,0,0,0,0,0,0,0,0,0,0,0,0,0,0,0,0,0,0,0,0,0,0,0,0,0,0,0,~
0)';
      INPUT_LOAD='(-0.01,0.01)';
      PINUSE='IN';
    'PE012_RBIAS'<1>:
      PIN_NUMBER='(CL30,0,0,0,0,0,0,0,0,0,0,0,0,0,0,0,0,0,0,0,0,0,0,0,0,0,0,0,0,~
0)';
      BIDIRECTIONAL='TRUE';
      INPUT_LOAD='(-0.01,0.01)';
      OUTPUT_LOAD='(1.0,-1.0)';
      PINUSE='BI';
    'PE012_RBIAS'<0>:
      PIN_NUMBER='(CN30,0,0,0,0,0,0,0,0,0,0,0,0,0,0,0,0,0,0,0,0,0,0,0,0,0,0,0,0,~
0)';
      BIDIRECTIONAL='TRUE';
      INPUT_LOAD='(-0.01,0.01)';
      OUTPUT_LOAD='(1.0,-1.0)';
      PINUSE='BI';
    'PE1_RX_DN'<15>:
      PIN_NUMBER='(0,0,0,0,0,0,0,0,0,DU16,0,0,0,0,0,0,0,0,0,0,0,0,0,0,0,0,0,0,0,~
0)';
      INPUT_LOAD='(-0.01,0.01)';
      PINUSE='IN';
    'PE1_RX_DN'<14>:
      PIN_NUMBER='(0,0,0,0,0,0,0,0,0,DY15,0,0,0,0,0,0,0,0,0,0,0,0,0,0,0,0,0,0,0,~
0)';
      INPUT_LOAD='(-0.01,0.01)';
      PINUSE='IN';
    'PE1_RX_DN'<13>:
      PIN_NUMBER='(0,0,0,0,0,0,0,0,0,DW14,0,0,0,0,0,0,0,0,0,0,0,0,0,0,0,0,0,0,0,~
0)';
      INPUT_LOAD='(-0.01,0.01)';
      PINUSE='IN';
    'PE1_RX_DN'<12>:
      PIN_NUMBER='(0,0,0,0,0,0,0,0,0,DV13,0,0,0,0,0,0,0,0,0,0,0,0,0,0,0,0,0,0,0,~
0)';
      INPUT_LOAD='(-0.01,0.01)';
      PINUSE='IN';
    'PE1_RX_DN'<11>:
      PIN_NUMBER='(0,0,0,0,0,0,0,0,0,DT13,0,0,0,0,0,0,0,0,0,0,0,0,0,0,0,0,0,0,0,~
0)';
      INPUT_LOAD='(-0.01,0.01)';
      PINUSE='IN';
    'PE1_RX_DN'<10>:
      PIN_NUMBER='(0,0,0,0,0,0,0,0,0,DT11,0,0,0,0,0,0,0,0,0,0,0,0,0,0,0,0,0,0,0,~
0)';
      INPUT_LOAD='(-0.01,0.01)';
      PINUSE='IN';
    'PE1_RX_DN'<9>:
      PIN_NUMBER='(0,0,0,0,0,0,0,0,0,DP11,0,0,0,0,0,0,0,0,0,0,0,0,0,0,0,0,0,0,0,~
0)';
      INPUT_LOAD='(-0.01,0.01)';
      PINUSE='IN';
    'PE1_RX_DN'<8>:
      PIN_NUMBER='(0,0,0,0,0,0,0,0,0,DM11,0,0,0,0,0,0,0,0,0,0,0,0,0,0,0,0,0,0,0,~
0)';
      INPUT_LOAD='(-0.01,0.01)';
      PINUSE='IN';
    'PE1_RX_DN'<7>:
      PIN_NUMBER='(0,0,0,0,0,0,0,0,0,DM9,0,0,0,0,0,0,0,0,0,0,0,0,0,0,0,0,0,0,0,0~
)';
      INPUT_LOAD='(-0.01,0.01)';
      PINUSE='IN';
    'PE1_RX_DN'<6>:
      PIN_NUMBER='(0,0,0,0,0,0,0,0,0,DK9,0,0,0,0,0,0,0,0,0,0,0,0,0,0,0,0,0,0,0,0~
)';
      INPUT_LOAD='(-0.01,0.01)';
      PINUSE='IN';
    'PE1_RX_DN'<5>:
      PIN_NUMBER='(0,0,0,0,0,0,0,0,0,DH9,0,0,0,0,0,0,0,0,0,0,0,0,0,0,0,0,0,0,0,0~
)';
      INPUT_LOAD='(-0.01,0.01)';
      PINUSE='IN';
    'PE1_RX_DN'<4>:
      PIN_NUMBER='(0,0,0,0,0,0,0,0,0,DE10,0,0,0,0,0,0,0,0,0,0,0,0,0,0,0,0,0,0,0,~
0)';
      INPUT_LOAD='(-0.01,0.01)';
      PINUSE='IN';
    'PE1_RX_DN'<3>:
      PIN_NUMBER='(0,0,0,0,0,0,0,0,0,DC10,0,0,0,0,0,0,0,0,0,0,0,0,0,0,0,0,0,0,0,~
0)';
      INPUT_LOAD='(-0.01,0.01)';
      PINUSE='IN';
    'PE1_RX_DN'<2>:
      PIN_NUMBER='(0,0,0,0,0,0,0,0,0,DC8,0,0,0,0,0,0,0,0,0,0,0,0,0,0,0,0,0,0,0,0~
)';
      INPUT_LOAD='(-0.01,0.01)';
      PINUSE='IN';
    'PE1_RX_DN'<1>:
      PIN_NUMBER='(0,0,0,0,0,0,0,0,0,DA8,0,0,0,0,0,0,0,0,0,0,0,0,0,0,0,0,0,0,0,0~
)';
      INPUT_LOAD='(-0.01,0.01)';
      PINUSE='IN';
    'PE1_RX_DN'<0>:
      PIN_NUMBER='(0,0,0,0,0,0,0,0,0,CW8,0,0,0,0,0,0,0,0,0,0,0,0,0,0,0,0,0,0,0,0~
)';
      INPUT_LOAD='(-0.01,0.01)';
      PINUSE='IN';
    'PE1_RX_DP'<15>:
      PIN_NUMBER='(0,0,0,0,0,0,0,0,0,DT15,0,0,0,0,0,0,0,0,0,0,0,0,0,0,0,0,0,0,0,~
0)';
      INPUT_LOAD='(-0.01,0.01)';
      PINUSE='IN';
    'PE1_RX_DP'<14>:
      PIN_NUMBER='(0,0,0,0,0,0,0,0,0,DV15,0,0,0,0,0,0,0,0,0,0,0,0,0,0,0,0,0,0,0,~
0)';
      INPUT_LOAD='(-0.01,0.01)';
      PINUSE='IN';
    'PE1_RX_DP'<13>:
      PIN_NUMBER='(0,0,0,0,0,0,0,0,0,DY13,0,0,0,0,0,0,0,0,0,0,0,0,0,0,0,0,0,0,0,~
0)';
      INPUT_LOAD='(-0.01,0.01)';
      PINUSE='IN';
    'PE1_RX_DP'<12>:
      PIN_NUMBER='(0,0,0,0,0,0,0,0,0,DU12,0,0,0,0,0,0,0,0,0,0,0,0,0,0,0,0,0,0,0,~
0)';
      INPUT_LOAD='(-0.01,0.01)';
      PINUSE='IN';
    'PE1_RX_DP'<11>:
      PIN_NUMBER='(0,0,0,0,0,0,0,0,0,DP13,0,0,0,0,0,0,0,0,0,0,0,0,0,0,0,0,0,0,0,~
0)';
      INPUT_LOAD='(-0.01,0.01)';
      PINUSE='IN';
    'PE1_RX_DP'<10>:
      PIN_NUMBER='(0,0,0,0,0,0,0,0,0,DR12,0,0,0,0,0,0,0,0,0,0,0,0,0,0,0,0,0,0,0,~
0)';
      INPUT_LOAD='(-0.01,0.01)';
      PINUSE='IN';
    'PE1_RX_DP'<9>:
      PIN_NUMBER='(0,0,0,0,0,0,0,0,0,DN10,0,0,0,0,0,0,0,0,0,0,0,0,0,0,0,0,0,0,0,~
0)';
      INPUT_LOAD='(-0.01,0.01)';
      PINUSE='IN';
    'PE1_RX_DP'<8>:
      PIN_NUMBER='(0,0,0,0,0,0,0,0,0,DK11,0,0,0,0,0,0,0,0,0,0,0,0,0,0,0,0,0,0,0,~
0)';
      INPUT_LOAD='(-0.01,0.01)';
      PINUSE='IN';
    'PE1_RX_DP'<7>:
      PIN_NUMBER='(0,0,0,0,0,0,0,0,0,DL10,0,0,0,0,0,0,0,0,0,0,0,0,0,0,0,0,0,0,0,~
0)';
      INPUT_LOAD='(-0.01,0.01)';
      PINUSE='IN';
    'PE1_RX_DP'<6>:
      PIN_NUMBER='(0,0,0,0,0,0,0,0,0,DJ8,0,0,0,0,0,0,0,0,0,0,0,0,0,0,0,0,0,0,0,0~
)';
      INPUT_LOAD='(-0.01,0.01)';
      PINUSE='IN';
    'PE1_RX_DP'<5>:
      PIN_NUMBER='(0,0,0,0,0,0,0,0,0,DF9,0,0,0,0,0,0,0,0,0,0,0,0,0,0,0,0,0,0,0,0~
)';
      INPUT_LOAD='(-0.01,0.01)';
      PINUSE='IN';
    'PE1_RX_DP'<4>:
      PIN_NUMBER='(0,0,0,0,0,0,0,0,0,DD9,0,0,0,0,0,0,0,0,0,0,0,0,0,0,0,0,0,0,0,0~
)';
      INPUT_LOAD='(-0.01,0.01)';
      PINUSE='IN';
    'PE1_RX_DP'<3>:
      PIN_NUMBER='(0,0,0,0,0,0,0,0,0,DA10,0,0,0,0,0,0,0,0,0,0,0,0,0,0,0,0,0,0,0,~
0)';
      INPUT_LOAD='(-0.01,0.01)';
      PINUSE='IN';
    'PE1_RX_DP'<2>:
      PIN_NUMBER='(0,0,0,0,0,0,0,0,0,DB9,0,0,0,0,0,0,0,0,0,0,0,0,0,0,0,0,0,0,0,0~
)';
      INPUT_LOAD='(-0.01,0.01)';
      PINUSE='IN';
    'PE1_RX_DP'<1>:
      PIN_NUMBER='(0,0,0,0,0,0,0,0,0,CY7,0,0,0,0,0,0,0,0,0,0,0,0,0,0,0,0,0,0,0,0~
)';
      INPUT_LOAD='(-0.01,0.01)';
      PINUSE='IN';
    'PE1_RX_DP'<0>:
      PIN_NUMBER='(0,0,0,0,0,0,0,0,0,CU8,0,0,0,0,0,0,0,0,0,0,0,0,0,0,0,0,0,0,0,0~
)';
      INPUT_LOAD='(-0.01,0.01)';
      PINUSE='IN';
    'PE1_TX_DN'<15>:
      PIN_NUMBER='(0,0,0,0,0,0,0,0,0,ED9,0,0,0,0,0,0,0,0,0,0,0,0,0,0,0,0,0,0,0,0~
)';
      OUTPUT_LOAD='(1.0,-1.0)';
      PINUSE='OUT';
    'PE1_TX_DN'<14>:
      PIN_NUMBER='(0,0,0,0,0,0,0,0,0,EA8,0,0,0,0,0,0,0,0,0,0,0,0,0,0,0,0,0,0,0,0~
)';
      OUTPUT_LOAD='(1.0,-1.0)';
      PINUSE='OUT';
    'PE1_TX_DN'<13>:
      PIN_NUMBER='(0,0,0,0,0,0,0,0,0,DY7,0,0,0,0,0,0,0,0,0,0,0,0,0,0,0,0,0,0,0,0~
)';
      OUTPUT_LOAD='(1.0,-1.0)';
      PINUSE='OUT';
    'PE1_TX_DN'<12>:
      PIN_NUMBER='(0,0,0,0,0,0,0,0,0,DV7,0,0,0,0,0,0,0,0,0,0,0,0,0,0,0,0,0,0,0,0~
)';
      OUTPUT_LOAD='(1.0,-1.0)';
      PINUSE='OUT';
    'PE1_TX_DN'<11>:
      PIN_NUMBER='(0,0,0,0,0,0,0,0,0,DU6,0,0,0,0,0,0,0,0,0,0,0,0,0,0,0,0,0,0,0,0~
)';
      OUTPUT_LOAD='(1.0,-1.0)';
      PINUSE='OUT';
    'PE1_TX_DN'<10>:
      PIN_NUMBER='(0,0,0,0,0,0,0,0,0,DW4,0,0,0,0,0,0,0,0,0,0,0,0,0,0,0,0,0,0,0,0~
)';
      OUTPUT_LOAD='(1.0,-1.0)';
      PINUSE='OUT';
    'PE1_TX_DN'<9>:
      PIN_NUMBER='(0,0,0,0,0,0,0,0,0,DV3,0,0,0,0,0,0,0,0,0,0,0,0,0,0,0,0,0,0,0,0~
)';
      OUTPUT_LOAD='(1.0,-1.0)';
      PINUSE='OUT';
    'PE1_TX_DN'<8>:
      PIN_NUMBER='(0,0,0,0,0,0,0,0,0,DT5,0,0,0,0,0,0,0,0,0,0,0,0,0,0,0,0,0,0,0,0~
)';
      OUTPUT_LOAD='(1.0,-1.0)';
      PINUSE='OUT';
    'PE1_TX_DN'<7>:
      PIN_NUMBER='(0,0,0,0,0,0,0,0,0,DN4,0,0,0,0,0,0,0,0,0,0,0,0,0,0,0,0,0,0,0,0~
)';
      OUTPUT_LOAD='(1.0,-1.0)';
      PINUSE='OUT';
    'PE1_TX_DN'<6>:
      PIN_NUMBER='(0,0,0,0,0,0,0,0,0,DM3,0,0,0,0,0,0,0,0,0,0,0,0,0,0,0,0,0,0,0,0~
)';
      OUTPUT_LOAD='(1.0,-1.0)';
      PINUSE='OUT';
    'PE1_TX_DN'<5>:
      PIN_NUMBER='(0,0,0,0,0,0,0,0,0,DK3,0,0,0,0,0,0,0,0,0,0,0,0,0,0,0,0,0,0,0,0~
)';
      OUTPUT_LOAD='(1.0,-1.0)';
      PINUSE='OUT';
    'PE1_TX_DN'<4>:
      PIN_NUMBER='(0,0,0,0,0,0,0,0,0,DG4,0,0,0,0,0,0,0,0,0,0,0,0,0,0,0,0,0,0,0,0~
)';
      OUTPUT_LOAD='(1.0,-1.0)';
      PINUSE='OUT';
    'PE1_TX_DN'<3>:
      PIN_NUMBER='(0,0,0,0,0,0,0,0,0,DE4,0,0,0,0,0,0,0,0,0,0,0,0,0,0,0,0,0,0,0,0~
)';
      OUTPUT_LOAD='(1.0,-1.0)';
      PINUSE='OUT';
    'PE1_TX_DN'<2>:
      PIN_NUMBER='(0,0,0,0,0,0,0,0,0,DE2,0,0,0,0,0,0,0,0,0,0,0,0,0,0,0,0,0,0,0,0~
)';
      OUTPUT_LOAD='(1.0,-1.0)';
      PINUSE='OUT';
    'PE1_TX_DN'<1>:
      PIN_NUMBER='(0,0,0,0,0,0,0,0,0,DC2,0,0,0,0,0,0,0,0,0,0,0,0,0,0,0,0,0,0,0,0~
)';
      OUTPUT_LOAD='(1.0,-1.0)';
      PINUSE='OUT';
    'PE1_TX_DN'<0>:
      PIN_NUMBER='(0,0,0,0,0,0,0,0,0,DA2,0,0,0,0,0,0,0,0,0,0,0,0,0,0,0,0,0,0,0,0~
)';
      OUTPUT_LOAD='(1.0,-1.0)';
      PINUSE='OUT';
    'PE1_TX_DP'<15>:
      PIN_NUMBER='(0,0,0,0,0,0,0,0,0,EC8,0,0,0,0,0,0,0,0,0,0,0,0,0,0,0,0,0,0,0,0~
)';
      OUTPUT_LOAD='(1.0,-1.0)';
      PINUSE='OUT';
    'PE1_TX_DP'<14>:
      PIN_NUMBER='(0,0,0,0,0,0,0,0,0,EB7,0,0,0,0,0,0,0,0,0,0,0,0,0,0,0,0,0,0,0,0~
)';
      OUTPUT_LOAD='(1.0,-1.0)';
      PINUSE='OUT';
    'PE1_TX_DP'<13>:
      PIN_NUMBER='(0,0,0,0,0,0,0,0,0,DW6,0,0,0,0,0,0,0,0,0,0,0,0,0,0,0,0,0,0,0,0~
)';
      OUTPUT_LOAD='(1.0,-1.0)';
      PINUSE='OUT';
    'PE1_TX_DP'<12>:
      PIN_NUMBER='(0,0,0,0,0,0,0,0,0,DT7,0,0,0,0,0,0,0,0,0,0,0,0,0,0,0,0,0,0,0,0~
)';
      OUTPUT_LOAD='(1.0,-1.0)';
      PINUSE='OUT';
    'PE1_TX_DP'<11>:
      PIN_NUMBER='(0,0,0,0,0,0,0,0,0,DV5,0,0,0,0,0,0,0,0,0,0,0,0,0,0,0,0,0,0,0,0~
)';
      OUTPUT_LOAD='(1.0,-1.0)';
      PINUSE='OUT';
    'PE1_TX_DP'<10>:
      PIN_NUMBER='(0,0,0,0,0,0,0,0,0,DU4,0,0,0,0,0,0,0,0,0,0,0,0,0,0,0,0,0,0,0,0~
)';
      OUTPUT_LOAD='(1.0,-1.0)';
      PINUSE='OUT';
    'PE1_TX_DP'<9>:
      PIN_NUMBER='(0,0,0,0,0,0,0,0,0,DU2,0,0,0,0,0,0,0,0,0,0,0,0,0,0,0,0,0,0,0,0~
)';
      OUTPUT_LOAD='(1.0,-1.0)';
      PINUSE='OUT';
    'PE1_TX_DP'<8>:
      PIN_NUMBER='(0,0,0,0,0,0,0,0,0,DR4,0,0,0,0,0,0,0,0,0,0,0,0,0,0,0,0,0,0,0,0~
)';
      OUTPUT_LOAD='(1.0,-1.0)';
      PINUSE='OUT';
    'PE1_TX_DP'<7>:
      PIN_NUMBER='(0,0,0,0,0,0,0,0,0,DP3,0,0,0,0,0,0,0,0,0,0,0,0,0,0,0,0,0,0,0,0~
)';
      OUTPUT_LOAD='(1.0,-1.0)';
      PINUSE='OUT';
    'PE1_TX_DP'<6>:
      PIN_NUMBER='(0,0,0,0,0,0,0,0,0,DL2,0,0,0,0,0,0,0,0,0,0,0,0,0,0,0,0,0,0,0,0~
)';
      OUTPUT_LOAD='(1.0,-1.0)';
      PINUSE='OUT';
    'PE1_TX_DP'<5>:
      PIN_NUMBER='(0,0,0,0,0,0,0,0,0,DH3,0,0,0,0,0,0,0,0,0,0,0,0,0,0,0,0,0,0,0,0~
)';
      OUTPUT_LOAD='(1.0,-1.0)';
      PINUSE='OUT';
    'PE1_TX_DP'<4>:
      PIN_NUMBER='(0,0,0,0,0,0,0,0,0,DF3,0,0,0,0,0,0,0,0,0,0,0,0,0,0,0,0,0,0,0,0~
)';
      OUTPUT_LOAD='(1.0,-1.0)';
      PINUSE='OUT';
    'PE1_TX_DP'<3>:
      PIN_NUMBER='(0,0,0,0,0,0,0,0,0,DC4,0,0,0,0,0,0,0,0,0,0,0,0,0,0,0,0,0,0,0,0~
)';
      OUTPUT_LOAD='(1.0,-1.0)';
      PINUSE='OUT';
    'PE1_TX_DP'<2>:
      PIN_NUMBER='(0,0,0,0,0,0,0,0,0,DD3,0,0,0,0,0,0,0,0,0,0,0,0,0,0,0,0,0,0,0,0~
)';
      OUTPUT_LOAD='(1.0,-1.0)';
      PINUSE='OUT';
    'PE1_TX_DP'<1>:
      PIN_NUMBER='(0,0,0,0,0,0,0,0,0,DB1,0,0,0,0,0,0,0,0,0,0,0,0,0,0,0,0,0,0,0,0~
)';
      OUTPUT_LOAD='(1.0,-1.0)';
      PINUSE='OUT';
    'PE1_TX_DP'<0>:
      PIN_NUMBER='(0,0,0,0,0,0,0,0,0,CW2,0,0,0,0,0,0,0,0,0,0,0,0,0,0,0,0,0,0,0,0~
)';
      OUTPUT_LOAD='(1.0,-1.0)';
      PINUSE='OUT';
    'PE2_RX_DN'<15>:
      PIN_NUMBER='(0,0,0,0,0,0,0,0,0,0,BK9,0,0,0,0,0,0,0,0,0,0,0,0,0,0,0,0,0,0,0~
)';
      INPUT_LOAD='(-0.01,0.01)';
      PINUSE='IN';
    'PE2_RX_DN'<14>:
      PIN_NUMBER='(0,0,0,0,0,0,0,0,0,0,BL8,0,0,0,0,0,0,0,0,0,0,0,0,0,0,0,0,0,0,0~
)';
      INPUT_LOAD='(-0.01,0.01)';
      PINUSE='IN';
    'PE2_RX_DN'<13>:
      PIN_NUMBER='(0,0,0,0,0,0,0,0,0,0,BN8,0,0,0,0,0,0,0,0,0,0,0,0,0,0,0,0,0,0,0~
)';
      INPUT_LOAD='(-0.01,0.01)';
      PINUSE='IN';
    'PE2_RX_DN'<12>:
      PIN_NUMBER='(0,0,0,0,0,0,0,0,0,0,BR8,0,0,0,0,0,0,0,0,0,0,0,0,0,0,0,0,0,0,0~
)';
      INPUT_LOAD='(-0.01,0.01)';
      PINUSE='IN';
    'PE2_RX_DN'<11>:
      PIN_NUMBER='(0,0,0,0,0,0,0,0,0,0,BT7,0,0,0,0,0,0,0,0,0,0,0,0,0,0,0,0,0,0,0~
)';
      INPUT_LOAD='(-0.01,0.01)';
      PINUSE='IN';
    'PE2_RX_DN'<10>:
      PIN_NUMBER='(0,0,0,0,0,0,0,0,0,0,BV7,0,0,0,0,0,0,0,0,0,0,0,0,0,0,0,0,0,0,0~
)';
      INPUT_LOAD='(-0.01,0.01)';
      PINUSE='IN';
    'PE2_RX_DN'<9>:
      PIN_NUMBER='(0,0,0,0,0,0,0,0,0,0,BY7,0,0,0,0,0,0,0,0,0,0,0,0,0,0,0,0,0,0,0~
)';
      INPUT_LOAD='(-0.01,0.01)';
      PINUSE='IN';
    'PE2_RX_DN'<8>:
      PIN_NUMBER='(0,0,0,0,0,0,0,0,0,0,BY9,0,0,0,0,0,0,0,0,0,0,0,0,0,0,0,0,0,0,0~
)';
      INPUT_LOAD='(-0.01,0.01)';
      PINUSE='IN';
    'PE2_RX_DN'<7>:
      PIN_NUMBER='(0,0,0,0,0,0,0,0,0,0,CE8,0,0,0,0,0,0,0,0,0,0,0,0,0,0,0,0,0,0,0~
)';
      INPUT_LOAD='(-0.01,0.01)';
      PINUSE='IN';
    'PE2_RX_DN'<6>:
      PIN_NUMBER='(0,0,0,0,0,0,0,0,0,0,CE6,0,0,0,0,0,0,0,0,0,0,0,0,0,0,0,0,0,0,0~
)';
      INPUT_LOAD='(-0.01,0.01)';
      PINUSE='IN';
    'PE2_RX_DN'<5>:
      PIN_NUMBER='(0,0,0,0,0,0,0,0,0,0,CG8,0,0,0,0,0,0,0,0,0,0,0,0,0,0,0,0,0,0,0~
)';
      INPUT_LOAD='(-0.01,0.01)';
      PINUSE='IN';
    'PE2_RX_DN'<4>:
      PIN_NUMBER='(0,0,0,0,0,0,0,0,0,0,CK7,0,0,0,0,0,0,0,0,0,0,0,0,0,0,0,0,0,0,0~
)';
      INPUT_LOAD='(-0.01,0.01)';
      PINUSE='IN';
    'PE2_RX_DN'<3>:
      PIN_NUMBER='(0,0,0,0,0,0,0,0,0,0,CM7,0,0,0,0,0,0,0,0,0,0,0,0,0,0,0,0,0,0,0~
)';
      INPUT_LOAD='(-0.01,0.01)';
      PINUSE='IN';
    'PE2_RX_DN'<2>:
      PIN_NUMBER='(0,0,0,0,0,0,0,0,0,0,CP7,0,0,0,0,0,0,0,0,0,0,0,0,0,0,0,0,0,0,0~
)';
      INPUT_LOAD='(-0.01,0.01)';
      PINUSE='IN';
    'PE2_RX_DN'<1>:
      PIN_NUMBER='(0,0,0,0,0,0,0,0,0,0,CP9,0,0,0,0,0,0,0,0,0,0,0,0,0,0,0,0,0,0,0~
)';
      INPUT_LOAD='(-0.01,0.01)';
      PINUSE='IN';
    'PE2_RX_DN'<0>:
      PIN_NUMBER='(0,0,0,0,0,0,0,0,0,0,CT9,0,0,0,0,0,0,0,0,0,0,0,0,0,0,0,0,0,0,0~
)';
      INPUT_LOAD='(-0.01,0.01)';
      PINUSE='IN';
    'PE2_RX_DP'<15>:
      PIN_NUMBER='(0,0,0,0,0,0,0,0,0,0,BJ10,0,0,0,0,0,0,0,0,0,0,0,0,0,0,0,0,0,0,~
0)';
      INPUT_LOAD='(-0.01,0.01)';
      PINUSE='IN';
    'PE2_RX_DP'<14>:
      PIN_NUMBER='(0,0,0,0,0,0,0,0,0,0,BJ8,0,0,0,0,0,0,0,0,0,0,0,0,0,0,0,0,0,0,0~
)';
      INPUT_LOAD='(-0.01,0.01)';
      PINUSE='IN';
    'PE2_RX_DP'<13>:
      PIN_NUMBER='(0,0,0,0,0,0,0,0,0,0,BM7,0,0,0,0,0,0,0,0,0,0,0,0,0,0,0,0,0,0,0~
)';
      INPUT_LOAD='(-0.01,0.01)';
      PINUSE='IN';
    'PE2_RX_DP'<12>:
      PIN_NUMBER='(0,0,0,0,0,0,0,0,0,0,BP9,0,0,0,0,0,0,0,0,0,0,0,0,0,0,0,0,0,0,0~
)';
      INPUT_LOAD='(-0.01,0.01)';
      PINUSE='IN';
    'PE2_RX_DP'<11>:
      PIN_NUMBER='(0,0,0,0,0,0,0,0,0,0,BP7,0,0,0,0,0,0,0,0,0,0,0,0,0,0,0,0,0,0,0~
)';
      INPUT_LOAD='(-0.01,0.01)';
      PINUSE='IN';
    'PE2_RX_DP'<10>:
      PIN_NUMBER='(0,0,0,0,0,0,0,0,0,0,BU6,0,0,0,0,0,0,0,0,0,0,0,0,0,0,0,0,0,0,0~
)';
      INPUT_LOAD='(-0.01,0.01)';
      PINUSE='IN';
    'PE2_RX_DP'<9>:
      PIN_NUMBER='(0,0,0,0,0,0,0,0,0,0,BW8,0,0,0,0,0,0,0,0,0,0,0,0,0,0,0,0,0,0,0~
)';
      INPUT_LOAD='(-0.01,0.01)';
      PINUSE='IN';
    'PE2_RX_DP'<8>:
      PIN_NUMBER='(0,0,0,0,0,0,0,0,0,0,BV9,0,0,0,0,0,0,0,0,0,0,0,0,0,0,0,0,0,0,0~
)';
      INPUT_LOAD='(-0.01,0.01)';
      PINUSE='IN';
    'PE2_RX_DP'<7>:
      PIN_NUMBER='(0,0,0,0,0,0,0,0,0,0,CC8,0,0,0,0,0,0,0,0,0,0,0,0,0,0,0,0,0,0,0~
)';
      INPUT_LOAD='(-0.01,0.01)';
      PINUSE='IN';
    'PE2_RX_DP'<6>:
      PIN_NUMBER='(0,0,0,0,0,0,0,0,0,0,CD7,0,0,0,0,0,0,0,0,0,0,0,0,0,0,0,0,0,0,0~
)';
      INPUT_LOAD='(-0.01,0.01)';
      PINUSE='IN';
    'PE2_RX_DP'<5>:
      PIN_NUMBER='(0,0,0,0,0,0,0,0,0,0,CF7,0,0,0,0,0,0,0,0,0,0,0,0,0,0,0,0,0,0,0~
)';
      INPUT_LOAD='(-0.01,0.01)';
      PINUSE='IN';
    'PE2_RX_DP'<4>:
      PIN_NUMBER='(0,0,0,0,0,0,0,0,0,0,CH7,0,0,0,0,0,0,0,0,0,0,0,0,0,0,0,0,0,0,0~
)';
      INPUT_LOAD='(-0.01,0.01)';
      PINUSE='IN';
    'PE2_RX_DP'<3>:
      PIN_NUMBER='(0,0,0,0,0,0,0,0,0,0,CL6,0,0,0,0,0,0,0,0,0,0,0,0,0,0,0,0,0,0,0~
)';
      INPUT_LOAD='(-0.01,0.01)';
      PINUSE='IN';
    'PE2_RX_DP'<2>:
      PIN_NUMBER='(0,0,0,0,0,0,0,0,0,0,CN8,0,0,0,0,0,0,0,0,0,0,0,0,0,0,0,0,0,0,0~
)';
      INPUT_LOAD='(-0.01,0.01)';
      PINUSE='IN';
    'PE2_RX_DP'<1>:
      PIN_NUMBER='(0,0,0,0,0,0,0,0,0,0,CM9,0,0,0,0,0,0,0,0,0,0,0,0,0,0,0,0,0,0,0~
)';
      INPUT_LOAD='(-0.01,0.01)';
      PINUSE='IN';
    'PE2_RX_DP'<0>:
      PIN_NUMBER='(0,0,0,0,0,0,0,0,0,0,CR8,0,0,0,0,0,0,0,0,0,0,0,0,0,0,0,0,0,0,0~
)';
      INPUT_LOAD='(-0.01,0.01)';
      PINUSE='IN';
    'PE2_TX_DN'<15>:
      PIN_NUMBER='(0,0,0,0,0,0,0,0,0,0,BM5,0,0,0,0,0,0,0,0,0,0,0,0,0,0,0,0,0,0,0~
)';
      OUTPUT_LOAD='(1.0,-1.0)';
      PINUSE='OUT';
    'PE2_TX_DN'<14>:
      PIN_NUMBER='(0,0,0,0,0,0,0,0,0,0,BL4,0,0,0,0,0,0,0,0,0,0,0,0,0,0,0,0,0,0,0~
)';
      OUTPUT_LOAD='(1.0,-1.0)';
      PINUSE='OUT';
    'PE2_TX_DN'<13>:
      PIN_NUMBER='(0,0,0,0,0,0,0,0,0,0,BP5,0,0,0,0,0,0,0,0,0,0,0,0,0,0,0,0,0,0,0~
)';
      OUTPUT_LOAD='(1.0,-1.0)';
      PINUSE='OUT';
    'PE2_TX_DN'<12>:
      PIN_NUMBER='(0,0,0,0,0,0,0,0,0,0,BU4,0,0,0,0,0,0,0,0,0,0,0,0,0,0,0,0,0,0,0~
)';
      OUTPUT_LOAD='(1.0,-1.0)';
      PINUSE='OUT';
    'PE2_TX_DN'<11>:
      PIN_NUMBER='(0,0,0,0,0,0,0,0,0,0,BW4,0,0,0,0,0,0,0,0,0,0,0,0,0,0,0,0,0,0,0~
)';
      OUTPUT_LOAD='(1.0,-1.0)';
      PINUSE='OUT';
    'PE2_TX_DN'<10>:
      PIN_NUMBER='(0,0,0,0,0,0,0,0,0,0,CA4,0,0,0,0,0,0,0,0,0,0,0,0,0,0,0,0,0,0,0~
)';
      OUTPUT_LOAD='(1.0,-1.0)';
      PINUSE='OUT';
    'PE2_TX_DN'<9>:
      PIN_NUMBER='(0,0,0,0,0,0,0,0,0,0,CB3,0,0,0,0,0,0,0,0,0,0,0,0,0,0,0,0,0,0,0~
)';
      OUTPUT_LOAD='(1.0,-1.0)';
      PINUSE='OUT';
    'PE2_TX_DN'<8>:
      PIN_NUMBER='(0,0,0,0,0,0,0,0,0,0,CC2,0,0,0,0,0,0,0,0,0,0,0,0,0,0,0,0,0,0,0~
)';
      OUTPUT_LOAD='(1.0,-1.0)';
      PINUSE='OUT';
    'PE2_TX_DN'<7>:
      PIN_NUMBER='(0,0,0,0,0,0,0,0,0,0,CF3,0,0,0,0,0,0,0,0,0,0,0,0,0,0,0,0,0,0,0~
)';
      OUTPUT_LOAD='(1.0,-1.0)';
      PINUSE='OUT';
    'PE2_TX_DN'<6>:
      PIN_NUMBER='(0,0,0,0,0,0,0,0,0,0,CG2,0,0,0,0,0,0,0,0,0,0,0,0,0,0,0,0,0,0,0~
)';
      OUTPUT_LOAD='(1.0,-1.0)';
      PINUSE='OUT';
    'PE2_TX_DN'<5>:
      PIN_NUMBER='(0,0,0,0,0,0,0,0,0,0,CL2,0,0,0,0,0,0,0,0,0,0,0,0,0,0,0,0,0,0,0~
)';
      OUTPUT_LOAD='(1.0,-1.0)';
      PINUSE='OUT';
    'PE2_TX_DN'<4>:
      PIN_NUMBER='(0,0,0,0,0,0,0,0,0,0,CM1,0,0,0,0,0,0,0,0,0,0,0,0,0,0,0,0,0,0,0~
)';
      OUTPUT_LOAD='(1.0,-1.0)';
      PINUSE='OUT';
    'PE2_TX_DN'<3>:
      PIN_NUMBER='(0,0,0,0,0,0,0,0,0,0,CT3,0,0,0,0,0,0,0,0,0,0,0,0,0,0,0,0,0,0,0~
)';
      OUTPUT_LOAD='(1.0,-1.0)';
      PINUSE='OUT';
    'PE2_TX_DN'<2>:
      PIN_NUMBER='(0,0,0,0,0,0,0,0,0,0,CT1,0,0,0,0,0,0,0,0,0,0,0,0,0,0,0,0,0,0,0~
)';
      OUTPUT_LOAD='(1.0,-1.0)';
      PINUSE='OUT';
    'PE2_TX_DN'<1>:
      PIN_NUMBER='(0,0,0,0,0,0,0,0,0,0,CV3,0,0,0,0,0,0,0,0,0,0,0,0,0,0,0,0,0,0,0~
)';
      OUTPUT_LOAD='(1.0,-1.0)';
      PINUSE='OUT';
    'PE2_TX_DN'<0>:
      PIN_NUMBER='(0,0,0,0,0,0,0,0,0,0,CY3,0,0,0,0,0,0,0,0,0,0,0,0,0,0,0,0,0,0,0~
)';
      OUTPUT_LOAD='(1.0,-1.0)';
      PINUSE='OUT';
    'PE2_TX_DP'<15>:
      PIN_NUMBER='(0,0,0,0,0,0,0,0,0,0,BK5,0,0,0,0,0,0,0,0,0,0,0,0,0,0,0,0,0,0,0~
)';
      OUTPUT_LOAD='(1.0,-1.0)';
      PINUSE='OUT';
    'PE2_TX_DP'<14>:
      PIN_NUMBER='(0,0,0,0,0,0,0,0,0,0,BM3,0,0,0,0,0,0,0,0,0,0,0,0,0,0,0,0,0,0,0~
)';
      OUTPUT_LOAD='(1.0,-1.0)';
      PINUSE='OUT';
    'PE2_TX_DP'<13>:
      PIN_NUMBER='(0,0,0,0,0,0,0,0,0,0,BN4,0,0,0,0,0,0,0,0,0,0,0,0,0,0,0,0,0,0,0~
)';
      OUTPUT_LOAD='(1.0,-1.0)';
      PINUSE='OUT';
    'PE2_TX_DP'<12>:
      PIN_NUMBER='(0,0,0,0,0,0,0,0,0,0,BR4,0,0,0,0,0,0,0,0,0,0,0,0,0,0,0,0,0,0,0~
)';
      OUTPUT_LOAD='(1.0,-1.0)';
      PINUSE='OUT';
    'PE2_TX_DP'<11>:
      PIN_NUMBER='(0,0,0,0,0,0,0,0,0,0,BV3,0,0,0,0,0,0,0,0,0,0,0,0,0,0,0,0,0,0,0~
)';
      OUTPUT_LOAD='(1.0,-1.0)';
      PINUSE='OUT';
    'PE2_TX_DP'<10>:
      PIN_NUMBER='(0,0,0,0,0,0,0,0,0,0,BY5,0,0,0,0,0,0,0,0,0,0,0,0,0,0,0,0,0,0,0~
)';
      OUTPUT_LOAD='(1.0,-1.0)';
      PINUSE='OUT';
    'PE2_TX_DP'<9>:
      PIN_NUMBER='(0,0,0,0,0,0,0,0,0,0,BY3,0,0,0,0,0,0,0,0,0,0,0,0,0,0,0,0,0,0,0~
)';
      OUTPUT_LOAD='(1.0,-1.0)';
      PINUSE='OUT';
    'PE2_TX_DP'<8>:
      PIN_NUMBER='(0,0,0,0,0,0,0,0,0,0,CD3,0,0,0,0,0,0,0,0,0,0,0,0,0,0,0,0,0,0,0~
)';
      OUTPUT_LOAD='(1.0,-1.0)';
      PINUSE='OUT';
    'PE2_TX_DP'<7>:
      PIN_NUMBER='(0,0,0,0,0,0,0,0,0,0,CE4,0,0,0,0,0,0,0,0,0,0,0,0,0,0,0,0,0,0,0~
)';
      OUTPUT_LOAD='(1.0,-1.0)';
      PINUSE='OUT';
    'PE2_TX_DP'<6>:
      PIN_NUMBER='(0,0,0,0,0,0,0,0,0,0,CE2,0,0,0,0,0,0,0,0,0,0,0,0,0,0,0,0,0,0,0~
)';
      OUTPUT_LOAD='(1.0,-1.0)';
      PINUSE='OUT';
    'PE2_TX_DP'<5>:
      PIN_NUMBER='(0,0,0,0,0,0,0,0,0,0,CK3,0,0,0,0,0,0,0,0,0,0,0,0,0,0,0,0,0,0,0~
)';
      OUTPUT_LOAD='(1.0,-1.0)';
      PINUSE='OUT';
    'PE2_TX_DP'<4>:
      PIN_NUMBER='(0,0,0,0,0,0,0,0,0,0,CK1,0,0,0,0,0,0,0,0,0,0,0,0,0,0,0,0,0,0,0~
)';
      OUTPUT_LOAD='(1.0,-1.0)';
      PINUSE='OUT';
    'PE2_TX_DP'<3>:
      PIN_NUMBER='(0,0,0,0,0,0,0,0,0,0,CP3,0,0,0,0,0,0,0,0,0,0,0,0,0,0,0,0,0,0,0~
)';
      OUTPUT_LOAD='(1.0,-1.0)';
      PINUSE='OUT';
    'PE2_TX_DP'<2>:
      PIN_NUMBER='(0,0,0,0,0,0,0,0,0,0,CR2,0,0,0,0,0,0,0,0,0,0,0,0,0,0,0,0,0,0,0~
)';
      OUTPUT_LOAD='(1.0,-1.0)';
      PINUSE='OUT';
    'PE2_TX_DP'<1>:
      PIN_NUMBER='(0,0,0,0,0,0,0,0,0,0,CU2,0,0,0,0,0,0,0,0,0,0,0,0,0,0,0,0,0,0,0~
)';
      OUTPUT_LOAD='(1.0,-1.0)';
      PINUSE='OUT';
    'PE2_TX_DP'<0>:
      PIN_NUMBER='(0,0,0,0,0,0,0,0,0,0,CW4,0,0,0,0,0,0,0,0,0,0,0,0,0,0,0,0,0,0,0~
)';
      OUTPUT_LOAD='(1.0,-1.0)';
      PINUSE='OUT';
    'PE3_RBIAS'<1>:
      PIN_NUMBER='(CR30,0,0,0,0,0,0,0,0,0,0,0,0,0,0,0,0,0,0,0,0,0,0,0,0,0,0,0,0,~
0)';
      INPUT_LOAD='(-0.01,0.01)';
      PINUSE='IN';
    'PE3_RBIAS'<0>:
      PIN_NUMBER='(CP29,0,0,0,0,0,0,0,0,0,0,0,0,0,0,0,0,0,0,0,0,0,0,0,0,0,0,0,0,~
0)';
      INPUT_LOAD='(-0.01,0.01)';
      PINUSE='IN';
    'PE3_RX_DN'<15>:
      PIN_NUMBER='(0,0,0,0,0,0,0,0,0,0,0,CV9,0,0,0,0,0,0,0,0,0,0,0,0,0,0,0,0,0,0~
)';
      INPUT_LOAD='(-0.01,0.01)';
      PINUSE='IN';
    'PE3_RX_DN'<14>:
      PIN_NUMBER='(0,0,0,0,0,0,0,0,0,0,0,CY11,0,0,0,0,0,0,0,0,0,0,0,0,0,0,0,0,0,~
0)';
      INPUT_LOAD='(-0.01,0.01)';
      PINUSE='IN';
    'PE3_RX_DN'<13>:
      PIN_NUMBER='(0,0,0,0,0,0,0,0,0,0,0,DB11,0,0,0,0,0,0,0,0,0,0,0,0,0,0,0,0,0,~
0)';
      INPUT_LOAD='(-0.01,0.01)';
      PINUSE='IN';
    'PE3_RX_DN'<12>:
      PIN_NUMBER='(0,0,0,0,0,0,0,0,0,0,0,DD13,0,0,0,0,0,0,0,0,0,0,0,0,0,0,0,0,0,~
0)';
      INPUT_LOAD='(-0.01,0.01)';
      PINUSE='IN';
    'PE3_RX_DN'<11>:
      PIN_NUMBER='(0,0,0,0,0,0,0,0,0,0,0,DG10,0,0,0,0,0,0,0,0,0,0,0,0,0,0,0,0,0,~
0)';
      INPUT_LOAD='(-0.01,0.01)';
      PINUSE='IN';
    'PE3_RX_DN'<10>:
      PIN_NUMBER='(0,0,0,0,0,0,0,0,0,0,0,DG12,0,0,0,0,0,0,0,0,0,0,0,0,0,0,0,0,0,~
0)';
      INPUT_LOAD='(-0.01,0.01)';
      PINUSE='IN';
    'PE3_RX_DN'<9>:
      PIN_NUMBER='(0,0,0,0,0,0,0,0,0,0,0,DJ12,0,0,0,0,0,0,0,0,0,0,0,0,0,0,0,0,0,~
0)';
      INPUT_LOAD='(-0.01,0.01)';
      PINUSE='IN';
    'PE3_RX_DN'<8>:
      PIN_NUMBER='(0,0,0,0,0,0,0,0,0,0,0,DL12,0,0,0,0,0,0,0,0,0,0,0,0,0,0,0,0,0,~
0)';
      INPUT_LOAD='(-0.01,0.01)';
      PINUSE='IN';
    'PE3_RX_DN'<7>:
      PIN_NUMBER='(0,0,0,0,0,0,0,0,0,0,0,DL14,0,0,0,0,0,0,0,0,0,0,0,0,0,0,0,0,0,~
0)';
      INPUT_LOAD='(-0.01,0.01)';
      PINUSE='IN';
    'PE3_RX_DN'<6>:
      PIN_NUMBER='(0,0,0,0,0,0,0,0,0,0,0,DN14,0,0,0,0,0,0,0,0,0,0,0,0,0,0,0,0,0,~
0)';
      INPUT_LOAD='(-0.01,0.01)';
      PINUSE='IN';
    'PE3_RX_DN'<5>:
      PIN_NUMBER='(0,0,0,0,0,0,0,0,0,0,0,DR14,0,0,0,0,0,0,0,0,0,0,0,0,0,0,0,0,0,~
0)';
      INPUT_LOAD='(-0.01,0.01)';
      PINUSE='IN';
    'PE3_RX_DN'<4>:
      PIN_NUMBER='(0,0,0,0,0,0,0,0,0,0,0,DR16,0,0,0,0,0,0,0,0,0,0,0,0,0,0,0,0,0,~
0)';
      INPUT_LOAD='(-0.01,0.01)';
      PINUSE='IN';
    'PE3_RX_DN'<3>:
      PIN_NUMBER='(0,0,0,0,0,0,0,0,0,0,0,DT19,0,0,0,0,0,0,0,0,0,0,0,0,0,0,0,0,0,~
0)';
      INPUT_LOAD='(-0.01,0.01)';
      PINUSE='IN';
    'PE3_RX_DN'<2>:
      PIN_NUMBER='(0,0,0,0,0,0,0,0,0,0,0,DW16,0,0,0,0,0,0,0,0,0,0,0,0,0,0,0,0,0,~
0)';
      INPUT_LOAD='(-0.01,0.01)';
      PINUSE='IN';
    'PE3_RX_DN'<1>:
      PIN_NUMBER='(0,0,0,0,0,0,0,0,0,0,0,DW18,0,0,0,0,0,0,0,0,0,0,0,0,0,0,0,0,0,~
0)';
      INPUT_LOAD='(-0.01,0.01)';
      PINUSE='IN';
    'PE3_RX_DN'<0>:
      PIN_NUMBER='(0,0,0,0,0,0,0,0,0,0,0,EA18,0,0,0,0,0,0,0,0,0,0,0,0,0,0,0,0,0,~
0)';
      INPUT_LOAD='(-0.01,0.01)';
      PINUSE='IN';
    'PE3_RX_DP'<15>:
      PIN_NUMBER='(0,0,0,0,0,0,0,0,0,0,0,CU10,0,0,0,0,0,0,0,0,0,0,0,0,0,0,0,0,0,~
0)';
      INPUT_LOAD='(-0.01,0.01)';
      PINUSE='IN';
    'PE3_RX_DP'<14>:
      PIN_NUMBER='(0,0,0,0,0,0,0,0,0,0,0,CW10,0,0,0,0,0,0,0,0,0,0,0,0,0,0,0,0,0,~
0)';
      INPUT_LOAD='(-0.01,0.01)';
      PINUSE='IN';
    'PE3_RX_DP'<13>:
      PIN_NUMBER='(0,0,0,0,0,0,0,0,0,0,0,DA12,0,0,0,0,0,0,0,0,0,0,0,0,0,0,0,0,0,~
0)';
      INPUT_LOAD='(-0.01,0.01)';
      PINUSE='IN';
    'PE3_RX_DP'<12>:
      PIN_NUMBER='(0,0,0,0,0,0,0,0,0,0,0,DC12,0,0,0,0,0,0,0,0,0,0,0,0,0,0,0,0,0,~
0)';
      INPUT_LOAD='(-0.01,0.01)';
      PINUSE='IN';
    'PE3_RX_DP'<11>:
      PIN_NUMBER='(0,0,0,0,0,0,0,0,0,0,0,DF11,0,0,0,0,0,0,0,0,0,0,0,0,0,0,0,0,0,~
0)';
      INPUT_LOAD='(-0.01,0.01)';
      PINUSE='IN';
    'PE3_RX_DP'<10>:
      PIN_NUMBER='(0,0,0,0,0,0,0,0,0,0,0,DE12,0,0,0,0,0,0,0,0,0,0,0,0,0,0,0,0,0,~
0)';
      INPUT_LOAD='(-0.01,0.01)';
      PINUSE='IN';
    'PE3_RX_DP'<9>:
      PIN_NUMBER='(0,0,0,0,0,0,0,0,0,0,0,DH11,0,0,0,0,0,0,0,0,0,0,0,0,0,0,0,0,0,~
0)';
      INPUT_LOAD='(-0.01,0.01)';
      PINUSE='IN';
    'PE3_RX_DP'<8>:
      PIN_NUMBER='(0,0,0,0,0,0,0,0,0,0,0,DK13,0,0,0,0,0,0,0,0,0,0,0,0,0,0,0,0,0,~
0)';
      INPUT_LOAD='(-0.01,0.01)';
      PINUSE='IN';
    'PE3_RX_DP'<7>:
      PIN_NUMBER='(0,0,0,0,0,0,0,0,0,0,0,DJ14,0,0,0,0,0,0,0,0,0,0,0,0,0,0,0,0,0,~
0)';
      INPUT_LOAD='(-0.01,0.01)';
      PINUSE='IN';
    'PE3_RX_DP'<6>:
      PIN_NUMBER='(0,0,0,0,0,0,0,0,0,0,0,DM13,0,0,0,0,0,0,0,0,0,0,0,0,0,0,0,0,0,~
0)';
      INPUT_LOAD='(-0.01,0.01)';
      PINUSE='IN';
    'PE3_RX_DP'<5>:
      PIN_NUMBER='(0,0,0,0,0,0,0,0,0,0,0,DP15,0,0,0,0,0,0,0,0,0,0,0,0,0,0,0,0,0,~
0)';
      INPUT_LOAD='(-0.01,0.01)';
      PINUSE='IN';
    'PE3_RX_DP'<4>:
      PIN_NUMBER='(0,0,0,0,0,0,0,0,0,0,0,DN16,0,0,0,0,0,0,0,0,0,0,0,0,0,0,0,0,0,~
0)';
      INPUT_LOAD='(-0.01,0.01)';
      PINUSE='IN';
    'PE3_RX_DP'<3>:
      PIN_NUMBER='(0,0,0,0,0,0,0,0,0,0,0,DR18,0,0,0,0,0,0,0,0,0,0,0,0,0,0,0,0,0,~
0)';
      INPUT_LOAD='(-0.01,0.01)';
      PINUSE='IN';
    'PE3_RX_DP'<2>:
      PIN_NUMBER='(0,0,0,0,0,0,0,0,0,0,0,DV17,0,0,0,0,0,0,0,0,0,0,0,0,0,0,0,0,0,~
0)';
      INPUT_LOAD='(-0.01,0.01)';
      PINUSE='IN';
    'PE3_RX_DP'<1>:
      PIN_NUMBER='(0,0,0,0,0,0,0,0,0,0,0,DU18,0,0,0,0,0,0,0,0,0,0,0,0,0,0,0,0,0,~
0)';
      INPUT_LOAD='(-0.01,0.01)';
      PINUSE='IN';
    'PE3_RX_DP'<0>:
      PIN_NUMBER='(0,0,0,0,0,0,0,0,0,0,0,DY17,0,0,0,0,0,0,0,0,0,0,0,0,0,0,0,0,0,~
0)';
      INPUT_LOAD='(-0.01,0.01)';
      PINUSE='IN';
    'PE3_TX_DN'<15>:
      PIN_NUMBER='(0,0,0,0,0,0,0,0,0,0,0,CY5,0,0,0,0,0,0,0,0,0,0,0,0,0,0,0,0,0,0~
)';
      OUTPUT_LOAD='(1.0,-1.0)';
      PINUSE='OUT';
    'PE3_TX_DN'<14>:
      PIN_NUMBER='(0,0,0,0,0,0,0,0,0,0,0,DB5,0,0,0,0,0,0,0,0,0,0,0,0,0,0,0,0,0,0~
)';
      OUTPUT_LOAD='(1.0,-1.0)';
      PINUSE='OUT';
    'PE3_TX_DN'<13>:
      PIN_NUMBER='(0,0,0,0,0,0,0,0,0,0,0,DD5,0,0,0,0,0,0,0,0,0,0,0,0,0,0,0,0,0,0~
)';
      OUTPUT_LOAD='(1.0,-1.0)';
      PINUSE='OUT';
    'PE3_TX_DN'<12>:
      PIN_NUMBER='(0,0,0,0,0,0,0,0,0,0,0,DJ6,0,0,0,0,0,0,0,0,0,0,0,0,0,0,0,0,0,0~
)';
      OUTPUT_LOAD='(1.0,-1.0)';
      PINUSE='OUT';
    'PE3_TX_DN'<11>:
      PIN_NUMBER='(0,0,0,0,0,0,0,0,0,0,0,DJ4,0,0,0,0,0,0,0,0,0,0,0,0,0,0,0,0,0,0~
)';
      OUTPUT_LOAD='(1.0,-1.0)';
      PINUSE='OUT';
    'PE3_TX_DN'<10>:
      PIN_NUMBER='(0,0,0,0,0,0,0,0,0,0,0,DL6,0,0,0,0,0,0,0,0,0,0,0,0,0,0,0,0,0,0~
)';
      OUTPUT_LOAD='(1.0,-1.0)';
      PINUSE='OUT';
    'PE3_TX_DN'<9>:
      PIN_NUMBER='(0,0,0,0,0,0,0,0,0,0,0,DP5,0,0,0,0,0,0,0,0,0,0,0,0,0,0,0,0,0,0~
)';
      OUTPUT_LOAD='(1.0,-1.0)';
      PINUSE='OUT';
    'PE3_TX_DN'<8>:
      PIN_NUMBER='(0,0,0,0,0,0,0,0,0,0,0,DM7,0,0,0,0,0,0,0,0,0,0,0,0,0,0,0,0,0,0~
)';
      OUTPUT_LOAD='(1.0,-1.0)';
      PINUSE='OUT';
    'PE3_TX_DN'<7>:
      PIN_NUMBER='(0,0,0,0,0,0,0,0,0,0,0,DR8,0,0,0,0,0,0,0,0,0,0,0,0,0,0,0,0,0,0~
)';
      OUTPUT_LOAD='(1.0,-1.0)';
      PINUSE='OUT';
    'PE3_TX_DN'<6>:
      PIN_NUMBER='(0,0,0,0,0,0,0,0,0,0,0,DU8,0,0,0,0,0,0,0,0,0,0,0,0,0,0,0,0,0,0~
)';
      OUTPUT_LOAD='(1.0,-1.0)';
      PINUSE='OUT';
    'PE3_TX_DN'<5>:
      PIN_NUMBER='(0,0,0,0,0,0,0,0,0,0,0,DW10,0,0,0,0,0,0,0,0,0,0,0,0,0,0,0,0,0,~
0)';
      OUTPUT_LOAD='(1.0,-1.0)';
      PINUSE='OUT';
    'PE3_TX_DN'<4>:
      PIN_NUMBER='(0,0,0,0,0,0,0,0,0,0,0,EB9,0,0,0,0,0,0,0,0,0,0,0,0,0,0,0,0,0,0~
)';
      OUTPUT_LOAD='(1.0,-1.0)';
      PINUSE='OUT';
    'PE3_TX_DN'<3>:
      PIN_NUMBER='(0,0,0,0,0,0,0,0,0,0,0,DY11,0,0,0,0,0,0,0,0,0,0,0,0,0,0,0,0,0,~
0)';
      OUTPUT_LOAD='(1.0,-1.0)';
      PINUSE='OUT';
    'PE3_TX_DN'<2>:
      PIN_NUMBER='(0,0,0,0,0,0,0,0,0,0,0,EC12,0,0,0,0,0,0,0,0,0,0,0,0,0,0,0,0,0,~
0)';
      OUTPUT_LOAD='(1.0,-1.0)';
      PINUSE='OUT';
    'PE3_TX_DN'<1>:
      PIN_NUMBER='(0,0,0,0,0,0,0,0,0,0,0,EE12,0,0,0,0,0,0,0,0,0,0,0,0,0,0,0,0,0,~
0)';
      OUTPUT_LOAD='(1.0,-1.0)';
      PINUSE='OUT';
    'PE3_TX_DN'<0>:
      PIN_NUMBER='(0,0,0,0,0,0,0,0,0,0,0,EE14,0,0,0,0,0,0,0,0,0,0,0,0,0,0,0,0,0,~
0)';
      OUTPUT_LOAD='(1.0,-1.0)';
      PINUSE='OUT';
    'PE3_TX_DP'<15>:
      PIN_NUMBER='(0,0,0,0,0,0,0,0,0,0,0,CV5,0,0,0,0,0,0,0,0,0,0,0,0,0,0,0,0,0,0~
)';
      OUTPUT_LOAD='(1.0,-1.0)';
      PINUSE='OUT';
    'PE3_TX_DP'<14>:
      PIN_NUMBER='(0,0,0,0,0,0,0,0,0,0,0,DA4,0,0,0,0,0,0,0,0,0,0,0,0,0,0,0,0,0,0~
)';
      OUTPUT_LOAD='(1.0,-1.0)';
      PINUSE='OUT';
    'PE3_TX_DP'<13>:
      PIN_NUMBER='(0,0,0,0,0,0,0,0,0,0,0,DC6,0,0,0,0,0,0,0,0,0,0,0,0,0,0,0,0,0,0~
)';
      OUTPUT_LOAD='(1.0,-1.0)';
      PINUSE='OUT';
    'PE3_TX_DP'<12>:
      PIN_NUMBER='(0,0,0,0,0,0,0,0,0,0,0,DG6,0,0,0,0,0,0,0,0,0,0,0,0,0,0,0,0,0,0~
)';
      OUTPUT_LOAD='(1.0,-1.0)';
      PINUSE='OUT';
    'PE3_TX_DP'<11>:
      PIN_NUMBER='(0,0,0,0,0,0,0,0,0,0,0,DH5,0,0,0,0,0,0,0,0,0,0,0,0,0,0,0,0,0,0~
)';
      OUTPUT_LOAD='(1.0,-1.0)';
      PINUSE='OUT';
    'PE3_TX_DP'<10>:
      PIN_NUMBER='(0,0,0,0,0,0,0,0,0,0,0,DK5,0,0,0,0,0,0,0,0,0,0,0,0,0,0,0,0,0,0~
)';
      OUTPUT_LOAD='(1.0,-1.0)';
      PINUSE='OUT';
    'PE3_TX_DP'<9>:
      PIN_NUMBER='(0,0,0,0,0,0,0,0,0,0,0,DM5,0,0,0,0,0,0,0,0,0,0,0,0,0,0,0,0,0,0~
)';
      OUTPUT_LOAD='(1.0,-1.0)';
      PINUSE='OUT';
    'PE3_TX_DP'<8>:
      PIN_NUMBER='(0,0,0,0,0,0,0,0,0,0,0,DN6,0,0,0,0,0,0,0,0,0,0,0,0,0,0,0,0,0,0~
)';
      OUTPUT_LOAD='(1.0,-1.0)';
      PINUSE='OUT';
    'PE3_TX_DP'<7>:
      PIN_NUMBER='(0,0,0,0,0,0,0,0,0,0,0,DP7,0,0,0,0,0,0,0,0,0,0,0,0,0,0,0,0,0,0~
)';
      OUTPUT_LOAD='(1.0,-1.0)';
      PINUSE='OUT';
    'PE3_TX_DP'<6>:
      PIN_NUMBER='(0,0,0,0,0,0,0,0,0,0,0,DT9,0,0,0,0,0,0,0,0,0,0,0,0,0,0,0,0,0,0~
)';
      OUTPUT_LOAD='(1.0,-1.0)';
      PINUSE='OUT';
    'PE3_TX_DP'<5>:
      PIN_NUMBER='(0,0,0,0,0,0,0,0,0,0,0,DV9,0,0,0,0,0,0,0,0,0,0,0,0,0,0,0,0,0,0~
)';
      OUTPUT_LOAD='(1.0,-1.0)';
      PINUSE='OUT';
    'PE3_TX_DP'<4>:
      PIN_NUMBER='(0,0,0,0,0,0,0,0,0,0,0,DY9,0,0,0,0,0,0,0,0,0,0,0,0,0,0,0,0,0,0~
)';
      OUTPUT_LOAD='(1.0,-1.0)';
      PINUSE='OUT';
    'PE3_TX_DP'<3>:
      PIN_NUMBER='(0,0,0,0,0,0,0,0,0,0,0,EA10,0,0,0,0,0,0,0,0,0,0,0,0,0,0,0,0,0,~
0)';
      OUTPUT_LOAD='(1.0,-1.0)';
      PINUSE='OUT';
    'PE3_TX_DP'<2>:
      PIN_NUMBER='(0,0,0,0,0,0,0,0,0,0,0,EB11,0,0,0,0,0,0,0,0,0,0,0,0,0,0,0,0,0,~
0)';
      OUTPUT_LOAD='(1.0,-1.0)';
      PINUSE='OUT';
    'PE3_TX_DP'<1>:
      PIN_NUMBER='(0,0,0,0,0,0,0,0,0,0,0,ED13,0,0,0,0,0,0,0,0,0,0,0,0,0,0,0,0,0,~
0)';
      OUTPUT_LOAD='(1.0,-1.0)';
      PINUSE='OUT';
    'PE3_TX_DP'<0>:
      PIN_NUMBER='(0,0,0,0,0,0,0,0,0,0,0,EC14,0,0,0,0,0,0,0,0,0,0,0,0,0,0,0,0,0,~
0)';
      OUTPUT_LOAD='(1.0,-1.0)';
      PINUSE='OUT';
    'PECI':
      PIN_NUMBER='(AU12,0,0,0,0,0,0,0,0,0,0,0,0,0,0,0,0,0,0,0,0,0,0,0,0,0,0,0,0,~
0)';
      BIDIRECTIONAL='TRUE';
      INPUT_LOAD='(-0.01,0.01)';
      OUTPUT_LOAD='(1.0,-1.0)';
      PINUSE='BI';
    'PE_HP_SCL':
      PIN_NUMBER='(AM19,0,0,0,0,0,0,0,0,0,0,0,0,0,0,0,0,0,0,0,0,0,0,0,0,0,0,0,0,~
0)';
      BIDIRECTIONAL='TRUE';
      INPUT_LOAD='(-0.01,0.01)';
      OUTPUT_LOAD='(1.0,-1.0)';
      PINUSE='BI';
    'PE_HP_SDA':
      PIN_NUMBER='(AL18,0,0,0,0,0,0,0,0,0,0,0,0,0,0,0,0,0,0,0,0,0,0,0,0,0,0,0,0,~
0)';
      BIDIRECTIONAL='TRUE';
      INPUT_LOAD='(-0.01,0.01)';
      OUTPUT_LOAD='(1.0,-1.0)';
      PINUSE='BI';
    'PIROM_ADDR'<2>:
      PIN_NUMBER='(CW56,0,0,0,0,0,0,0,0,0,0,0,0,0,0,0,0,0,0,0,0,0,0,0,0,0,0,0,0,~
0)';
      BIDIRECTIONAL='TRUE';
      INPUT_LOAD='(-0.01,0.01)';
      OUTPUT_LOAD='(1.0,-1.0)';
      PINUSE='BI';
    'PIROM_ADDR'<1>:
      PIN_NUMBER='(CV57,0,0,0,0,0,0,0,0,0,0,0,0,0,0,0,0,0,0,0,0,0,0,0,0,0,0,0,0,~
0)';
      BIDIRECTIONAL='TRUE';
      INPUT_LOAD='(-0.01,0.01)';
      OUTPUT_LOAD='(1.0,-1.0)';
      PINUSE='BI';
    'PIROM_ADDR'<0>:
      PIN_NUMBER='(CU58,0,0,0,0,0,0,0,0,0,0,0,0,0,0,0,0,0,0,0,0,0,0,0,0,0,0,0,0,~
0)';
      BIDIRECTIONAL='TRUE';
      INPUT_LOAD='(-0.01,0.01)';
      OUTPUT_LOAD='(1.0,-1.0)';
      PINUSE='BI';
    'PKGID'<2>:
      PIN_NUMBER='(DA72,0,0,0,0,0,0,0,0,0,0,0,0,0,0,0,0,0,0,0,0,0,0,0,0,0,0,0,0,~
0)';
      BIDIRECTIONAL='TRUE';
      INPUT_LOAD='(-0.01,0.01)';
      OUTPUT_LOAD='(1.0,-1.0)';
      PINUSE='BI';
    'PKGID'<1>:
      PIN_NUMBER='(CW72,0,0,0,0,0,0,0,0,0,0,0,0,0,0,0,0,0,0,0,0,0,0,0,0,0,0,0,0,~
0)';
      BIDIRECTIONAL='TRUE';
      INPUT_LOAD='(-0.01,0.01)';
      OUTPUT_LOAD='(1.0,-1.0)';
      PINUSE='BI';
    'PKGID'<0>:
      PIN_NUMBER='(DC72,0,0,0,0,0,0,0,0,0,0,0,0,0,0,0,0,0,0,0,0,0,0,0,0,0,0,0,0,~
0)';
      BIDIRECTIONAL='TRUE';
      INPUT_LOAD='(-0.01,0.01)';
      OUTPUT_LOAD='(1.0,-1.0)';
      PINUSE='BI';
    'PMSYNC':
      PIN_NUMBER='(AR14,0,0,0,0,0,0,0,0,0,0,0,0,0,0,0,0,0,0,0,0,0,0,0,0,0,0,0,0,~
0)';
      INPUT_LOAD='(-0.01,0.01)';
      PINUSE='IN';
    'PMSYNC_CLK':
      PIN_NUMBER='(AT19,0,0,0,0,0,0,0,0,0,0,0,0,0,0,0,0,0,0,0,0,0,0,0,0,0,0,0,0,~
0)';
      INPUT_LOAD='(-0.01,0.01)';
      PINUSE='IN';
    'PM_FAST_WAKE_N':
      PIN_NUMBER='(AF15,0,0,0,0,0,0,0,0,0,0,0,0,0,0,0,0,0,0,0,0,0,0,0,0,0,0,0,0,~
0)';
      BIDIRECTIONAL='TRUE';
      INPUT_LOAD='(-0.01,0.01)';
      OUTPUT_LOAD='(1.0,-1.0)';
      PINUSE='BI';
    'PRDY_N':
      PIN_NUMBER='(AG16,0,0,0,0,0,0,0,0,0,0,0,0,0,0,0,0,0,0,0,0,0,0,0,0,0,0,0,0,~
0)';
      OUTPUT_LOAD='(1.0,-1.0)';
      PINUSE='OUT';
    'PREQ_N':
      PIN_NUMBER='(AR12,0,0,0,0,0,0,0,0,0,0,0,0,0,0,0,0,0,0,0,0,0,0,0,0,0,0,0,0,~
0)';
      INPUT_LOAD='(-0.01,0.01)';
      PINUSE='IN';
    'PROCDIS_N':
      PIN_NUMBER='(AB17,0,0,0,0,0,0,0,0,0,0,0,0,0,0,0,0,0,0,0,0,0,0,0,0,0,0,0,0,~
0)';
      INPUT_LOAD='(-0.01,0.01)';
      PINUSE='IN';
    'PROCHOT_N':
      PIN_NUMBER='(AC16,0,0,0,0,0,0,0,0,0,0,0,0,0,0,0,0,0,0,0,0,0,0,0,0,0,0,0,0,~
0)';
      BIDIRECTIONAL='TRUE';
      INPUT_LOAD='(-0.01,0.01)';
      OUTPUT_LOAD='(1.0,-1.0)';
      PINUSE='BI';
    'PROC_ID'<1>:
      PIN_NUMBER='(DB71,0,0,0,0,0,0,0,0,0,0,0,0,0,0,0,0,0,0,0,0,0,0,0,0,0,0,0,0,~
0)';
      OUTPUT_LOAD='(1.0,-1.0)';
      PINUSE='OUT';
    'PROC_ID'<0>:
      PIN_NUMBER='(CY71,0,0,0,0,0,0,0,0,0,0,0,0,0,0,0,0,0,0,0,0,0,0,0,0,0,0,0,0,~
0)';
      OUTPUT_LOAD='(1.0,-1.0)';
      PINUSE='OUT';
    'PWRGOOD':
      PIN_NUMBER='(BC24,0,0,0,0,0,0,0,0,0,0,0,0,0,0,0,0,0,0,0,0,0,0,0,0,0,0,0,0,~
0)';
      INPUT_LOAD='(-0.01,0.01)';
      PINUSE='IN';
    'PWR_DEBUG_N':
      PIN_NUMBER='(0,AP17,0,0,0,0,0,0,0,0,0,0,0,0,0,0,0,0,0,0,0,0,0,0,0,0,0,0,0,~
0)';
      INPUT_LOAD='(-0.01,0.01)';
      PINUSE='IN';
    'RESET_N':
      PIN_NUMBER='(AP21,0,0,0,0,0,0,0,0,0,0,0,0,0,0,0,0,0,0,0,0,0,0,0,0,0,0,0,0,~
0)';
      INPUT_LOAD='(-0.01,0.01)';
      PINUSE='IN';
    'RSVD'<304>:
      PIN_NUMBER='(0,A4,0,0,0,0,0,0,0,0,0,0,0,0,0,0,0,0,0,0,0,0,0,0,0,0,0,0,0,0)~
';
      BIDIRECTIONAL='TRUE';
      INPUT_LOAD='(-0.01,0.01)';
      OUTPUT_LOAD='(1.0,-1.0)';
      PINUSE='BI';
    'RSVD'<303>:
      PIN_NUMBER='(0,A6,0,0,0,0,0,0,0,0,0,0,0,0,0,0,0,0,0,0,0,0,0,0,0,0,0,0,0,0)~
';
      BIDIRECTIONAL='TRUE';
      INPUT_LOAD='(-0.01,0.01)';
      OUTPUT_LOAD='(1.0,-1.0)';
      PINUSE='BI';
    'RSVD'<302>:
      PIN_NUMBER='(0,A14,0,0,0,0,0,0,0,0,0,0,0,0,0,0,0,0,0,0,0,0,0,0,0,0,0,0,0,0~
)';
      BIDIRECTIONAL='TRUE';
      INPUT_LOAD='(-0.01,0.01)';
      OUTPUT_LOAD='(1.0,-1.0)';
      PINUSE='BI';
    'RSVD'<301>:
      PIN_NUMBER='(0,A16,0,0,0,0,0,0,0,0,0,0,0,0,0,0,0,0,0,0,0,0,0,0,0,0,0,0,0,0~
)';
      BIDIRECTIONAL='TRUE';
      INPUT_LOAD='(-0.01,0.01)';
      OUTPUT_LOAD='(1.0,-1.0)';
      PINUSE='BI';
    'RSVD'<300>:
      PIN_NUMBER='(0,A24,0,0,0,0,0,0,0,0,0,0,0,0,0,0,0,0,0,0,0,0,0,0,0,0,0,0,0,0~
)';
      BIDIRECTIONAL='TRUE';
      INPUT_LOAD='(-0.01,0.01)';
      OUTPUT_LOAD='(1.0,-1.0)';
      PINUSE='BI';
    'RSVD'<299>:
      PIN_NUMBER='(0,B3,0,0,0,0,0,0,0,0,0,0,0,0,0,0,0,0,0,0,0,0,0,0,0,0,0,0,0,0)~
';
      BIDIRECTIONAL='TRUE';
      INPUT_LOAD='(-0.01,0.01)';
      OUTPUT_LOAD='(1.0,-1.0)';
      PINUSE='BI';
    'RSVD'<298>:
      PIN_NUMBER='(0,B7,0,0,0,0,0,0,0,0,0,0,0,0,0,0,0,0,0,0,0,0,0,0,0,0,0,0,0,0)~
';
      BIDIRECTIONAL='TRUE';
      INPUT_LOAD='(-0.01,0.01)';
      OUTPUT_LOAD='(1.0,-1.0)';
      PINUSE='BI';
    'RSVD'<296>:
      PIN_NUMBER='(0,B13,0,0,0,0,0,0,0,0,0,0,0,0,0,0,0,0,0,0,0,0,0,0,0,0,0,0,0,0~
)';
      BIDIRECTIONAL='TRUE';
      INPUT_LOAD='(-0.01,0.01)';
      OUTPUT_LOAD='(1.0,-1.0)';
      PINUSE='BI';
    'RSVD'<295>:
      PIN_NUMBER='(0,B15,0,0,0,0,0,0,0,0,0,0,0,0,0,0,0,0,0,0,0,0,0,0,0,0,0,0,0,0~
)';
      BIDIRECTIONAL='TRUE';
      INPUT_LOAD='(-0.01,0.01)';
      OUTPUT_LOAD='(1.0,-1.0)';
      PINUSE='BI';
    'RSVD'<294>:
      PIN_NUMBER='(0,B17,0,0,0,0,0,0,0,0,0,0,0,0,0,0,0,0,0,0,0,0,0,0,0,0,0,0,0,0~
)';
      BIDIRECTIONAL='TRUE';
      INPUT_LOAD='(-0.01,0.01)';
      OUTPUT_LOAD='(1.0,-1.0)';
      PINUSE='BI';
    'RSVD'<293>:
      PIN_NUMBER='(0,B77,0,0,0,0,0,0,0,0,0,0,0,0,0,0,0,0,0,0,0,0,0,0,0,0,0,0,0,0~
)';
      BIDIRECTIONAL='TRUE';
      INPUT_LOAD='(-0.01,0.01)';
      OUTPUT_LOAD='(1.0,-1.0)';
      PINUSE='BI';
    'RSVD'<292>:
      PIN_NUMBER='(0,B81,0,0,0,0,0,0,0,0,0,0,0,0,0,0,0,0,0,0,0,0,0,0,0,0,0,0,0,0~
)';
      BIDIRECTIONAL='TRUE';
      INPUT_LOAD='(-0.01,0.01)';
      OUTPUT_LOAD='(1.0,-1.0)';
      PINUSE='BI';
    'RSVD'<291>:
      PIN_NUMBER='(0,C6,0,0,0,0,0,0,0,0,0,0,0,0,0,0,0,0,0,0,0,0,0,0,0,0,0,0,0,0)~
';
      BIDIRECTIONAL='TRUE';
      INPUT_LOAD='(-0.01,0.01)';
      OUTPUT_LOAD='(1.0,-1.0)';
      PINUSE='BI';
    'RSVD'<290>:
      PIN_NUMBER='(0,C18,0,0,0,0,0,0,0,0,0,0,0,0,0,0,0,0,0,0,0,0,0,0,0,0,0,0,0,0~
)';
      BIDIRECTIONAL='TRUE';
      INPUT_LOAD='(-0.01,0.01)';
      OUTPUT_LOAD='(1.0,-1.0)';
      PINUSE='BI';
    'RSVD'<289>:
      PIN_NUMBER='(0,C24,0,0,0,0,0,0,0,0,0,0,0,0,0,0,0,0,0,0,0,0,0,0,0,0,0,0,0,0~
)';
      BIDIRECTIONAL='TRUE';
      INPUT_LOAD='(-0.01,0.01)';
      OUTPUT_LOAD='(1.0,-1.0)';
      PINUSE='BI';
    'RSVD'<288>:
      PIN_NUMBER='(0,C82,0,0,0,0,0,0,0,0,0,0,0,0,0,0,0,0,0,0,0,0,0,0,0,0,0,0,0,0~
)';
      BIDIRECTIONAL='TRUE';
      INPUT_LOAD='(-0.01,0.01)';
      OUTPUT_LOAD='(1.0,-1.0)';
      PINUSE='BI';
    'RSVD'<287>:
      PIN_NUMBER='(0,D5,0,0,0,0,0,0,0,0,0,0,0,0,0,0,0,0,0,0,0,0,0,0,0,0,0,0,0,0)~
';
      BIDIRECTIONAL='TRUE';
      INPUT_LOAD='(-0.01,0.01)';
      OUTPUT_LOAD='(1.0,-1.0)';
      PINUSE='BI';
    'RSVD'<286>:
      PIN_NUMBER='(0,D17,0,0,0,0,0,0,0,0,0,0,0,0,0,0,0,0,0,0,0,0,0,0,0,0,0,0,0,0~
)';
      BIDIRECTIONAL='TRUE';
      INPUT_LOAD='(-0.01,0.01)';
      OUTPUT_LOAD='(1.0,-1.0)';
      PINUSE='BI';
    'RSVD'<285>:
      PIN_NUMBER='(0,D65,0,0,0,0,0,0,0,0,0,0,0,0,0,0,0,0,0,0,0,0,0,0,0,0,0,0,0,0~
)';
      BIDIRECTIONAL='TRUE';
      INPUT_LOAD='(-0.01,0.01)';
      OUTPUT_LOAD='(1.0,-1.0)';
      PINUSE='BI';
    'RSVD'<284>:
      PIN_NUMBER='(0,D83,0,0,0,0,0,0,0,0,0,0,0,0,0,0,0,0,0,0,0,0,0,0,0,0,0,0,0,0~
)';
      BIDIRECTIONAL='TRUE';
      INPUT_LOAD='(-0.01,0.01)';
      OUTPUT_LOAD='(1.0,-1.0)';
      PINUSE='BI';
    'RSVD'<283>:
      PIN_NUMBER='(0,E2,0,0,0,0,0,0,0,0,0,0,0,0,0,0,0,0,0,0,0,0,0,0,0,0,0,0,0,0)~
';
      BIDIRECTIONAL='TRUE';
      INPUT_LOAD='(-0.01,0.01)';
      OUTPUT_LOAD='(1.0,-1.0)';
      PINUSE='BI';
    'RSVD'<282>:
      PIN_NUMBER='(0,E4,0,0,0,0,0,0,0,0,0,0,0,0,0,0,0,0,0,0,0,0,0,0,0,0,0,0,0,0)~
';
      BIDIRECTIONAL='TRUE';
      INPUT_LOAD='(-0.01,0.01)';
      OUTPUT_LOAD='(1.0,-1.0)';
      PINUSE='BI';
    'RSVD'<281>:
      PIN_NUMBER='(0,E24,0,0,0,0,0,0,0,0,0,0,0,0,0,0,0,0,0,0,0,0,0,0,0,0,0,0,0,0~
)';
      BIDIRECTIONAL='TRUE';
      INPUT_LOAD='(-0.01,0.01)';
      OUTPUT_LOAD='(1.0,-1.0)';
      PINUSE='BI';
    'RSVD'<280>:
      PIN_NUMBER='(0,E84,0,0,0,0,0,0,0,0,0,0,0,0,0,0,0,0,0,0,0,0,0,0,0,0,0,0,0,0~
)';
      BIDIRECTIONAL='TRUE';
      INPUT_LOAD='(-0.01,0.01)';
      OUTPUT_LOAD='(1.0,-1.0)';
      PINUSE='BI';
    'RSVD'<279>:
      PIN_NUMBER='(0,F3,0,0,0,0,0,0,0,0,0,0,0,0,0,0,0,0,0,0,0,0,0,0,0,0,0,0,0,0)~
';
      BIDIRECTIONAL='TRUE';
      INPUT_LOAD='(-0.01,0.01)';
      OUTPUT_LOAD='(1.0,-1.0)';
      PINUSE='BI';
    'RSVD'<278>:
      PIN_NUMBER='(0,F23,0,0,0,0,0,0,0,0,0,0,0,0,0,0,0,0,0,0,0,0,0,0,0,0,0,0,0,0~
)';
      BIDIRECTIONAL='TRUE';
      INPUT_LOAD='(-0.01,0.01)';
      OUTPUT_LOAD='(1.0,-1.0)';
      PINUSE='BI';
    'RSVD'<277>:
      PIN_NUMBER='(0,F65,0,0,0,0,0,0,0,0,0,0,0,0,0,0,0,0,0,0,0,0,0,0,0,0,0,0,0,0~
)';
      BIDIRECTIONAL='TRUE';
      INPUT_LOAD='(-0.01,0.01)';
      OUTPUT_LOAD='(1.0,-1.0)';
      PINUSE='BI';
    'RSVD'<276>:
      PIN_NUMBER='(0,F83,0,0,0,0,0,0,0,0,0,0,0,0,0,0,0,0,0,0,0,0,0,0,0,0,0,0,0,0~
)';
      BIDIRECTIONAL='TRUE';
      INPUT_LOAD='(-0.01,0.01)';
      OUTPUT_LOAD='(1.0,-1.0)';
      PINUSE='BI';
    'RSVD'<275>:
      PIN_NUMBER='(0,G2,0,0,0,0,0,0,0,0,0,0,0,0,0,0,0,0,0,0,0,0,0,0,0,0,0,0,0,0)~
';
      BIDIRECTIONAL='TRUE';
      INPUT_LOAD='(-0.01,0.01)';
      OUTPUT_LOAD='(1.0,-1.0)';
      PINUSE='BI';
    'RSVD'<274>:
      PIN_NUMBER='(0,G64,0,0,0,0,0,0,0,0,0,0,0,0,0,0,0,0,0,0,0,0,0,0,0,0,0,0,0,0~
)';
      BIDIRECTIONAL='TRUE';
      INPUT_LOAD='(-0.01,0.01)';
      OUTPUT_LOAD='(1.0,-1.0)';
      PINUSE='BI';
    'RSVD'<273>:
      PIN_NUMBER='(0,G84,0,0,0,0,0,0,0,0,0,0,0,0,0,0,0,0,0,0,0,0,0,0,0,0,0,0,0,0~
)';
      BIDIRECTIONAL='TRUE';
      INPUT_LOAD='(-0.01,0.01)';
      OUTPUT_LOAD='(1.0,-1.0)';
      PINUSE='BI';
    'RSVD'<272>:
      PIN_NUMBER='(0,H1,0,0,0,0,0,0,0,0,0,0,0,0,0,0,0,0,0,0,0,0,0,0,0,0,0,0,0,0)~
';
      BIDIRECTIONAL='TRUE';
      INPUT_LOAD='(-0.01,0.01)';
      OUTPUT_LOAD='(1.0,-1.0)';
      PINUSE='BI';
    'RSVD'<271>:
      PIN_NUMBER='(0,H83,0,0,0,0,0,0,0,0,0,0,0,0,0,0,0,0,0,0,0,0,0,0,0,0,0,0,0,0~
)';
      BIDIRECTIONAL='TRUE';
      INPUT_LOAD='(-0.01,0.01)';
      OUTPUT_LOAD='(1.0,-1.0)';
      PINUSE='BI';
    'RSVD'<270>:
      PIN_NUMBER='(0,H85,0,0,0,0,0,0,0,0,0,0,0,0,0,0,0,0,0,0,0,0,0,0,0,0,0,0,0,0~
)';
      BIDIRECTIONAL='TRUE';
      INPUT_LOAD='(-0.01,0.01)';
      OUTPUT_LOAD='(1.0,-1.0)';
      PINUSE='BI';
    'RSVD'<269>:
      PIN_NUMBER='(0,J46,0,0,0,0,0,0,0,0,0,0,0,0,0,0,0,0,0,0,0,0,0,0,0,0,0,0,0,0~
)';
      BIDIRECTIONAL='TRUE';
      INPUT_LOAD='(-0.01,0.01)';
      OUTPUT_LOAD='(1.0,-1.0)';
      PINUSE='BI';
    'RSVD'<268>:
      PIN_NUMBER='(0,J62,0,0,0,0,0,0,0,0,0,0,0,0,0,0,0,0,0,0,0,0,0,0,0,0,0,0,0,0~
)';
      BIDIRECTIONAL='TRUE';
      INPUT_LOAD='(-0.01,0.01)';
      OUTPUT_LOAD='(1.0,-1.0)';
      PINUSE='BI';
    'RSVD'<267>:
      PIN_NUMBER='(0,K61,0,0,0,0,0,0,0,0,0,0,0,0,0,0,0,0,0,0,0,0,0,0,0,0,0,0,0,0~
)';
      BIDIRECTIONAL='TRUE';
      INPUT_LOAD='(-0.01,0.01)';
      OUTPUT_LOAD='(1.0,-1.0)';
      PINUSE='BI';
    'RSVD'<266>:
      PIN_NUMBER='(0,M63,0,0,0,0,0,0,0,0,0,0,0,0,0,0,0,0,0,0,0,0,0,0,0,0,0,0,0,0~
)';
      BIDIRECTIONAL='TRUE';
      INPUT_LOAD='(-0.01,0.01)';
      OUTPUT_LOAD='(1.0,-1.0)';
      PINUSE='BI';
    'RSVD'<265>:
      PIN_NUMBER='(0,P65,0,0,0,0,0,0,0,0,0,0,0,0,0,0,0,0,0,0,0,0,0,0,0,0,0,0,0,0~
)';
      BIDIRECTIONAL='TRUE';
      INPUT_LOAD='(-0.01,0.01)';
      OUTPUT_LOAD='(1.0,-1.0)';
      PINUSE='BI';
    'RSVD'<264>:
      PIN_NUMBER='(0,R62,0,0,0,0,0,0,0,0,0,0,0,0,0,0,0,0,0,0,0,0,0,0,0,0,0,0,0,0~
)';
      BIDIRECTIONAL='TRUE';
      INPUT_LOAD='(-0.01,0.01)';
      OUTPUT_LOAD='(1.0,-1.0)';
      PINUSE='BI';
    'RSVD'<263>:
      PIN_NUMBER='(0,R66,0,0,0,0,0,0,0,0,0,0,0,0,0,0,0,0,0,0,0,0,0,0,0,0,0,0,0,0~
)';
      BIDIRECTIONAL='TRUE';
      INPUT_LOAD='(-0.01,0.01)';
      OUTPUT_LOAD='(1.0,-1.0)';
      PINUSE='BI';
    'RSVD'<262>:
      PIN_NUMBER='(0,T67,0,0,0,0,0,0,0,0,0,0,0,0,0,0,0,0,0,0,0,0,0,0,0,0,0,0,0,0~
)';
      BIDIRECTIONAL='TRUE';
      INPUT_LOAD='(-0.01,0.01)';
      OUTPUT_LOAD='(1.0,-1.0)';
      PINUSE='BI';
    'RSVD'<261>:
      PIN_NUMBER='(0,U66,0,0,0,0,0,0,0,0,0,0,0,0,0,0,0,0,0,0,0,0,0,0,0,0,0,0,0,0~
)';
      BIDIRECTIONAL='TRUE';
      INPUT_LOAD='(-0.01,0.01)';
      OUTPUT_LOAD='(1.0,-1.0)';
      PINUSE='BI';
    'RSVD'<260>:
      PIN_NUMBER='(0,V65,0,0,0,0,0,0,0,0,0,0,0,0,0,0,0,0,0,0,0,0,0,0,0,0,0,0,0,0~
)';
      BIDIRECTIONAL='TRUE';
      INPUT_LOAD='(-0.01,0.01)';
      OUTPUT_LOAD='(1.0,-1.0)';
      PINUSE='BI';
    'RSVD'<259>:
      PIN_NUMBER='(0,V67,0,0,0,0,0,0,0,0,0,0,0,0,0,0,0,0,0,0,0,0,0,0,0,0,0,0,0,0~
)';
      BIDIRECTIONAL='TRUE';
      INPUT_LOAD='(-0.01,0.01)';
      OUTPUT_LOAD='(1.0,-1.0)';
      PINUSE='BI';
    'RSVD'<258>:
      PIN_NUMBER='(0,W66,0,0,0,0,0,0,0,0,0,0,0,0,0,0,0,0,0,0,0,0,0,0,0,0,0,0,0,0~
)';
      BIDIRECTIONAL='TRUE';
      INPUT_LOAD='(-0.01,0.01)';
      OUTPUT_LOAD='(1.0,-1.0)';
      PINUSE='BI';
    'RSVD'<257>:
      PIN_NUMBER='(0,Y23,0,0,0,0,0,0,0,0,0,0,0,0,0,0,0,0,0,0,0,0,0,0,0,0,0,0,0,0~
)';
      BIDIRECTIONAL='TRUE';
      INPUT_LOAD='(-0.01,0.01)';
      OUTPUT_LOAD='(1.0,-1.0)';
      PINUSE='BI';
    'RSVD'<256>:
      PIN_NUMBER='(0,Y65,0,0,0,0,0,0,0,0,0,0,0,0,0,0,0,0,0,0,0,0,0,0,0,0,0,0,0,0~
)';
      BIDIRECTIONAL='TRUE';
      INPUT_LOAD='(-0.01,0.01)';
      OUTPUT_LOAD='(1.0,-1.0)';
      PINUSE='BI';
    'RSVD'<255>:
      PIN_NUMBER='(0,0,0,0,0,0,0,0,0,0,0,0,0,0,0,AY83,0,0,0,0,0,0,0,0,0,0,0,0,0,~
0)';
      BIDIRECTIONAL='TRUE';
      INPUT_LOAD='(-0.01,0.01)';
      OUTPUT_LOAD='(1.0,-1.0)';
      PINUSE='BI';
    'RSVD'<254>:
      PIN_NUMBER='(0,AD47,0,0,0,0,0,0,0,0,0,0,0,0,0,0,0,0,0,0,0,0,0,0,0,0,0,0,0,~
0)';
      BIDIRECTIONAL='TRUE';
      INPUT_LOAD='(-0.01,0.01)';
      OUTPUT_LOAD='(1.0,-1.0)';
      PINUSE='BI';
    'RSVD'<253>:
      PIN_NUMBER='(0,AD49,0,0,0,0,0,0,0,0,0,0,0,0,0,0,0,0,0,0,0,0,0,0,0,0,0,0,0,~
0)';
      BIDIRECTIONAL='TRUE';
      INPUT_LOAD='(-0.01,0.01)';
      OUTPUT_LOAD='(1.0,-1.0)';
      PINUSE='BI';
    'RSVD'<252>:
      PIN_NUMBER='(0,AD51,0,0,0,0,0,0,0,0,0,0,0,0,0,0,0,0,0,0,0,0,0,0,0,0,0,0,0,~
0)';
      BIDIRECTIONAL='TRUE';
      INPUT_LOAD='(-0.01,0.01)';
      OUTPUT_LOAD='(1.0,-1.0)';
      PINUSE='BI';
    'RSVD'<251>:
      PIN_NUMBER='(0,AE46,0,0,0,0,0,0,0,0,0,0,0,0,0,0,0,0,0,0,0,0,0,0,0,0,0,0,0,~
0)';
      BIDIRECTIONAL='TRUE';
      INPUT_LOAD='(-0.01,0.01)';
      OUTPUT_LOAD='(1.0,-1.0)';
      PINUSE='BI';
    'RSVD'<250>:
      PIN_NUMBER='(0,AE48,0,0,0,0,0,0,0,0,0,0,0,0,0,0,0,0,0,0,0,0,0,0,0,0,0,0,0,~
0)';
      BIDIRECTIONAL='TRUE';
      INPUT_LOAD='(-0.01,0.01)';
      OUTPUT_LOAD='(1.0,-1.0)';
      PINUSE='BI';
    'RSVD'<249>:
      PIN_NUMBER='(0,AE50,0,0,0,0,0,0,0,0,0,0,0,0,0,0,0,0,0,0,0,0,0,0,0,0,0,0,0,~
0)';
      BIDIRECTIONAL='TRUE';
      INPUT_LOAD='(-0.01,0.01)';
      OUTPUT_LOAD='(1.0,-1.0)';
      PINUSE='BI';
    'RSVD'<248>:
      PIN_NUMBER='(0,AE52,0,0,0,0,0,0,0,0,0,0,0,0,0,0,0,0,0,0,0,0,0,0,0,0,0,0,0,~
0)';
      BIDIRECTIONAL='TRUE';
      INPUT_LOAD='(-0.01,0.01)';
      OUTPUT_LOAD='(1.0,-1.0)';
      PINUSE='BI';
    'RSVD'<247>:
      PIN_NUMBER='(0,AE72,0,0,0,0,0,0,0,0,0,0,0,0,0,0,0,0,0,0,0,0,0,0,0,0,0,0,0,~
0)';
      BIDIRECTIONAL='TRUE';
      INPUT_LOAD='(-0.01,0.01)';
      OUTPUT_LOAD='(1.0,-1.0)';
      PINUSE='BI';
    'RSVD'<246>:
      PIN_NUMBER='(0,AF19,0,0,0,0,0,0,0,0,0,0,0,0,0,0,0,0,0,0,0,0,0,0,0,0,0,0,0,~
0)';
      BIDIRECTIONAL='TRUE';
      INPUT_LOAD='(-0.01,0.01)';
      OUTPUT_LOAD='(1.0,-1.0)';
      PINUSE='BI';
    'RSVD'<245>:
      PIN_NUMBER='(0,AF47,0,0,0,0,0,0,0,0,0,0,0,0,0,0,0,0,0,0,0,0,0,0,0,0,0,0,0,~
0)';
      BIDIRECTIONAL='TRUE';
      INPUT_LOAD='(-0.01,0.01)';
      OUTPUT_LOAD='(1.0,-1.0)';
      PINUSE='BI';
    'RSVD'<244>:
      PIN_NUMBER='(0,AF49,0,0,0,0,0,0,0,0,0,0,0,0,0,0,0,0,0,0,0,0,0,0,0,0,0,0,0,~
0)';
      BIDIRECTIONAL='TRUE';
      INPUT_LOAD='(-0.01,0.01)';
      OUTPUT_LOAD='(1.0,-1.0)';
      PINUSE='BI';
    'RSVD'<243>:
      PIN_NUMBER='(0,AF51,0,0,0,0,0,0,0,0,0,0,0,0,0,0,0,0,0,0,0,0,0,0,0,0,0,0,0,~
0)';
      BIDIRECTIONAL='TRUE';
      INPUT_LOAD='(-0.01,0.01)';
      OUTPUT_LOAD='(1.0,-1.0)';
      PINUSE='BI';
    'RSVD'<242>:
      PIN_NUMBER='(0,AF53,0,0,0,0,0,0,0,0,0,0,0,0,0,0,0,0,0,0,0,0,0,0,0,0,0,0,0,~
0)';
      BIDIRECTIONAL='TRUE';
      INPUT_LOAD='(-0.01,0.01)';
      OUTPUT_LOAD='(1.0,-1.0)';
      PINUSE='BI';
    'RSVD'<241>:
      PIN_NUMBER='(0,AF71,0,0,0,0,0,0,0,0,0,0,0,0,0,0,0,0,0,0,0,0,0,0,0,0,0,0,0,~
0)';
      BIDIRECTIONAL='TRUE';
      INPUT_LOAD='(-0.01,0.01)';
      OUTPUT_LOAD='(1.0,-1.0)';
      PINUSE='BI';
    'RSVD'<240>:
      PIN_NUMBER='(0,AG20,0,0,0,0,0,0,0,0,0,0,0,0,0,0,0,0,0,0,0,0,0,0,0,0,0,0,0,~
0)';
      BIDIRECTIONAL='TRUE';
      INPUT_LOAD='(-0.01,0.01)';
      OUTPUT_LOAD='(1.0,-1.0)';
      PINUSE='BI';
    'RSVD'<239>:
      PIN_NUMBER='(0,AG48,0,0,0,0,0,0,0,0,0,0,0,0,0,0,0,0,0,0,0,0,0,0,0,0,0,0,0,~
0)';
      BIDIRECTIONAL='TRUE';
      INPUT_LOAD='(-0.01,0.01)';
      OUTPUT_LOAD='(1.0,-1.0)';
      PINUSE='BI';
    'RSVD'<238>:
      PIN_NUMBER='(0,AG50,0,0,0,0,0,0,0,0,0,0,0,0,0,0,0,0,0,0,0,0,0,0,0,0,0,0,0,~
0)';
      BIDIRECTIONAL='TRUE';
      INPUT_LOAD='(-0.01,0.01)';
      OUTPUT_LOAD='(1.0,-1.0)';
      PINUSE='BI';
    'RSVD'<237>:
      PIN_NUMBER='(0,AG52,0,0,0,0,0,0,0,0,0,0,0,0,0,0,0,0,0,0,0,0,0,0,0,0,0,0,0,~
0)';
      BIDIRECTIONAL='TRUE';
      INPUT_LOAD='(-0.01,0.01)';
      OUTPUT_LOAD='(1.0,-1.0)';
      PINUSE='BI';
    'RSVD'<236>:
      PIN_NUMBER='(0,AG54,0,0,0,0,0,0,0,0,0,0,0,0,0,0,0,0,0,0,0,0,0,0,0,0,0,0,0,~
0)';
      BIDIRECTIONAL='TRUE';
      INPUT_LOAD='(-0.01,0.01)';
      OUTPUT_LOAD='(1.0,-1.0)';
      PINUSE='BI';
    'RSVD'<235>:
      PIN_NUMBER='(0,AG56,0,0,0,0,0,0,0,0,0,0,0,0,0,0,0,0,0,0,0,0,0,0,0,0,0,0,0,~
0)';
      BIDIRECTIONAL='TRUE';
      INPUT_LOAD='(-0.01,0.01)';
      OUTPUT_LOAD='(1.0,-1.0)';
      PINUSE='BI';
    'RSVD'<234>:
      PIN_NUMBER='(0,AG72,0,0,0,0,0,0,0,0,0,0,0,0,0,0,0,0,0,0,0,0,0,0,0,0,0,0,0,~
0)';
      BIDIRECTIONAL='TRUE';
      INPUT_LOAD='(-0.01,0.01)';
      OUTPUT_LOAD='(1.0,-1.0)';
      PINUSE='BI';
    'RSVD'<233>:
      PIN_NUMBER='(0,AH15,0,0,0,0,0,0,0,0,0,0,0,0,0,0,0,0,0,0,0,0,0,0,0,0,0,0,0,~
0)';
      BIDIRECTIONAL='TRUE';
      INPUT_LOAD='(-0.01,0.01)';
      OUTPUT_LOAD='(1.0,-1.0)';
      PINUSE='BI';
    'RSVD'<232>:
      PIN_NUMBER='(0,AH19,0,0,0,0,0,0,0,0,0,0,0,0,0,0,0,0,0,0,0,0,0,0,0,0,0,0,0,~
0)';
      BIDIRECTIONAL='TRUE';
      INPUT_LOAD='(-0.01,0.01)';
      OUTPUT_LOAD='(1.0,-1.0)';
      PINUSE='BI';
    'RSVD'<231>:
      PIN_NUMBER='(0,AH55,0,0,0,0,0,0,0,0,0,0,0,0,0,0,0,0,0,0,0,0,0,0,0,0,0,0,0,~
0)';
      BIDIRECTIONAL='TRUE';
      INPUT_LOAD='(-0.01,0.01)';
      OUTPUT_LOAD='(1.0,-1.0)';
      PINUSE='BI';
    'RSVD'<230>:
      PIN_NUMBER='(0,AH57,0,0,0,0,0,0,0,0,0,0,0,0,0,0,0,0,0,0,0,0,0,0,0,0,0,0,0,~
0)';
      BIDIRECTIONAL='TRUE';
      INPUT_LOAD='(-0.01,0.01)';
      OUTPUT_LOAD='(1.0,-1.0)';
      PINUSE='BI';
    'RSVD'<229>:
      PIN_NUMBER='(0,AH71,0,0,0,0,0,0,0,0,0,0,0,0,0,0,0,0,0,0,0,0,0,0,0,0,0,0,0,~
0)';
      BIDIRECTIONAL='TRUE';
      INPUT_LOAD='(-0.01,0.01)';
      OUTPUT_LOAD='(1.0,-1.0)';
      PINUSE='BI';
    'RSVD'<228>:
      PIN_NUMBER='(0,AH73,0,0,0,0,0,0,0,0,0,0,0,0,0,0,0,0,0,0,0,0,0,0,0,0,0,0,0,~
0)';
      BIDIRECTIONAL='TRUE';
      INPUT_LOAD='(-0.01,0.01)';
      OUTPUT_LOAD='(1.0,-1.0)';
      PINUSE='BI';
    'RSVD'<227>:
      PIN_NUMBER='(0,AJ20,0,0,0,0,0,0,0,0,0,0,0,0,0,0,0,0,0,0,0,0,0,0,0,0,0,0,0,~
0)';
      BIDIRECTIONAL='TRUE';
      INPUT_LOAD='(-0.01,0.01)';
      OUTPUT_LOAD='(1.0,-1.0)';
      PINUSE='BI';
    'RSVD'<226>:
      PIN_NUMBER='(0,AJ56,0,0,0,0,0,0,0,0,0,0,0,0,0,0,0,0,0,0,0,0,0,0,0,0,0,0,0,~
0)';
      BIDIRECTIONAL='TRUE';
      INPUT_LOAD='(-0.01,0.01)';
      OUTPUT_LOAD='(1.0,-1.0)';
      PINUSE='BI';
    'RSVD'<225>:
      PIN_NUMBER='(0,AJ58,0,0,0,0,0,0,0,0,0,0,0,0,0,0,0,0,0,0,0,0,0,0,0,0,0,0,0,~
0)';
      BIDIRECTIONAL='TRUE';
      INPUT_LOAD='(-0.01,0.01)';
      OUTPUT_LOAD='(1.0,-1.0)';
      PINUSE='BI';
    'RSVD'<224>:
      PIN_NUMBER='(0,AJ60,0,0,0,0,0,0,0,0,0,0,0,0,0,0,0,0,0,0,0,0,0,0,0,0,0,0,0,~
0)';
      BIDIRECTIONAL='TRUE';
      INPUT_LOAD='(-0.01,0.01)';
      OUTPUT_LOAD='(1.0,-1.0)';
      PINUSE='BI';
    'RSVD'<223>:
      PIN_NUMBER='(0,AJ62,0,0,0,0,0,0,0,0,0,0,0,0,0,0,0,0,0,0,0,0,0,0,0,0,0,0,0,~
0)';
      BIDIRECTIONAL='TRUE';
      INPUT_LOAD='(-0.01,0.01)';
      OUTPUT_LOAD='(1.0,-1.0)';
      PINUSE='BI';
    'RSVD'<222>:
      PIN_NUMBER='(0,AJ70,0,0,0,0,0,0,0,0,0,0,0,0,0,0,0,0,0,0,0,0,0,0,0,0,0,0,0,~
0)';
      BIDIRECTIONAL='TRUE';
      INPUT_LOAD='(-0.01,0.01)';
      OUTPUT_LOAD='(1.0,-1.0)';
      PINUSE='BI';
    'RSVD'<221>:
      PIN_NUMBER='(0,AK21,0,0,0,0,0,0,0,0,0,0,0,0,0,0,0,0,0,0,0,0,0,0,0,0,0,0,0,~
0)';
      BIDIRECTIONAL='TRUE';
      INPUT_LOAD='(-0.01,0.01)';
      OUTPUT_LOAD='(1.0,-1.0)';
      PINUSE='BI';
    'RSVD'<220>:
      PIN_NUMBER='(0,AK27,0,0,0,0,0,0,0,0,0,0,0,0,0,0,0,0,0,0,0,0,0,0,0,0,0,0,0,~
0)';
      BIDIRECTIONAL='TRUE';
      INPUT_LOAD='(-0.01,0.01)';
      OUTPUT_LOAD='(1.0,-1.0)';
      PINUSE='BI';
    'RSVD'<219>:
      PIN_NUMBER='(0,AK57,0,0,0,0,0,0,0,0,0,0,0,0,0,0,0,0,0,0,0,0,0,0,0,0,0,0,0,~
0)';
      BIDIRECTIONAL='TRUE';
      INPUT_LOAD='(-0.01,0.01)';
      OUTPUT_LOAD='(1.0,-1.0)';
      PINUSE='BI';
    'RSVD'<218>:
      PIN_NUMBER='(0,AK59,0,0,0,0,0,0,0,0,0,0,0,0,0,0,0,0,0,0,0,0,0,0,0,0,0,0,0,~
0)';
      BIDIRECTIONAL='TRUE';
      INPUT_LOAD='(-0.01,0.01)';
      OUTPUT_LOAD='(1.0,-1.0)';
      PINUSE='BI';
    'RSVD'<217>:
      PIN_NUMBER='(0,AK61,0,0,0,0,0,0,0,0,0,0,0,0,0,0,0,0,0,0,0,0,0,0,0,0,0,0,0,~
0)';
      BIDIRECTIONAL='TRUE';
      INPUT_LOAD='(-0.01,0.01)';
      OUTPUT_LOAD='(1.0,-1.0)';
      PINUSE='BI';
    'RSVD'<216>:
      PIN_NUMBER='(0,AK69,0,0,0,0,0,0,0,0,0,0,0,0,0,0,0,0,0,0,0,0,0,0,0,0,0,0,0,~
0)';
      BIDIRECTIONAL='TRUE';
      INPUT_LOAD='(-0.01,0.01)';
      OUTPUT_LOAD='(1.0,-1.0)';
      PINUSE='BI';
    'RSVD'<215>:
      PIN_NUMBER='(0,AL20,0,0,0,0,0,0,0,0,0,0,0,0,0,0,0,0,0,0,0,0,0,0,0,0,0,0,0,~
0)';
      BIDIRECTIONAL='TRUE';
      INPUT_LOAD='(-0.01,0.01)';
      OUTPUT_LOAD='(1.0,-1.0)';
      PINUSE='BI';
    'RSVD'<214>:
      PIN_NUMBER='(0,AL22,0,0,0,0,0,0,0,0,0,0,0,0,0,0,0,0,0,0,0,0,0,0,0,0,0,0,0,~
0)';
      BIDIRECTIONAL='TRUE';
      INPUT_LOAD='(-0.01,0.01)';
      OUTPUT_LOAD='(1.0,-1.0)';
      PINUSE='BI';
    'RSVD'<213>:
      PIN_NUMBER='(0,AL26,0,0,0,0,0,0,0,0,0,0,0,0,0,0,0,0,0,0,0,0,0,0,0,0,0,0,0,~
0)';
      BIDIRECTIONAL='TRUE';
      INPUT_LOAD='(-0.01,0.01)';
      OUTPUT_LOAD='(1.0,-1.0)';
      PINUSE='BI';
    'RSVD'<212>:
      PIN_NUMBER='(0,AL58,0,0,0,0,0,0,0,0,0,0,0,0,0,0,0,0,0,0,0,0,0,0,0,0,0,0,0,~
0)';
      BIDIRECTIONAL='TRUE';
      INPUT_LOAD='(-0.01,0.01)';
      OUTPUT_LOAD='(1.0,-1.0)';
      PINUSE='BI';
    'RSVD'<211>:
      PIN_NUMBER='(0,AL60,0,0,0,0,0,0,0,0,0,0,0,0,0,0,0,0,0,0,0,0,0,0,0,0,0,0,0,~
0)';
      BIDIRECTIONAL='TRUE';
      INPUT_LOAD='(-0.01,0.01)';
      OUTPUT_LOAD='(1.0,-1.0)';
      PINUSE='BI';
    'RSVD'<210>:
      PIN_NUMBER='(0,AL62,0,0,0,0,0,0,0,0,0,0,0,0,0,0,0,0,0,0,0,0,0,0,0,0,0,0,0,~
0)';
      BIDIRECTIONAL='TRUE';
      INPUT_LOAD='(-0.01,0.01)';
      OUTPUT_LOAD='(1.0,-1.0)';
      PINUSE='BI';
    'RSVD'<209>:
      PIN_NUMBER='(0,AM21,0,0,0,0,0,0,0,0,0,0,0,0,0,0,0,0,0,0,0,0,0,0,0,0,0,0,0,~
0)';
      BIDIRECTIONAL='TRUE';
      INPUT_LOAD='(-0.01,0.01)';
      OUTPUT_LOAD='(1.0,-1.0)';
      PINUSE='BI';
    'RSVD'<208>:
      PIN_NUMBER='(0,AM23,0,0,0,0,0,0,0,0,0,0,0,0,0,0,0,0,0,0,0,0,0,0,0,0,0,0,0,~
0)';
      BIDIRECTIONAL='TRUE';
      INPUT_LOAD='(-0.01,0.01)';
      OUTPUT_LOAD='(1.0,-1.0)';
      PINUSE='BI';
    'RSVD'<207>:
      PIN_NUMBER='(0,AM25,0,0,0,0,0,0,0,0,0,0,0,0,0,0,0,0,0,0,0,0,0,0,0,0,0,0,0,~
0)';
      BIDIRECTIONAL='TRUE';
      INPUT_LOAD='(-0.01,0.01)';
      OUTPUT_LOAD='(1.0,-1.0)';
      PINUSE='BI';
    'RSVD'<206>:
      PIN_NUMBER='(0,AM27,0,0,0,0,0,0,0,0,0,0,0,0,0,0,0,0,0,0,0,0,0,0,0,0,0,0,0,~
0)';
      BIDIRECTIONAL='TRUE';
      INPUT_LOAD='(-0.01,0.01)';
      OUTPUT_LOAD='(1.0,-1.0)';
      PINUSE='BI';
    'RSVD'<205>:
      PIN_NUMBER='(0,AM59,0,0,0,0,0,0,0,0,0,0,0,0,0,0,0,0,0,0,0,0,0,0,0,0,0,0,0,~
0)';
      BIDIRECTIONAL='TRUE';
      INPUT_LOAD='(-0.01,0.01)';
      OUTPUT_LOAD='(1.0,-1.0)';
      PINUSE='BI';
    'RSVD'<204>:
      PIN_NUMBER='(0,AM61,0,0,0,0,0,0,0,0,0,0,0,0,0,0,0,0,0,0,0,0,0,0,0,0,0,0,0,~
0)';
      BIDIRECTIONAL='TRUE';
      INPUT_LOAD='(-0.01,0.01)';
      OUTPUT_LOAD='(1.0,-1.0)';
      PINUSE='BI';
    'RSVD'<203>:
      PIN_NUMBER='(0,AN18,0,0,0,0,0,0,0,0,0,0,0,0,0,0,0,0,0,0,0,0,0,0,0,0,0,0,0,~
0)';
      BIDIRECTIONAL='TRUE';
      INPUT_LOAD='(-0.01,0.01)';
      OUTPUT_LOAD='(1.0,-1.0)';
      PINUSE='BI';
    'RSVD'<202>:
      PIN_NUMBER='(0,AN22,0,0,0,0,0,0,0,0,0,0,0,0,0,0,0,0,0,0,0,0,0,0,0,0,0,0,0,~
0)';
      BIDIRECTIONAL='TRUE';
      INPUT_LOAD='(-0.01,0.01)';
      OUTPUT_LOAD='(1.0,-1.0)';
      PINUSE='BI';
    'RSVD'<201>:
      PIN_NUMBER='(0,AN24,0,0,0,0,0,0,0,0,0,0,0,0,0,0,0,0,0,0,0,0,0,0,0,0,0,0,0,~
0)';
      BIDIRECTIONAL='TRUE';
      INPUT_LOAD='(-0.01,0.01)';
      OUTPUT_LOAD='(1.0,-1.0)';
      PINUSE='BI';
    'RSVD'<200>:
      PIN_NUMBER='(0,AN26,0,0,0,0,0,0,0,0,0,0,0,0,0,0,0,0,0,0,0,0,0,0,0,0,0,0,0,~
0)';
      BIDIRECTIONAL='TRUE';
      INPUT_LOAD='(-0.01,0.01)';
      OUTPUT_LOAD='(1.0,-1.0)';
      PINUSE='BI';
    'RSVD'<199>:
      PIN_NUMBER='(0,AN60,0,0,0,0,0,0,0,0,0,0,0,0,0,0,0,0,0,0,0,0,0,0,0,0,0,0,0,~
0)';
      BIDIRECTIONAL='TRUE';
      INPUT_LOAD='(-0.01,0.01)';
      OUTPUT_LOAD='(1.0,-1.0)';
      PINUSE='BI';
    'RSVD'<198>:
      PIN_NUMBER='(0,AN62,0,0,0,0,0,0,0,0,0,0,0,0,0,0,0,0,0,0,0,0,0,0,0,0,0,0,0,~
0)';
      BIDIRECTIONAL='TRUE';
      INPUT_LOAD='(-0.01,0.01)';
      OUTPUT_LOAD='(1.0,-1.0)';
      PINUSE='BI';
    'RSVD'<197>:
      PIN_NUMBER='(0,AP23,0,0,0,0,0,0,0,0,0,0,0,0,0,0,0,0,0,0,0,0,0,0,0,0,0,0,0,~
0)';
      BIDIRECTIONAL='TRUE';
      INPUT_LOAD='(-0.01,0.01)';
      OUTPUT_LOAD='(1.0,-1.0)';
      PINUSE='BI';
    'RSVD'<196>:
      PIN_NUMBER='(0,AP25,0,0,0,0,0,0,0,0,0,0,0,0,0,0,0,0,0,0,0,0,0,0,0,0,0,0,0,~
0)';
      BIDIRECTIONAL='TRUE';
      INPUT_LOAD='(-0.01,0.01)';
      OUTPUT_LOAD='(1.0,-1.0)';
      PINUSE='BI';
    'RSVD'<195>:
      PIN_NUMBER='(0,AP27,0,0,0,0,0,0,0,0,0,0,0,0,0,0,0,0,0,0,0,0,0,0,0,0,0,0,0,~
0)';
      BIDIRECTIONAL='TRUE';
      INPUT_LOAD='(-0.01,0.01)';
      OUTPUT_LOAD='(1.0,-1.0)';
      PINUSE='BI';
    'RSVD'<194>:
      PIN_NUMBER='(0,AP61,0,0,0,0,0,0,0,0,0,0,0,0,0,0,0,0,0,0,0,0,0,0,0,0,0,0,0,~
0)';
      BIDIRECTIONAL='TRUE';
      INPUT_LOAD='(-0.01,0.01)';
      OUTPUT_LOAD='(1.0,-1.0)';
      PINUSE='BI';
    'RSVD'<193>:
      PIN_NUMBER='(0,0,0,0,0,0,0,0,AR20,0,0,0,0,0,0,0,0,0,0,0,0,0,0,0,0,0,0,0,0,~
0)';
      BIDIRECTIONAL='TRUE';
      INPUT_LOAD='(-0.01,0.01)';
      OUTPUT_LOAD='(1.0,-1.0)';
      PINUSE='BI';
    'RSVD'<192>:
      PIN_NUMBER='(0,0,0,0,0,0,0,0,AR22,0,0,0,0,0,0,0,0,0,0,0,0,0,0,0,0,0,0,0,0,~
0)';
      BIDIRECTIONAL='TRUE';
      INPUT_LOAD='(-0.01,0.01)';
      OUTPUT_LOAD='(1.0,-1.0)';
      PINUSE='BI';
    'RSVD'<191>:
      PIN_NUMBER='(0,0,0,0,0,0,0,0,AR26,0,0,0,0,0,0,0,0,0,0,0,0,0,0,0,0,0,0,0,0,~
0)';
      BIDIRECTIONAL='TRUE';
      INPUT_LOAD='(-0.01,0.01)';
      OUTPUT_LOAD='(1.0,-1.0)';
      PINUSE='BI';
    'RSVD'<190>:
      PIN_NUMBER='(0,0,0,0,0,0,0,0,AR62,0,0,0,0,0,0,0,0,0,0,0,0,0,0,0,0,0,0,0,0,~
0)';
      BIDIRECTIONAL='TRUE';
      INPUT_LOAD='(-0.01,0.01)';
      OUTPUT_LOAD='(1.0,-1.0)';
      PINUSE='BI';
    'RSVD'<189>:
      PIN_NUMBER='(0,0,0,0,0,0,0,0,AT13,0,0,0,0,0,0,0,0,0,0,0,0,0,0,0,0,0,0,0,0,~
0)';
      BIDIRECTIONAL='TRUE';
      INPUT_LOAD='(-0.01,0.01)';
      OUTPUT_LOAD='(1.0,-1.0)';
      PINUSE='BI';
    'RSVD'<188>:
      PIN_NUMBER='(0,0,0,0,0,0,0,0,AT23,0,0,0,0,0,0,0,0,0,0,0,0,0,0,0,0,0,0,0,0,~
0)';
      BIDIRECTIONAL='TRUE';
      INPUT_LOAD='(-0.01,0.01)';
      OUTPUT_LOAD='(1.0,-1.0)';
      PINUSE='BI';
    'RSVD'<187>:
      PIN_NUMBER='(0,0,0,0,0,0,0,0,AT25,0,0,0,0,0,0,0,0,0,0,0,0,0,0,0,0,0,0,0,0,~
0)';
      BIDIRECTIONAL='TRUE';
      INPUT_LOAD='(-0.01,0.01)';
      OUTPUT_LOAD='(1.0,-1.0)';
      PINUSE='BI';
    'RSVD'<186>:
      PIN_NUMBER='(0,0,0,0,0,0,0,0,AV77,0,0,0,0,0,0,0,0,0,0,0,0,0,0,0,0,0,0,0,0,~
0)';
      BIDIRECTIONAL='TRUE';
      INPUT_LOAD='(-0.01,0.01)';
      OUTPUT_LOAD='(1.0,-1.0)';
      PINUSE='BI';
    'RSVD'<184>:
      PIN_NUMBER='(0,0,0,0,0,0,0,0,AW64,0,0,0,0,0,0,0,0,0,0,0,0,0,0,0,0,0,0,0,0,~
0)';
      BIDIRECTIONAL='TRUE';
      INPUT_LOAD='(-0.01,0.01)';
      OUTPUT_LOAD='(1.0,-1.0)';
      PINUSE='BI';
    'RSVD'<183>:
      PIN_NUMBER='(0,0,0,0,0,0,0,0,AW76,0,0,0,0,0,0,0,0,0,0,0,0,0,0,0,0,0,0,0,0,~
0)';
      BIDIRECTIONAL='TRUE';
      INPUT_LOAD='(-0.01,0.01)';
      OUTPUT_LOAD='(1.0,-1.0)';
      PINUSE='BI';
    'RSVD'<182>:
      PIN_NUMBER='(0,0,0,0,0,0,0,0,AY65,0,0,0,0,0,0,0,0,0,0,0,0,0,0,0,0,0,0,0,0,~
0)';
      BIDIRECTIONAL='TRUE';
      INPUT_LOAD='(-0.01,0.01)';
      OUTPUT_LOAD='(1.0,-1.0)';
      PINUSE='BI';
    'RSVD'<181>:
      PIN_NUMBER='(0,0,0,0,0,0,0,0,AY67,0,0,0,0,0,0,0,0,0,0,0,0,0,0,0,0,0,0,0,0,~
0)';
      BIDIRECTIONAL='TRUE';
      INPUT_LOAD='(-0.01,0.01)';
      OUTPUT_LOAD='(1.0,-1.0)';
      PINUSE='BI';
    'RSVD'<180>:
      PIN_NUMBER='(0,0,0,0,0,0,0,0,AY75,0,0,0,0,0,0,0,0,0,0,0,0,0,0,0,0,0,0,0,0,~
0)';
      BIDIRECTIONAL='TRUE';
      INPUT_LOAD='(-0.01,0.01)';
      OUTPUT_LOAD='(1.0,-1.0)';
      PINUSE='BI';
    'RSVD'<179>:
      PIN_NUMBER='(0,0,0,0,0,0,0,0,AY77,0,0,0,0,0,0,0,0,0,0,0,0,0,0,0,0,0,0,0,0,~
0)';
      BIDIRECTIONAL='TRUE';
      INPUT_LOAD='(-0.01,0.01)';
      OUTPUT_LOAD='(1.0,-1.0)';
      PINUSE='BI';
    'RSVD'<178>:
      PIN_NUMBER='(0,0,0,0,0,0,0,0,BA14,0,0,0,0,0,0,0,0,0,0,0,0,0,0,0,0,0,0,0,0,~
0)';
      BIDIRECTIONAL='TRUE';
      INPUT_LOAD='(-0.01,0.01)';
      OUTPUT_LOAD='(1.0,-1.0)';
      PINUSE='BI';
    'RSVD'<177>:
      PIN_NUMBER='(0,0,0,0,0,0,0,0,BA16,0,0,0,0,0,0,0,0,0,0,0,0,0,0,0,0,0,0,0,0,~
0)';
      BIDIRECTIONAL='TRUE';
      INPUT_LOAD='(-0.01,0.01)';
      OUTPUT_LOAD='(1.0,-1.0)';
      PINUSE='BI';
    'RSVD'<176>:
      PIN_NUMBER='(0,0,0,0,0,0,0,0,BA18,0,0,0,0,0,0,0,0,0,0,0,0,0,0,0,0,0,0,0,0,~
0)';
      BIDIRECTIONAL='TRUE';
      INPUT_LOAD='(-0.01,0.01)';
      OUTPUT_LOAD='(1.0,-1.0)';
      PINUSE='BI';
    'RSVD'<175>:
      PIN_NUMBER='(0,0,0,0,0,0,0,0,BA22,0,0,0,0,0,0,0,0,0,0,0,0,0,0,0,0,0,0,0,0,~
0)';
      BIDIRECTIONAL='TRUE';
      INPUT_LOAD='(-0.01,0.01)';
      OUTPUT_LOAD='(1.0,-1.0)';
      PINUSE='BI';
    'RSVD'<174>:
      PIN_NUMBER='(0,0,0,0,0,0,0,0,BA64,0,0,0,0,0,0,0,0,0,0,0,0,0,0,0,0,0,0,0,0,~
0)';
      BIDIRECTIONAL='TRUE';
      INPUT_LOAD='(-0.01,0.01)';
      OUTPUT_LOAD='(1.0,-1.0)';
      PINUSE='BI';
    'RSVD'<173>:
      PIN_NUMBER='(0,0,0,0,0,0,0,0,BA66,0,0,0,0,0,0,0,0,0,0,0,0,0,0,0,0,0,0,0,0,~
0)';
      BIDIRECTIONAL='TRUE';
      INPUT_LOAD='(-0.01,0.01)';
      OUTPUT_LOAD='(1.0,-1.0)';
      PINUSE='BI';
    'RSVD'<172>:
      PIN_NUMBER='(0,0,0,0,0,0,0,0,BA76,0,0,0,0,0,0,0,0,0,0,0,0,0,0,0,0,0,0,0,0,~
0)';
      BIDIRECTIONAL='TRUE';
      INPUT_LOAD='(-0.01,0.01)';
      OUTPUT_LOAD='(1.0,-1.0)';
      PINUSE='BI';
    'RSVD'<171>:
      PIN_NUMBER='(0,0,0,0,0,0,0,0,0,0,0,0,0,0,0,BA78,0,0,0,0,0,0,0,0,0,0,0,0,0,~
0)';
      BIDIRECTIONAL='TRUE';
      INPUT_LOAD='(-0.01,0.01)';
      OUTPUT_LOAD='(1.0,-1.0)';
      PINUSE='BI';
    'RSVD'<170>:
      PIN_NUMBER='(0,0,0,0,0,0,0,0,0,0,0,0,0,0,0,BA82,0,0,0,0,0,0,0,0,0,0,0,0,0,~
0)';
      BIDIRECTIONAL='TRUE';
      INPUT_LOAD='(-0.01,0.01)';
      OUTPUT_LOAD='(1.0,-1.0)';
      PINUSE='BI';
    'RSVD'<169>:
      PIN_NUMBER='(0,0,0,0,0,0,0,0,0,0,0,0,0,0,0,BB13,0,0,0,0,0,0,0,0,0,0,0,0,0,~
0)';
      BIDIRECTIONAL='TRUE';
      INPUT_LOAD='(-0.01,0.01)';
      OUTPUT_LOAD='(1.0,-1.0)';
      PINUSE='BI';
    'RSVD'<168>:
      PIN_NUMBER='(0,0,0,0,0,0,0,0,0,0,0,0,0,0,0,BB15,0,0,0,0,0,0,0,0,0,0,0,0,0,~
0)';
      BIDIRECTIONAL='TRUE';
      INPUT_LOAD='(-0.01,0.01)';
      OUTPUT_LOAD='(1.0,-1.0)';
      PINUSE='BI';
    'RSVD'<167>:
      PIN_NUMBER='(0,0,0,0,0,0,0,0,0,0,0,0,0,0,0,BB17,0,0,0,0,0,0,0,0,0,0,0,0,0,~
0)';
      BIDIRECTIONAL='TRUE';
      INPUT_LOAD='(-0.01,0.01)';
      OUTPUT_LOAD='(1.0,-1.0)';
      PINUSE='BI';
    'RSVD'<166>:
      PIN_NUMBER='(0,0,0,0,0,0,0,0,0,0,0,0,0,0,0,BB21,0,0,0,0,0,0,0,0,0,0,0,0,0,~
0)';
      BIDIRECTIONAL='TRUE';
      INPUT_LOAD='(-0.01,0.01)';
      OUTPUT_LOAD='(1.0,-1.0)';
      PINUSE='BI';
    'RSVD'<165>:
      PIN_NUMBER='(0,0,0,0,0,0,0,0,0,0,0,0,0,0,0,BB25,0,0,0,0,0,0,0,0,0,0,0,0,0,~
0)';
      BIDIRECTIONAL='TRUE';
      INPUT_LOAD='(-0.01,0.01)';
      OUTPUT_LOAD='(1.0,-1.0)';
      PINUSE='BI';
    'RSVD'<164>:
      PIN_NUMBER='(0,0,0,0,0,0,0,0,0,0,0,0,0,0,0,BB65,0,0,0,0,0,0,0,0,0,0,0,0,0,~
0)';
      BIDIRECTIONAL='TRUE';
      INPUT_LOAD='(-0.01,0.01)';
      OUTPUT_LOAD='(1.0,-1.0)';
      PINUSE='BI';
    'RSVD'<163>:
      PIN_NUMBER='(0,0,0,0,0,0,0,0,0,0,0,0,0,0,0,BB67,0,0,0,0,0,0,0,0,0,0,0,0,0,~
0)';
      BIDIRECTIONAL='TRUE';
      INPUT_LOAD='(-0.01,0.01)';
      OUTPUT_LOAD='(1.0,-1.0)';
      PINUSE='BI';
    'RSVD'<162>:
      PIN_NUMBER='(0,0,0,0,0,0,0,0,0,0,0,0,0,0,0,BC14,0,0,0,0,0,0,0,0,0,0,0,0,0,~
0)';
      BIDIRECTIONAL='TRUE';
      INPUT_LOAD='(-0.01,0.01)';
      OUTPUT_LOAD='(1.0,-1.0)';
      PINUSE='BI';
    'RSVD'<161>:
      PIN_NUMBER='(0,0,0,0,0,0,0,0,0,0,0,0,0,0,0,BC18,0,0,0,0,0,0,0,0,0,0,0,0,0,~
0)';
      BIDIRECTIONAL='TRUE';
      INPUT_LOAD='(-0.01,0.01)';
      OUTPUT_LOAD='(1.0,-1.0)';
      PINUSE='BI';
    'RSVD'<160>:
      PIN_NUMBER='(0,0,0,0,0,0,0,0,0,0,0,0,0,0,0,BC20,0,0,0,0,0,0,0,0,0,0,0,0,0,~
0)';
      BIDIRECTIONAL='TRUE';
      INPUT_LOAD='(-0.01,0.01)';
      OUTPUT_LOAD='(1.0,-1.0)';
      PINUSE='BI';
    'RSVD'<159>:
      PIN_NUMBER='(0,0,0,0,0,0,0,0,0,0,0,0,0,0,0,BC22,0,0,0,0,0,0,0,0,0,0,0,0,0,~
0)';
      BIDIRECTIONAL='TRUE';
      INPUT_LOAD='(-0.01,0.01)';
      OUTPUT_LOAD='(1.0,-1.0)';
      PINUSE='BI';
    'RSVD'<158>:
      PIN_NUMBER='(0,0,0,0,0,0,0,0,0,0,0,0,0,0,0,BC64,0,0,0,0,0,0,0,0,0,0,0,0,0,~
0)';
      BIDIRECTIONAL='TRUE';
      INPUT_LOAD='(-0.01,0.01)';
      OUTPUT_LOAD='(1.0,-1.0)';
      PINUSE='BI';
    'RSVD'<157>:
      PIN_NUMBER='(0,0,0,0,0,0,0,0,0,0,0,0,0,0,0,BC66,0,0,0,0,0,0,0,0,0,0,0,0,0,~
0)';
      BIDIRECTIONAL='TRUE';
      INPUT_LOAD='(-0.01,0.01)';
      OUTPUT_LOAD='(1.0,-1.0)';
      PINUSE='BI';
    'RSVD'<156>:
      PIN_NUMBER='(0,0,0,0,0,0,0,0,0,0,0,0,0,0,0,BC68,0,0,0,0,0,0,0,0,0,0,0,0,0,~
0)';
      BIDIRECTIONAL='TRUE';
      INPUT_LOAD='(-0.01,0.01)';
      OUTPUT_LOAD='(1.0,-1.0)';
      PINUSE='BI';
    'RSVD'<155>:
      PIN_NUMBER='(0,0,0,0,0,0,0,0,0,0,0,0,0,0,0,BD17,0,0,0,0,0,0,0,0,0,0,0,0,0,~
0)';
      BIDIRECTIONAL='TRUE';
      INPUT_LOAD='(-0.01,0.01)';
      OUTPUT_LOAD='(1.0,-1.0)';
      PINUSE='BI';
    'RSVD'<154>:
      PIN_NUMBER='(0,0,0,0,0,0,0,0,0,0,0,0,0,0,0,BD19,0,0,0,0,0,0,0,0,0,0,0,0,0,~
0)';
      BIDIRECTIONAL='TRUE';
      INPUT_LOAD='(-0.01,0.01)';
      OUTPUT_LOAD='(1.0,-1.0)';
      PINUSE='BI';
    'RSVD'<153>:
      PIN_NUMBER='(0,0,0,0,0,0,0,0,0,0,0,0,0,0,0,BD25,0,0,0,0,0,0,0,0,0,0,0,0,0,~
0)';
      BIDIRECTIONAL='TRUE';
      INPUT_LOAD='(-0.01,0.01)';
      OUTPUT_LOAD='(1.0,-1.0)';
      PINUSE='BI';
    'RSVD'<152>:
      PIN_NUMBER='(0,0,0,0,0,0,0,0,0,0,0,0,0,0,0,BD65,0,0,0,0,0,0,0,0,0,0,0,0,0,~
0)';
      BIDIRECTIONAL='TRUE';
      INPUT_LOAD='(-0.01,0.01)';
      OUTPUT_LOAD='(1.0,-1.0)';
      PINUSE='BI';
    'RSVD'<151>:
      PIN_NUMBER='(0,0,0,0,0,0,0,0,0,0,0,0,0,0,0,BD67,0,0,0,0,0,0,0,0,0,0,0,0,0,~
0)';
      BIDIRECTIONAL='TRUE';
      INPUT_LOAD='(-0.01,0.01)';
      OUTPUT_LOAD='(1.0,-1.0)';
      PINUSE='BI';
    'RSVD'<150>:
      PIN_NUMBER='(0,0,0,0,0,0,0,0,0,0,0,0,0,0,0,BD69,0,0,0,0,0,0,0,0,0,0,0,0,0,~
0)';
      BIDIRECTIONAL='TRUE';
      INPUT_LOAD='(-0.01,0.01)';
      OUTPUT_LOAD='(1.0,-1.0)';
      PINUSE='BI';
    'RSVD'<149>:
      PIN_NUMBER='(0,0,0,0,0,0,0,0,0,0,0,0,0,0,0,BE18,0,0,0,0,0,0,0,0,0,0,0,0,0,~
0)';
      BIDIRECTIONAL='TRUE';
      INPUT_LOAD='(-0.01,0.01)';
      OUTPUT_LOAD='(1.0,-1.0)';
      PINUSE='BI';
    'RSVD'<148>:
      PIN_NUMBER='(0,0,0,0,0,0,0,0,0,0,0,0,0,0,0,BE20,0,0,0,0,0,0,0,0,0,0,0,0,0,~
0)';
      BIDIRECTIONAL='TRUE';
      INPUT_LOAD='(-0.01,0.01)';
      OUTPUT_LOAD='(1.0,-1.0)';
      PINUSE='BI';
    'RSVD'<147>:
      PIN_NUMBER='(0,0,0,0,0,0,0,0,0,0,0,0,0,0,0,BE22,0,0,0,0,0,0,0,0,0,0,0,0,0,~
0)';
      BIDIRECTIONAL='TRUE';
      INPUT_LOAD='(-0.01,0.01)';
      OUTPUT_LOAD='(1.0,-1.0)';
      PINUSE='BI';
    'RSVD'<146>:
      PIN_NUMBER='(0,0,0,0,0,0,0,0,0,0,0,0,0,0,0,BF21,0,0,0,0,0,0,0,0,0,0,0,0,0,~
0)';
      BIDIRECTIONAL='TRUE';
      INPUT_LOAD='(-0.01,0.01)';
      OUTPUT_LOAD='(1.0,-1.0)';
      PINUSE='BI';
    'RSVD'<145>:
      PIN_NUMBER='(0,0,0,0,0,0,0,0,0,0,0,0,0,0,0,BG18,0,0,0,0,0,0,0,0,0,0,0,0,0,~
0)';
      BIDIRECTIONAL='TRUE';
      INPUT_LOAD='(-0.01,0.01)';
      OUTPUT_LOAD='(1.0,-1.0)';
      PINUSE='BI';
    'RSVD'<144>:
      PIN_NUMBER='(0,0,0,0,0,0,0,0,0,0,0,0,0,0,0,BG20,0,0,0,0,0,0,0,0,0,0,0,0,0,~
0)';
      BIDIRECTIONAL='TRUE';
      INPUT_LOAD='(-0.01,0.01)';
      OUTPUT_LOAD='(1.0,-1.0)';
      PINUSE='BI';
    'RSVD'<143>:
      PIN_NUMBER='(0,0,0,0,0,0,0,0,0,0,0,0,0,0,0,BH19,0,0,0,0,0,0,0,0,0,0,0,0,0,~
0)';
      BIDIRECTIONAL='TRUE';
      INPUT_LOAD='(-0.01,0.01)';
      OUTPUT_LOAD='(1.0,-1.0)';
      PINUSE='BI';
    'RSVD'<142>:
      PIN_NUMBER='(0,0,0,0,0,0,0,0,0,0,0,0,0,0,0,BJ16,0,0,0,0,0,0,0,0,0,0,0,0,0,~
0)';
      BIDIRECTIONAL='TRUE';
      INPUT_LOAD='(-0.01,0.01)';
      OUTPUT_LOAD='(1.0,-1.0)';
      PINUSE='BI';
    'RSVD'<141>:
      PIN_NUMBER='(0,0,0,0,0,0,0,0,0,0,0,0,0,0,0,BJ18,0,0,0,0,0,0,0,0,0,0,0,0,0,~
0)';
      BIDIRECTIONAL='TRUE';
      INPUT_LOAD='(-0.01,0.01)';
      OUTPUT_LOAD='(1.0,-1.0)';
      PINUSE='BI';
    'RSVD'<140>:
      PIN_NUMBER='(0,0,0,0,0,0,0,0,0,0,0,0,0,0,0,BJ20,0,0,0,0,0,0,0,0,0,0,0,0,0,~
0)';
      BIDIRECTIONAL='TRUE';
      INPUT_LOAD='(-0.01,0.01)';
      OUTPUT_LOAD='(1.0,-1.0)';
      PINUSE='BI';
    'RSVD'<139>:
      PIN_NUMBER='(0,0,0,0,0,0,0,0,0,0,0,0,0,0,0,BK17,0,0,0,0,0,0,0,0,0,0,0,0,0,~
0)';
      BIDIRECTIONAL='TRUE';
      INPUT_LOAD='(-0.01,0.01)';
      OUTPUT_LOAD='(1.0,-1.0)';
      PINUSE='BI';
    'RSVD'<138>:
      PIN_NUMBER='(0,0,0,0,0,0,0,0,0,0,0,0,0,0,0,BL18,0,0,0,0,0,0,0,0,0,0,0,0,0,~
0)';
      BIDIRECTIONAL='TRUE';
      INPUT_LOAD='(-0.01,0.01)';
      OUTPUT_LOAD='(1.0,-1.0)';
      PINUSE='BI';
    'RSVD'<137>:
      PIN_NUMBER='(0,0,0,0,0,0,0,0,0,0,0,0,0,0,0,BL20,0,0,0,0,0,0,0,0,0,0,0,0,0,~
0)';
      BIDIRECTIONAL='TRUE';
      INPUT_LOAD='(-0.01,0.01)';
      OUTPUT_LOAD='(1.0,-1.0)';
      PINUSE='BI';
    'RSVD'<136>:
      PIN_NUMBER='(0,0,0,0,0,0,0,0,0,0,0,0,0,0,0,BM17,0,0,0,0,0,0,0,0,0,0,0,0,0,~
0)';
      BIDIRECTIONAL='TRUE';
      INPUT_LOAD='(-0.01,0.01)';
      OUTPUT_LOAD='(1.0,-1.0)';
      PINUSE='BI';
    'RSVD'<135>:
      PIN_NUMBER='(0,0,0,0,0,0,0,0,0,0,0,0,0,0,0,BM19,0,0,0,0,0,0,0,0,0,0,0,0,0,~
0)';
      BIDIRECTIONAL='TRUE';
      INPUT_LOAD='(-0.01,0.01)';
      OUTPUT_LOAD='(1.0,-1.0)';
      PINUSE='BI';
    'RSVD'<134>:
      PIN_NUMBER='(0,0,0,0,0,0,0,0,0,0,0,0,0,0,0,BN18,0,0,0,0,0,0,0,0,0,0,0,0,0,~
0)';
      BIDIRECTIONAL='TRUE';
      INPUT_LOAD='(-0.01,0.01)';
      OUTPUT_LOAD='(1.0,-1.0)';
      PINUSE='BI';
    'RSVD'<133>:
      PIN_NUMBER='(0,0,0,0,0,0,0,0,0,0,0,0,0,0,0,BP17,0,0,0,0,0,0,0,0,0,0,0,0,0,~
0)';
      BIDIRECTIONAL='TRUE';
      INPUT_LOAD='(-0.01,0.01)';
      OUTPUT_LOAD='(1.0,-1.0)';
      PINUSE='BI';
    'RSVD'<132>:
      PIN_NUMBER='(0,0,0,0,0,0,0,0,0,0,0,0,0,0,0,BP21,0,0,0,0,0,0,0,0,0,0,0,0,0,~
0)';
      BIDIRECTIONAL='TRUE';
      INPUT_LOAD='(-0.01,0.01)';
      OUTPUT_LOAD='(1.0,-1.0)';
      PINUSE='BI';
    'RSVD'<131>:
      PIN_NUMBER='(0,0,0,0,0,0,0,0,0,0,0,0,0,0,0,BR22,0,0,0,0,0,0,0,0,0,0,0,0,0,~
0)';
      BIDIRECTIONAL='TRUE';
      INPUT_LOAD='(-0.01,0.01)';
      OUTPUT_LOAD='(1.0,-1.0)';
      PINUSE='BI';
    'RSVD'<130>:
      PIN_NUMBER='(0,0,0,0,0,0,0,0,0,0,0,0,0,0,0,BR24,0,0,0,0,0,0,0,0,0,0,0,0,0,~
0)';
      BIDIRECTIONAL='TRUE';
      INPUT_LOAD='(-0.01,0.01)';
      OUTPUT_LOAD='(1.0,-1.0)';
      PINUSE='BI';
    'RSVD'<129>:
      PIN_NUMBER='(0,0,0,0,0,0,0,0,0,0,0,0,0,0,0,BU18,0,0,0,0,0,0,0,0,0,0,0,0,0,~
0)';
      BIDIRECTIONAL='TRUE';
      INPUT_LOAD='(-0.01,0.01)';
      OUTPUT_LOAD='(1.0,-1.0)';
      PINUSE='BI';
    'RSVD'<128>:
      PIN_NUMBER='(0,0,0,0,0,0,0,0,0,0,0,0,0,0,0,BU20,0,0,0,0,0,0,0,0,0,0,0,0,0,~
0)';
      BIDIRECTIONAL='TRUE';
      INPUT_LOAD='(-0.01,0.01)';
      OUTPUT_LOAD='(1.0,-1.0)';
      PINUSE='BI';
    'RSVD'<127>:
      PIN_NUMBER='(0,0,0,0,0,0,0,0,0,0,0,0,0,0,0,BU22,0,0,0,0,0,0,0,0,0,0,0,0,0,~
0)';
      BIDIRECTIONAL='TRUE';
      INPUT_LOAD='(-0.01,0.01)';
      OUTPUT_LOAD='(1.0,-1.0)';
      PINUSE='BI';
    'RSVD'<126>:
      PIN_NUMBER='(0,0,0,0,0,0,0,0,0,0,0,0,0,0,0,BV19,0,0,0,0,0,0,0,0,0,0,0,0,0,~
0)';
      BIDIRECTIONAL='TRUE';
      INPUT_LOAD='(-0.01,0.01)';
      OUTPUT_LOAD='(1.0,-1.0)';
      PINUSE='BI';
    'RSVD'<125>:
      PIN_NUMBER='(0,0,0,0,0,0,0,0,0,0,0,0,0,0,0,BV21,0,0,0,0,0,0,0,0,0,0,0,0,0,~
0)';
      BIDIRECTIONAL='TRUE';
      INPUT_LOAD='(-0.01,0.01)';
      OUTPUT_LOAD='(1.0,-1.0)';
      PINUSE='BI';
    'RSVD'<124>:
      PIN_NUMBER='(0,0,0,0,0,0,0,0,0,0,0,0,0,0,0,BV23,0,0,0,0,0,0,0,0,0,0,0,0,0,~
0)';
      BIDIRECTIONAL='TRUE';
      INPUT_LOAD='(-0.01,0.01)';
      OUTPUT_LOAD='(1.0,-1.0)';
      PINUSE='BI';
    'RSVD'<123>:
      PIN_NUMBER='(0,0,0,0,0,0,0,0,0,0,0,0,0,0,0,BW10,0,0,0,0,0,0,0,0,0,0,0,0,0,~
0)';
      BIDIRECTIONAL='TRUE';
      INPUT_LOAD='(-0.01,0.01)';
      OUTPUT_LOAD='(1.0,-1.0)';
      PINUSE='BI';
    'RSVD'<122>:
      PIN_NUMBER='(0,0,0,0,0,0,0,0,0,0,0,0,0,0,0,BW20,0,0,0,0,0,0,0,0,0,0,0,0,0,~
0)';
      BIDIRECTIONAL='TRUE';
      INPUT_LOAD='(-0.01,0.01)';
      OUTPUT_LOAD='(1.0,-1.0)';
      PINUSE='BI';
    'RSVD'<121>:
      PIN_NUMBER='(0,0,0,0,0,0,0,0,0,0,0,0,0,0,0,BW22,0,0,0,0,0,0,0,0,0,0,0,0,0,~
0)';
      BIDIRECTIONAL='TRUE';
      INPUT_LOAD='(-0.01,0.01)';
      OUTPUT_LOAD='(1.0,-1.0)';
      PINUSE='BI';
    'RSVD'<120>:
      PIN_NUMBER='(0,0,0,0,0,0,0,0,0,0,0,0,0,0,0,BY19,0,0,0,0,0,0,0,0,0,0,0,0,0,~
0)';
      BIDIRECTIONAL='TRUE';
      INPUT_LOAD='(-0.01,0.01)';
      OUTPUT_LOAD='(1.0,-1.0)';
      PINUSE='BI';
    'RSVD'<119>:
      PIN_NUMBER='(0,0,0,0,0,0,0,0,0,0,0,0,0,0,0,BY25,0,0,0,0,0,0,0,0,0,0,0,0,0,~
0)';
      BIDIRECTIONAL='TRUE';
      INPUT_LOAD='(-0.01,0.01)';
      OUTPUT_LOAD='(1.0,-1.0)';
      PINUSE='BI';
    'RSVD'<118>:
      PIN_NUMBER='(0,0,0,0,0,0,0,0,0,0,0,0,0,0,0,CA22,0,0,0,0,0,0,0,0,0,0,0,0,0,~
0)';
      BIDIRECTIONAL='TRUE';
      INPUT_LOAD='(-0.01,0.01)';
      OUTPUT_LOAD='(1.0,-1.0)';
      PINUSE='BI';
    'RSVD'<117>:
      PIN_NUMBER='(0,0,0,0,0,0,0,0,0,0,0,0,0,0,0,CA24,0,0,0,0,0,0,0,0,0,0,0,0,0,~
0)';
      BIDIRECTIONAL='TRUE';
      INPUT_LOAD='(-0.01,0.01)';
      OUTPUT_LOAD='(1.0,-1.0)';
      PINUSE='BI';
    'RSVD'<116>:
      PIN_NUMBER='(0,0,0,0,0,0,0,0,0,0,0,0,0,0,0,CB19,0,0,0,0,0,0,0,0,0,0,0,0,0,~
0)';
      BIDIRECTIONAL='TRUE';
      INPUT_LOAD='(-0.01,0.01)';
      OUTPUT_LOAD='(1.0,-1.0)';
      PINUSE='BI';
    'RSVD'<115>:
      PIN_NUMBER='(0,0,0,0,0,0,0,0,0,0,0,0,0,0,0,CB21,0,0,0,0,0,0,0,0,0,0,0,0,0,~
0)';
      BIDIRECTIONAL='TRUE';
      INPUT_LOAD='(-0.01,0.01)';
      OUTPUT_LOAD='(1.0,-1.0)';
      PINUSE='BI';
    'RSVD'<114>:
      PIN_NUMBER='(0,0,0,0,0,0,0,0,0,0,0,0,0,0,0,CB25,0,0,0,0,0,0,0,0,0,0,0,0,0,~
0)';
      BIDIRECTIONAL='TRUE';
      INPUT_LOAD='(-0.01,0.01)';
      OUTPUT_LOAD='(1.0,-1.0)';
      PINUSE='BI';
    'RSVD'<113>:
      PIN_NUMBER='(0,0,0,0,0,0,0,0,0,0,0,0,0,0,0,CB5,0,0,0,0,0,0,0,0,0,0,0,0,0,0~
)';
      BIDIRECTIONAL='TRUE';
      INPUT_LOAD='(-0.01,0.01)';
      OUTPUT_LOAD='(1.0,-1.0)';
      PINUSE='BI';
    'RSVD'<112>:
      PIN_NUMBER='(0,0,0,0,0,0,0,0,0,0,0,0,0,0,0,CC20,0,0,0,0,0,0,0,0,0,0,0,0,0,~
0)';
      BIDIRECTIONAL='TRUE';
      INPUT_LOAD='(-0.01,0.01)';
      OUTPUT_LOAD='(1.0,-1.0)';
      PINUSE='BI';
    'RSVD'<111>:
      PIN_NUMBER='(0,0,0,0,0,0,0,0,0,0,0,0,0,0,0,CC6,0,0,0,0,0,0,0,0,0,0,0,0,0,0~
)';
      BIDIRECTIONAL='TRUE';
      INPUT_LOAD='(-0.01,0.01)';
      OUTPUT_LOAD='(1.0,-1.0)';
      PINUSE='BI';
    'RSVD'<110>:
      PIN_NUMBER='(0,0,0,0,0,0,0,0,0,0,0,0,0,0,0,CD19,0,0,0,0,0,0,0,0,0,0,0,0,0,~
0)';
      BIDIRECTIONAL='TRUE';
      INPUT_LOAD='(-0.01,0.01)';
      OUTPUT_LOAD='(1.0,-1.0)';
      PINUSE='BI';
    'RSVD'<109>:
      PIN_NUMBER='(0,0,0,0,0,0,0,0,0,0,0,0,0,0,0,CD21,0,0,0,0,0,0,0,0,0,0,0,0,0,~
0)';
      BIDIRECTIONAL='TRUE';
      INPUT_LOAD='(-0.01,0.01)';
      OUTPUT_LOAD='(1.0,-1.0)';
      PINUSE='BI';
    'RSVD'<108>:
      PIN_NUMBER='(0,0,0,0,0,0,0,0,0,0,0,0,0,0,0,CD25,0,0,0,0,0,0,0,0,0,0,0,0,0,~
0)';
      BIDIRECTIONAL='TRUE';
      INPUT_LOAD='(-0.01,0.01)';
      OUTPUT_LOAD='(1.0,-1.0)';
      PINUSE='BI';
    'RSVD'<107>:
      PIN_NUMBER='(0,0,0,0,0,0,0,0,0,0,0,0,0,0,0,CE22,0,0,0,0,0,0,0,0,0,0,0,0,0,~
0)';
      BIDIRECTIONAL='TRUE';
      INPUT_LOAD='(-0.01,0.01)';
      OUTPUT_LOAD='(1.0,-1.0)';
      PINUSE='BI';
    'RSVD'<106>:
      PIN_NUMBER='(0,0,0,0,0,0,0,0,0,0,0,0,0,0,0,CE78,0,0,0,0,0,0,0,0,0,0,0,0,0,~
0)';
      BIDIRECTIONAL='TRUE';
      INPUT_LOAD='(-0.01,0.01)';
      OUTPUT_LOAD='(1.0,-1.0)';
      PINUSE='BI';
    'RSVD'<105>:
      PIN_NUMBER='(0,0,0,0,0,0,0,0,0,0,0,0,0,0,0,CE80,0,0,0,0,0,0,0,0,0,0,0,0,0,~
0)';
      BIDIRECTIONAL='TRUE';
      INPUT_LOAD='(-0.01,0.01)';
      OUTPUT_LOAD='(1.0,-1.0)';
      PINUSE='BI';
    'RSVD'<104>:
      PIN_NUMBER='(0,0,0,0,0,0,0,0,0,0,0,0,0,0,0,CF19,0,0,0,0,0,0,0,0,0,0,0,0,0,~
0)';
      BIDIRECTIONAL='TRUE';
      INPUT_LOAD='(-0.01,0.01)';
      OUTPUT_LOAD='(1.0,-1.0)';
      PINUSE='BI';
    'RSVD'<103>:
      PIN_NUMBER='(0,0,0,0,0,0,0,0,0,0,0,0,0,0,0,CF21,0,0,0,0,0,0,0,0,0,0,0,0,0,~
0)';
      BIDIRECTIONAL='TRUE';
      INPUT_LOAD='(-0.01,0.01)';
      OUTPUT_LOAD='(1.0,-1.0)';
      PINUSE='BI';
    'RSVD'<102>:
      PIN_NUMBER='(0,0,0,0,0,0,0,0,0,0,0,0,0,0,0,CF23,0,0,0,0,0,0,0,0,0,0,0,0,0,~
0)';
      BIDIRECTIONAL='TRUE';
      INPUT_LOAD='(-0.01,0.01)';
      OUTPUT_LOAD='(1.0,-1.0)';
      PINUSE='BI';
    'RSVD'<101>:
      PIN_NUMBER='(0,0,0,0,0,0,0,0,0,0,0,0,0,0,0,CF79,0,0,0,0,0,0,0,0,0,0,0,0,0,~
0)';
      BIDIRECTIONAL='TRUE';
      INPUT_LOAD='(-0.01,0.01)';
      OUTPUT_LOAD='(1.0,-1.0)';
      PINUSE='BI';
    'RSVD'<100>:
      PIN_NUMBER='(0,0,0,0,0,0,0,0,0,0,0,0,0,0,0,CF81,0,0,0,0,0,0,0,0,0,0,0,0,0,~
0)';
      BIDIRECTIONAL='TRUE';
      INPUT_LOAD='(-0.01,0.01)';
      OUTPUT_LOAD='(1.0,-1.0)';
      PINUSE='BI';
    'RSVD'<99>:
      PIN_NUMBER='(0,0,0,0,0,0,0,0,0,0,0,0,0,0,0,CG10,0,0,0,0,0,0,0,0,0,0,0,0,0,~
0)';
      BIDIRECTIONAL='TRUE';
      INPUT_LOAD='(-0.01,0.01)';
      OUTPUT_LOAD='(1.0,-1.0)';
      PINUSE='BI';
    'RSVD'<98>:
      PIN_NUMBER='(0,0,0,0,0,0,0,0,0,0,0,0,0,0,0,CG20,0,0,0,0,0,0,0,0,0,0,0,0,0,~
0)';
      BIDIRECTIONAL='TRUE';
      INPUT_LOAD='(-0.01,0.01)';
      OUTPUT_LOAD='(1.0,-1.0)';
      PINUSE='BI';
    'RSVD'<97>:
      PIN_NUMBER='(0,0,0,0,0,0,0,0,0,0,0,0,0,0,0,CG24,0,0,0,0,0,0,0,0,0,0,0,0,0,~
0)';
      BIDIRECTIONAL='TRUE';
      INPUT_LOAD='(-0.01,0.01)';
      OUTPUT_LOAD='(1.0,-1.0)';
      PINUSE='BI';
    'RSVD'<96>:
      PIN_NUMBER='(0,0,0,0,0,0,0,0,0,0,0,0,0,0,0,CG26,0,0,0,0,0,0,0,0,0,0,0,0,0,~
0)';
      BIDIRECTIONAL='TRUE';
      INPUT_LOAD='(-0.01,0.01)';
      OUTPUT_LOAD='(1.0,-1.0)';
      PINUSE='BI';
    'RSVD'<95>:
      PIN_NUMBER='(0,0,0,0,0,0,0,0,0,0,0,0,0,0,0,CG78,0,0,0,0,0,0,0,0,0,0,0,0,0,~
0)';
      BIDIRECTIONAL='TRUE';
      INPUT_LOAD='(-0.01,0.01)';
      OUTPUT_LOAD='(1.0,-1.0)';
      PINUSE='BI';
    'RSVD'<94>:
      PIN_NUMBER='(0,0,0,0,0,0,0,0,0,0,0,0,0,0,0,CG82,0,0,0,0,0,0,0,0,0,0,0,0,0,~
0)';
      BIDIRECTIONAL='TRUE';
      INPUT_LOAD='(-0.01,0.01)';
      OUTPUT_LOAD='(1.0,-1.0)';
      PINUSE='BI';
    'RSVD'<93>:
      PIN_NUMBER='(0,0,0,0,0,0,0,0,0,0,0,0,0,0,0,CH21,0,0,0,0,0,0,0,0,0,0,0,0,0,~
0)';
      BIDIRECTIONAL='TRUE';
      INPUT_LOAD='(-0.01,0.01)';
      OUTPUT_LOAD='(1.0,-1.0)';
      PINUSE='BI';
    'RSVD'<92>:
      PIN_NUMBER='(0,0,0,0,0,0,0,0,0,0,0,0,0,0,0,CH23,0,0,0,0,0,0,0,0,0,0,0,0,0,~
0)';
      BIDIRECTIONAL='TRUE';
      INPUT_LOAD='(-0.01,0.01)';
      OUTPUT_LOAD='(1.0,-1.0)';
      PINUSE='BI';
    'RSVD'<91>:
      PIN_NUMBER='(0,0,0,0,0,0,0,0,0,0,0,0,0,0,0,0,CH25,0,0,0,0,0,0,0,0,0,0,0,0,~
0)';
      BIDIRECTIONAL='TRUE';
      INPUT_LOAD='(-0.01,0.01)';
      OUTPUT_LOAD='(1.0,-1.0)';
      PINUSE='BI';
    'RSVD'<90>:
      PIN_NUMBER='(0,0,0,0,0,0,0,0,0,0,0,0,0,0,0,0,CH77,0,0,0,0,0,0,0,0,0,0,0,0,~
0)';
      BIDIRECTIONAL='TRUE';
      INPUT_LOAD='(-0.01,0.01)';
      OUTPUT_LOAD='(1.0,-1.0)';
      PINUSE='BI';
    'RSVD'<89>:
      PIN_NUMBER='(0,0,0,0,0,0,0,0,0,0,0,0,0,0,0,0,CJ20,0,0,0,0,0,0,0,0,0,0,0,0,~
0)';
      BIDIRECTIONAL='TRUE';
      INPUT_LOAD='(-0.01,0.01)';
      OUTPUT_LOAD='(1.0,-1.0)';
      PINUSE='BI';
    'RSVD'<88>:
      PIN_NUMBER='(0,0,0,0,0,0,0,0,0,0,0,0,0,0,0,0,CJ22,0,0,0,0,0,0,0,0,0,0,0,0,~
0)';
      BIDIRECTIONAL='TRUE';
      INPUT_LOAD='(-0.01,0.01)';
      OUTPUT_LOAD='(1.0,-1.0)';
      PINUSE='BI';
    'RSVD'<87>:
      PIN_NUMBER='(0,0,0,0,0,0,0,0,0,0,0,0,0,0,0,0,CJ24,0,0,0,0,0,0,0,0,0,0,0,0,~
0)';
      BIDIRECTIONAL='TRUE';
      INPUT_LOAD='(-0.01,0.01)';
      OUTPUT_LOAD='(1.0,-1.0)';
      PINUSE='BI';
    'RSVD'<86>:
      PIN_NUMBER='(0,0,0,0,0,0,0,0,0,0,0,0,0,0,0,0,CJ26,0,0,0,0,0,0,0,0,0,0,0,0,~
0)';
      BIDIRECTIONAL='TRUE';
      INPUT_LOAD='(-0.01,0.01)';
      OUTPUT_LOAD='(1.0,-1.0)';
      PINUSE='BI';
    'RSVD'<85>:
      PIN_NUMBER='(0,0,0,0,0,0,0,0,0,0,0,0,0,0,0,0,CK19,0,0,0,0,0,0,0,0,0,0,0,0,~
0)';
      BIDIRECTIONAL='TRUE';
      INPUT_LOAD='(-0.01,0.01)';
      OUTPUT_LOAD='(1.0,-1.0)';
      PINUSE='BI';
    'RSVD'<84>:
      PIN_NUMBER='(0,0,0,0,0,0,0,0,0,0,0,0,0,0,0,0,CK23,0,0,0,0,0,0,0,0,0,0,0,0,~
0)';
      BIDIRECTIONAL='TRUE';
      INPUT_LOAD='(-0.01,0.01)';
      OUTPUT_LOAD='(1.0,-1.0)';
      PINUSE='BI';
    'RSVD'<83>:
      PIN_NUMBER='(0,0,0,0,0,0,0,0,0,0,0,0,0,0,0,0,CK25,0,0,0,0,0,0,0,0,0,0,0,0,~
0)';
      BIDIRECTIONAL='TRUE';
      INPUT_LOAD='(-0.01,0.01)';
      OUTPUT_LOAD='(1.0,-1.0)';
      PINUSE='BI';
    'RSVD'<82>:
      PIN_NUMBER='(0,0,0,0,0,0,0,0,0,0,0,0,0,0,0,0,CK77,0,0,0,0,0,0,0,0,0,0,0,0,~
0)';
      BIDIRECTIONAL='TRUE';
      INPUT_LOAD='(-0.01,0.01)';
      OUTPUT_LOAD='(1.0,-1.0)';
      PINUSE='BI';
    'RSVD'<81>:
      PIN_NUMBER='(0,0,0,0,0,0,0,0,0,0,0,0,0,0,0,0,CL24,0,0,0,0,0,0,0,0,0,0,0,0,~
0)';
      BIDIRECTIONAL='TRUE';
      INPUT_LOAD='(-0.01,0.01)';
      OUTPUT_LOAD='(1.0,-1.0)';
      PINUSE='BI';
    'RSVD'<80>:
      PIN_NUMBER='(0,0,0,0,0,0,0,0,0,0,0,0,0,0,0,0,0,0,0,0,0,CL26,0,0,0,0,0,0,0,~
0)';
      BIDIRECTIONAL='TRUE';
      INPUT_LOAD='(-0.01,0.01)';
      OUTPUT_LOAD='(1.0,-1.0)';
      PINUSE='BI';
    'RSVD'<79>:
      PIN_NUMBER='(0,0,0,0,0,0,0,0,0,0,0,0,0,0,0,0,0,0,0,0,0,CM23,0,0,0,0,0,0,0,~
0)';
      BIDIRECTIONAL='TRUE';
      INPUT_LOAD='(-0.01,0.01)';
      OUTPUT_LOAD='(1.0,-1.0)';
      PINUSE='BI';
    'RSVD'<78>:
      PIN_NUMBER='(0,0,0,0,0,0,0,0,0,0,0,0,0,0,0,0,0,0,0,0,0,CM25,0,0,0,0,0,0,0,~
0)';
      BIDIRECTIONAL='TRUE';
      INPUT_LOAD='(-0.01,0.01)';
      OUTPUT_LOAD='(1.0,-1.0)';
      PINUSE='BI';
    'RSVD'<77>:
      PIN_NUMBER='(0,0,0,0,0,0,0,0,0,0,0,0,0,0,0,0,0,0,0,0,0,CN22,0,0,0,0,0,0,0,~
0)';
      BIDIRECTIONAL='TRUE';
      INPUT_LOAD='(-0.01,0.01)';
      OUTPUT_LOAD='(1.0,-1.0)';
      PINUSE='BI';
    'RSVD'<76>:
      PIN_NUMBER='(0,0,0,0,0,0,0,0,0,0,0,0,0,0,0,0,0,0,0,0,0,CN24,0,0,0,0,0,0,0,~
0)';
      BIDIRECTIONAL='TRUE';
      INPUT_LOAD='(-0.01,0.01)';
      OUTPUT_LOAD='(1.0,-1.0)';
      PINUSE='BI';
    'RSVD'<75>:
      PIN_NUMBER='(0,0,0,0,0,0,0,0,0,0,0,0,0,0,0,0,0,0,0,0,0,CN28,0,0,0,0,0,0,0,~
0)';
      BIDIRECTIONAL='TRUE';
      INPUT_LOAD='(-0.01,0.01)';
      OUTPUT_LOAD='(1.0,-1.0)';
      PINUSE='BI';
    'RSVD'<74>:
      PIN_NUMBER='(0,0,0,0,0,0,0,0,0,0,0,0,0,0,0,0,0,0,0,0,0,CP23,0,0,0,0,0,0,0,~
0)';
      BIDIRECTIONAL='TRUE';
      INPUT_LOAD='(-0.01,0.01)';
      OUTPUT_LOAD='(1.0,-1.0)';
      PINUSE='BI';
    'RSVD'<73>:
      PIN_NUMBER='(0,0,0,0,0,0,0,0,0,0,0,0,0,0,0,0,0,0,0,0,0,CP31,0,0,0,0,0,0,0,~
0)';
      BIDIRECTIONAL='TRUE';
      INPUT_LOAD='(-0.01,0.01)';
      OUTPUT_LOAD='(1.0,-1.0)';
      PINUSE='BI';
    'RSVD'<72>:
      PIN_NUMBER='(0,0,0,0,0,0,0,0,0,0,0,0,0,0,0,0,0,0,0,0,0,CR60,0,0,0,0,0,0,0,~
0)';
      BIDIRECTIONAL='TRUE';
      INPUT_LOAD='(-0.01,0.01)';
      OUTPUT_LOAD='(1.0,-1.0)';
      PINUSE='BI';
    'RSVD'<71>:
      PIN_NUMBER='(0,0,0,0,0,0,0,0,0,0,0,0,0,0,0,0,0,0,0,0,0,CT23,0,0,0,0,0,0,0,~
0)';
      BIDIRECTIONAL='TRUE';
      INPUT_LOAD='(-0.01,0.01)';
      OUTPUT_LOAD='(1.0,-1.0)';
      PINUSE='BI';
    'RSVD'<70>:
      PIN_NUMBER='(0,0,0,0,0,0,0,0,0,0,0,0,0,0,0,0,0,0,0,0,0,CT5,0,0,0,0,0,0,0,0~
)';
      BIDIRECTIONAL='TRUE';
      INPUT_LOAD='(-0.01,0.01)';
      OUTPUT_LOAD='(1.0,-1.0)';
      PINUSE='BI';
    'RSVD'<69>:
      PIN_NUMBER='(0,0,0,0,0,0,0,0,0,0,0,0,0,0,0,0,0,0,0,0,0,CT69,0,0,0,0,0,0,0,~
0)';
      BIDIRECTIONAL='TRUE';
      INPUT_LOAD='(-0.01,0.01)';
      OUTPUT_LOAD='(1.0,-1.0)';
      PINUSE='BI';
    'RSVD'<68>:
      PIN_NUMBER='(0,0,0,0,0,0,0,0,0,0,0,0,0,0,0,0,0,0,0,0,0,CU24,0,0,0,0,0,0,0,~
0)';
      BIDIRECTIONAL='TRUE';
      INPUT_LOAD='(-0.01,0.01)';
      OUTPUT_LOAD='(1.0,-1.0)';
      PINUSE='BI';
    'RSVD'<67>:
      PIN_NUMBER='(0,0,0,0,0,0,0,0,0,0,0,0,0,0,0,0,0,0,0,0,0,CU6,0,0,0,0,0,0,0,0~
)';
      BIDIRECTIONAL='TRUE';
      INPUT_LOAD='(-0.01,0.01)';
      OUTPUT_LOAD='(1.0,-1.0)';
      PINUSE='BI';
    'RSVD'<66>:
      PIN_NUMBER='(0,0,0,0,0,0,0,0,0,0,0,0,0,0,0,0,0,0,0,0,0,CU60,0,0,0,0,0,0,0,~
0)';
      BIDIRECTIONAL='TRUE';
      INPUT_LOAD='(-0.01,0.01)';
      OUTPUT_LOAD='(1.0,-1.0)';
      PINUSE='BI';
    'RSVD'<65>:
      PIN_NUMBER='(0,0,0,0,0,0,0,0,0,0,0,0,0,0,0,0,0,0,0,0,0,CV23,0,0,0,0,0,0,0,~
0)';
      BIDIRECTIONAL='TRUE';
      INPUT_LOAD='(-0.01,0.01)';
      OUTPUT_LOAD='(1.0,-1.0)';
      PINUSE='BI';
    'RSVD'<64>:
      PIN_NUMBER='(0,0,0,0,0,0,0,0,0,0,0,0,0,0,0,0,0,0,0,0,0,CV69,0,0,0,0,0,0,0,~
0)';
      BIDIRECTIONAL='TRUE';
      INPUT_LOAD='(-0.01,0.01)';
      OUTPUT_LOAD='(1.0,-1.0)';
      PINUSE='BI';
    'RSVD'<63>:
      PIN_NUMBER='(0,0,0,0,0,0,0,0,0,0,0,0,0,0,0,0,0,0,0,0,0,CW22,0,0,0,0,0,0,0,~
0)';
      BIDIRECTIONAL='TRUE';
      INPUT_LOAD='(-0.01,0.01)';
      OUTPUT_LOAD='(1.0,-1.0)';
      PINUSE='BI';
    'RSVD'<62>:
      PIN_NUMBER='(0,0,0,0,0,0,0,0,0,0,0,0,0,0,0,0,0,0,0,0,0,CW24,0,0,0,0,0,0,0,~
0)';
      BIDIRECTIONAL='TRUE';
      INPUT_LOAD='(-0.01,0.01)';
      OUTPUT_LOAD='(1.0,-1.0)';
      PINUSE='BI';
    'RSVD'<61>:
      PIN_NUMBER='(0,0,0,0,0,0,0,0,0,0,0,0,0,0,0,0,0,0,0,0,0,CW60,0,0,0,0,0,0,0,~
0)';
      BIDIRECTIONAL='TRUE';
      INPUT_LOAD='(-0.01,0.01)';
      OUTPUT_LOAD='(1.0,-1.0)';
      PINUSE='BI';
    'RSVD'<60>:
      PIN_NUMBER='(0,0,0,0,0,0,0,0,0,0,0,0,0,0,0,0,0,0,0,0,0,CW62,0,0,0,0,0,0,0,~
0)';
      BIDIRECTIONAL='TRUE';
      INPUT_LOAD='(-0.01,0.01)';
      OUTPUT_LOAD='(1.0,-1.0)';
      PINUSE='BI';
    'RSVD'<59>:
      PIN_NUMBER='(0,0,0,0,0,0,0,0,0,0,0,0,0,0,0,0,0,0,0,0,0,CY23,0,0,0,0,0,0,0,~
0)';
      BIDIRECTIONAL='TRUE';
      INPUT_LOAD='(-0.01,0.01)';
      OUTPUT_LOAD='(1.0,-1.0)';
      PINUSE='BI';
    'RSVD'<58>:
      PIN_NUMBER='(0,0,0,0,0,0,0,0,0,0,0,0,0,0,0,0,0,0,0,0,0,CY25,0,0,0,0,0,0,0,~
0)';
      BIDIRECTIONAL='TRUE';
      INPUT_LOAD='(-0.01,0.01)';
      OUTPUT_LOAD='(1.0,-1.0)';
      PINUSE='BI';
    'RSVD'<57>:
      PIN_NUMBER='(0,0,0,0,0,0,0,0,0,0,0,0,0,0,0,0,0,0,0,0,0,CY39,0,0,0,0,0,0,0,~
0)';
      BIDIRECTIONAL='TRUE';
      INPUT_LOAD='(-0.01,0.01)';
      OUTPUT_LOAD='(1.0,-1.0)';
      PINUSE='BI';
    'RSVD'<56>:
      PIN_NUMBER='(0,0,0,0,0,0,0,0,0,0,0,0,0,0,0,0,0,0,0,0,0,CY53,0,0,0,0,0,0,0,~
0)';
      BIDIRECTIONAL='TRUE';
      INPUT_LOAD='(-0.01,0.01)';
      OUTPUT_LOAD='(1.0,-1.0)';
      PINUSE='BI';
    'RSVD'<55>:
      PIN_NUMBER='(0,0,0,0,0,0,0,0,0,0,0,0,0,0,0,0,0,0,0,0,0,CY57,0,0,0,0,0,0,0,~
0)';
      BIDIRECTIONAL='TRUE';
      INPUT_LOAD='(-0.01,0.01)';
      OUTPUT_LOAD='(1.0,-1.0)';
      PINUSE='BI';
    'RSVD'<54>:
      PIN_NUMBER='(0,0,0,0,0,0,0,0,0,0,0,0,0,0,0,0,0,0,0,0,0,CY63,0,0,0,0,0,0,0,~
0)';
      BIDIRECTIONAL='TRUE';
      INPUT_LOAD='(-0.01,0.01)';
      OUTPUT_LOAD='(1.0,-1.0)';
      PINUSE='BI';
    'RSVD'<53>:
      PIN_NUMBER='(0,0,0,0,0,0,0,0,0,0,0,0,0,0,0,0,0,0,0,0,0,CY73,0,0,0,0,0,0,0,~
0)';
      BIDIRECTIONAL='TRUE';
      INPUT_LOAD='(-0.01,0.01)';
      OUTPUT_LOAD='(1.0,-1.0)';
      PINUSE='BI';
    'RSVD'<52>:
      PIN_NUMBER='(0,0,0,0,0,0,0,0,0,0,0,0,0,0,0,0,0,0,0,0,0,DA24,0,0,0,0,0,0,0,~
0)';
      BIDIRECTIONAL='TRUE';
      INPUT_LOAD='(-0.01,0.01)';
      OUTPUT_LOAD='(1.0,-1.0)';
      PINUSE='BI';
    'RSVD'<51>:
      PIN_NUMBER='(0,0,0,0,0,0,0,0,0,0,0,0,0,0,0,0,0,0,0,0,0,DA40,0,0,0,0,0,0,0,~
0)';
      BIDIRECTIONAL='TRUE';
      INPUT_LOAD='(-0.01,0.01)';
      OUTPUT_LOAD='(1.0,-1.0)';
      PINUSE='BI';
    'RSVD'<50>:
      PIN_NUMBER='(0,0,0,0,0,0,0,0,0,0,0,0,0,0,0,0,0,0,0,0,0,DA52,0,0,0,0,0,0,0,~
0)';
      BIDIRECTIONAL='TRUE';
      INPUT_LOAD='(-0.01,0.01)';
      OUTPUT_LOAD='(1.0,-1.0)';
      PINUSE='BI';
    'RSVD'<49>:
      PIN_NUMBER='(0,0,0,0,0,0,0,0,0,0,0,0,0,0,0,0,0,0,0,0,0,DA54,0,0,0,0,0,0,0,~
0)';
      BIDIRECTIONAL='TRUE';
      INPUT_LOAD='(-0.01,0.01)';
      OUTPUT_LOAD='(1.0,-1.0)';
      PINUSE='BI';
    'RSVD'<48>:
      PIN_NUMBER='(0,0,0,0,0,0,0,0,0,0,0,0,0,0,0,0,0,0,0,0,0,DA56,0,0,0,0,0,0,0,~
0)';
      BIDIRECTIONAL='TRUE';
      INPUT_LOAD='(-0.01,0.01)';
      OUTPUT_LOAD='(1.0,-1.0)';
      PINUSE='BI';
    'RSVD'<47>:
      PIN_NUMBER='(0,0,0,0,0,0,0,0,0,0,0,0,0,0,0,0,0,0,0,0,0,DC46,0,0,0,0,0,0,0,~
0)';
      BIDIRECTIONAL='TRUE';
      INPUT_LOAD='(-0.01,0.01)';
      OUTPUT_LOAD='(1.0,-1.0)';
      PINUSE='BI';
    'RSVD'<46>:
      PIN_NUMBER='(0,0,0,0,0,0,0,0,0,0,0,0,0,0,0,0,0,0,0,0,0,DC52,0,0,0,0,0,0,0,~
0)';
      BIDIRECTIONAL='TRUE';
      INPUT_LOAD='(-0.01,0.01)';
      OUTPUT_LOAD='(1.0,-1.0)';
      PINUSE='BI';
    'RSVD'<45>:
      PIN_NUMBER='(0,0,0,0,0,0,0,0,0,0,0,0,0,0,0,0,0,0,0,0,0,DD51,0,0,0,0,0,0,0,~
0)';
      BIDIRECTIONAL='TRUE';
      INPUT_LOAD='(-0.01,0.01)';
      OUTPUT_LOAD='(1.0,-1.0)';
      PINUSE='BI';
    'RSVD'<44>:
      PIN_NUMBER='(0,0,0,0,0,0,0,0,0,0,0,0,0,0,0,0,0,0,0,0,0,DG36,0,0,0,0,0,0,0,~
0)';
      BIDIRECTIONAL='TRUE';
      INPUT_LOAD='(-0.01,0.01)';
      OUTPUT_LOAD='(1.0,-1.0)';
      PINUSE='BI';
    'RSVD'<43>:
      PIN_NUMBER='(0,0,0,0,0,0,0,0,0,0,0,0,0,0,0,0,0,0,0,0,0,DG64,0,0,0,0,0,0,0,~
0)';
      BIDIRECTIONAL='TRUE';
      INPUT_LOAD='(-0.01,0.01)';
      OUTPUT_LOAD='(1.0,-1.0)';
      PINUSE='BI';
    'RSVD'<42>:
      PIN_NUMBER='(0,0,0,0,0,0,0,0,0,0,0,0,0,0,0,0,0,0,0,0,0,DH65,0,0,0,0,0,0,0,~
0)';
      BIDIRECTIONAL='TRUE';
      INPUT_LOAD='(-0.01,0.01)';
      OUTPUT_LOAD='(1.0,-1.0)';
      PINUSE='BI';
    'RSVD'<41>:
      PIN_NUMBER='(0,0,0,0,0,0,0,0,0,0,0,0,0,0,0,0,0,0,0,0,0,DJ36,0,0,0,0,0,0,0,~
0)';
      BIDIRECTIONAL='TRUE';
      INPUT_LOAD='(-0.01,0.01)';
      OUTPUT_LOAD='(1.0,-1.0)';
      PINUSE='BI';
    'RSVD'<40>:
      PIN_NUMBER='(0,0,0,0,0,0,0,0,0,0,0,0,0,0,0,0,0,0,0,0,0,DJ66,0,0,0,0,0,0,0,~
0)';
      BIDIRECTIONAL='TRUE';
      INPUT_LOAD='(-0.01,0.01)';
      OUTPUT_LOAD='(1.0,-1.0)';
      PINUSE='BI';
    'RSVD'<39>:
      PIN_NUMBER='(0,0,0,0,0,0,0,0,0,0,0,0,0,0,0,0,0,0,0,0,0,DK15,0,0,0,0,0,0,0,~
0)';
      BIDIRECTIONAL='TRUE';
      INPUT_LOAD='(-0.01,0.01)';
      OUTPUT_LOAD='(1.0,-1.0)';
      PINUSE='BI';
    'RSVD'<38>:
      PIN_NUMBER='(0,0,0,0,0,0,0,0,0,0,0,0,0,0,0,0,0,0,0,0,0,DK37,0,0,0,0,0,0,0,~
0)';
      BIDIRECTIONAL='TRUE';
      INPUT_LOAD='(-0.01,0.01)';
      OUTPUT_LOAD='(1.0,-1.0)';
      PINUSE='BI';
    'RSVD'<37>:
      PIN_NUMBER='(0,0,0,0,0,0,0,0,0,0,0,0,0,0,0,0,0,0,0,0,0,DK65,0,0,0,0,0,0,0,~
0)';
      BIDIRECTIONAL='TRUE';
      INPUT_LOAD='(-0.01,0.01)';
      OUTPUT_LOAD='(1.0,-1.0)';
      PINUSE='BI';
    'RSVD'<36>:
      PIN_NUMBER='(0,0,0,0,0,0,0,0,0,0,0,0,0,0,0,0,0,0,0,0,0,DK67,0,0,0,0,0,0,0,~
0)';
      BIDIRECTIONAL='TRUE';
      INPUT_LOAD='(-0.01,0.01)';
      OUTPUT_LOAD='(1.0,-1.0)';
      PINUSE='BI';
    'RSVD'<35>:
      PIN_NUMBER='(0,0,0,0,0,0,0,0,0,0,0,0,0,0,0,0,0,0,0,0,0,DL38,0,0,0,0,0,0,0,~
0)';
      BIDIRECTIONAL='TRUE';
      INPUT_LOAD='(-0.01,0.01)';
      OUTPUT_LOAD='(1.0,-1.0)';
      PINUSE='BI';
    'RSVD'<34>:
      PIN_NUMBER='(0,0,0,0,0,0,0,0,0,0,0,0,0,0,0,0,0,0,0,0,0,DL66,0,0,0,0,0,0,0,~
0)';
      BIDIRECTIONAL='TRUE';
      INPUT_LOAD='(-0.01,0.01)';
      OUTPUT_LOAD='(1.0,-1.0)';
      PINUSE='BI';
    'RSVD'<33>:
      PIN_NUMBER='(0,0,0,0,0,0,0,0,0,0,0,0,0,0,0,0,0,0,0,0,0,DM67,0,0,0,0,0,0,0,~
0)';
      BIDIRECTIONAL='TRUE';
      INPUT_LOAD='(-0.01,0.01)';
      OUTPUT_LOAD='(1.0,-1.0)';
      PINUSE='BI';
    'RSVD'<32>:
      PIN_NUMBER='(0,0,0,0,0,0,0,0,0,0,0,0,0,0,0,0,0,0,0,0,0,DN62,0,0,0,0,0,0,0,~
0)';
      BIDIRECTIONAL='TRUE';
      INPUT_LOAD='(-0.01,0.01)';
      OUTPUT_LOAD='(1.0,-1.0)';
      PINUSE='BI';
    'RSVD'<31>:
      PIN_NUMBER='(0,0,0,0,0,0,0,0,0,0,0,0,0,0,0,0,0,0,0,0,0,DN66,0,0,0,0,0,0,0,~
0)';
      BIDIRECTIONAL='TRUE';
      INPUT_LOAD='(-0.01,0.01)';
      OUTPUT_LOAD='(1.0,-1.0)';
      PINUSE='BI';
    'RSVD'<30>:
      PIN_NUMBER='(0,0,0,0,0,0,0,0,0,0,0,0,0,0,0,0,0,0,0,0,0,DP17,0,0,0,0,0,0,0,~
0)';
      BIDIRECTIONAL='TRUE';
      INPUT_LOAD='(-0.01,0.01)';
      OUTPUT_LOAD='(1.0,-1.0)';
      PINUSE='BI';
    'RSVD'<29>:
      PIN_NUMBER='(0,0,0,0,0,0,0,0,0,0,0,0,0,0,0,0,0,0,0,0,0,DP65,0,0,0,0,0,0,0,~
0)';
      BIDIRECTIONAL='TRUE';
      INPUT_LOAD='(-0.01,0.01)';
      OUTPUT_LOAD='(1.0,-1.0)';
      PINUSE='BI';
    'RSVD'<28>:
      PIN_NUMBER='(0,0,0,0,0,0,0,0,0,0,0,0,0,0,0,0,0,0,0,0,0,DR44,0,0,0,0,0,0,0,~
0)';
      BIDIRECTIONAL='TRUE';
      INPUT_LOAD='(-0.01,0.01)';
      OUTPUT_LOAD='(1.0,-1.0)';
      PINUSE='BI';
    'RSVD'<27>:
      PIN_NUMBER='(0,0,0,0,0,0,0,0,0,0,0,0,0,0,0,0,0,0,0,0,0,DT71,0,0,0,0,0,0,0,~
0)';
      BIDIRECTIONAL='TRUE';
      INPUT_LOAD='(-0.01,0.01)';
      OUTPUT_LOAD='(1.0,-1.0)';
      PINUSE='BI';
    'RSVD'<26>:
      PIN_NUMBER='(0,0,0,0,0,0,0,0,0,0,0,0,0,0,0,0,0,0,0,0,0,DU44,0,0,0,0,0,0,0,~
0)';
      BIDIRECTIONAL='TRUE';
      INPUT_LOAD='(-0.01,0.01)';
      OUTPUT_LOAD='(1.0,-1.0)';
      PINUSE='BI';
    'RSVD'<25>:
      PIN_NUMBER='(0,0,0,0,0,0,0,0,0,0,0,0,0,0,0,0,0,0,0,0,0,DV61,0,0,0,0,0,0,0,~
0)';
      BIDIRECTIONAL='TRUE';
      INPUT_LOAD='(-0.01,0.01)';
      OUTPUT_LOAD='(1.0,-1.0)';
      PINUSE='BI';
    'RSVD'<24>:
      PIN_NUMBER='(0,0,0,0,0,0,0,0,0,0,0,0,0,0,0,0,0,0,0,0,0,DV71,0,0,0,0,0,0,0,~
0)';
      BIDIRECTIONAL='TRUE';
      INPUT_LOAD='(-0.01,0.01)';
      OUTPUT_LOAD='(1.0,-1.0)';
      PINUSE='BI';
    'RSVD'<23>:
      PIN_NUMBER='(0,0,0,0,0,0,0,0,0,0,0,0,0,0,0,0,0,0,0,0,0,DW44,0,0,0,0,0,0,0,~
0)';
      BIDIRECTIONAL='TRUE';
      INPUT_LOAD='(-0.01,0.01)';
      OUTPUT_LOAD='(1.0,-1.0)';
      PINUSE='BI';
    'RSVD'<22>:
      PIN_NUMBER='(0,0,0,0,0,0,0,0,0,0,0,0,0,0,0,0,0,0,0,0,0,DW46,0,0,0,0,0,0,0,~
0)';
      BIDIRECTIONAL='TRUE';
      INPUT_LOAD='(-0.01,0.01)';
      OUTPUT_LOAD='(1.0,-1.0)';
      PINUSE='BI';
    'RSVD'<21>:
      PIN_NUMBER='(0,0,0,0,0,0,0,0,0,0,0,0,0,0,0,0,0,0,0,0,0,DY3,0,0,0,0,0,0,0,0~
)';
      BIDIRECTIONAL='TRUE';
      INPUT_LOAD='(-0.01,0.01)';
      OUTPUT_LOAD='(1.0,-1.0)';
      PINUSE='BI';
    'RSVD'<20>:
      PIN_NUMBER='(0,0,0,0,0,0,0,0,0,0,0,0,0,0,0,0,0,0,0,0,0,EA4,0,0,0,0,0,0,0,0~
)';
      BIDIRECTIONAL='TRUE';
      INPUT_LOAD='(-0.01,0.01)';
      OUTPUT_LOAD='(1.0,-1.0)';
      PINUSE='BI';
    'RSVD'<19>:
      PIN_NUMBER='(0,0,0,0,0,0,0,0,0,0,0,0,0,0,0,0,0,0,0,0,0,EA44,0,0,0,0,0,0,0,~
0)';
      BIDIRECTIONAL='TRUE';
      INPUT_LOAD='(-0.01,0.01)';
      OUTPUT_LOAD='(1.0,-1.0)';
      PINUSE='BI';
    'RSVD'<18>:
      PIN_NUMBER='(0,0,0,0,0,0,0,0,0,0,0,0,0,0,0,0,0,0,0,0,0,EB3,0,0,0,0,0,0,0,0~
)';
      BIDIRECTIONAL='TRUE';
      INPUT_LOAD='(-0.01,0.01)';
      OUTPUT_LOAD='(1.0,-1.0)';
      PINUSE='BI';
    'RSVD'<17>:
      PIN_NUMBER='(0,0,0,0,0,0,0,0,0,0,0,0,0,0,0,0,0,0,0,0,0,EB5,0,0,0,0,0,0,0,0~
)';
      BIDIRECTIONAL='TRUE';
      INPUT_LOAD='(-0.01,0.01)';
      OUTPUT_LOAD='(1.0,-1.0)';
      PINUSE='BI';
    'RSVD'<16>:
      PIN_NUMBER='(0,0,0,0,0,0,0,0,0,0,0,0,0,0,0,0,0,0,0,0,0,EB85,0,0,0,0,0,0,0,~
0)';
      BIDIRECTIONAL='TRUE';
      INPUT_LOAD='(-0.01,0.01)';
      OUTPUT_LOAD='(1.0,-1.0)';
      PINUSE='BI';
    'RSVD'<15>:
      PIN_NUMBER='(0,0,0,0,0,0,0,0,0,0,0,0,0,0,0,0,0,0,0,0,0,EC16,0,0,0,0,0,0,0,~
0)';
      BIDIRECTIONAL='TRUE';
      INPUT_LOAD='(-0.01,0.01)';
      OUTPUT_LOAD='(1.0,-1.0)';
      PINUSE='BI';
    'RSVD'<14>:
      PIN_NUMBER='(0,0,0,0,0,0,0,0,0,0,0,0,0,0,0,0,0,0,0,0,0,EC4,0,0,0,0,0,0,0,0~
)';
      BIDIRECTIONAL='TRUE';
      INPUT_LOAD='(-0.01,0.01)';
      OUTPUT_LOAD='(1.0,-1.0)';
      PINUSE='BI';
    'RSVD'<13>:
      PIN_NUMBER='(0,0,0,0,0,0,0,0,0,0,0,0,0,0,0,0,0,0,0,0,0,EC44,0,0,0,0,0,0,0,~
0)';
      BIDIRECTIONAL='TRUE';
      INPUT_LOAD='(-0.01,0.01)';
      OUTPUT_LOAD='(1.0,-1.0)';
      PINUSE='BI';
    'RSVD'<12>:
      PIN_NUMBER='(0,0,0,0,0,0,0,0,0,0,0,0,0,0,0,0,0,0,0,0,0,EC84,0,0,0,0,0,0,0,~
0)';
      BIDIRECTIONAL='TRUE';
      INPUT_LOAD='(-0.01,0.01)';
      OUTPUT_LOAD='(1.0,-1.0)';
      PINUSE='BI';
    'RSVD'<11>:
      PIN_NUMBER='(0,0,0,0,0,0,0,0,0,0,0,0,0,0,0,0,0,0,0,0,0,ED45,0,0,0,0,0,0,0,~
0)';
      BIDIRECTIONAL='TRUE';
      INPUT_LOAD='(-0.01,0.01)';
      OUTPUT_LOAD='(1.0,-1.0)';
      PINUSE='BI';
    'RSVD'<10>:
      PIN_NUMBER='(0,0,0,0,0,0,0,0,0,0,0,0,0,0,0,0,0,0,0,0,0,ED5,0,0,0,0,0,0,0,0~
)';
      BIDIRECTIONAL='TRUE';
      INPUT_LOAD='(-0.01,0.01)';
      OUTPUT_LOAD='(1.0,-1.0)';
      PINUSE='BI';
    'RSVD'<9>:
      PIN_NUMBER='(0,0,0,0,0,0,0,0,0,0,0,0,0,0,0,0,0,0,0,0,0,ED83,0,0,0,0,0,0,0,~
0)';
      BIDIRECTIONAL='TRUE';
      INPUT_LOAD='(-0.01,0.01)';
      OUTPUT_LOAD='(1.0,-1.0)';
      PINUSE='BI';
    'RSVD'<8>:
      PIN_NUMBER='(0,0,0,0,0,0,0,0,0,0,0,0,0,0,0,0,0,0,0,0,0,EE16,0,0,0,0,0,0,0,~
0)';
      BIDIRECTIONAL='TRUE';
      INPUT_LOAD='(-0.01,0.01)';
      OUTPUT_LOAD='(1.0,-1.0)';
      PINUSE='BI';
    'RSVD'<7>:
      PIN_NUMBER='(0,0,0,0,0,0,0,0,0,0,0,0,0,0,0,0,0,0,0,0,0,EE46,0,0,0,0,0,0,0,~
0)';
      BIDIRECTIONAL='TRUE';
      INPUT_LOAD='(-0.01,0.01)';
      OUTPUT_LOAD='(1.0,-1.0)';
      PINUSE='BI';
    'RSVD'<6>:
      PIN_NUMBER='(0,0,0,0,0,0,0,0,0,0,0,0,0,0,0,0,0,0,0,0,0,EE6,0,0,0,0,0,0,0,0~
)';
      BIDIRECTIONAL='TRUE';
      INPUT_LOAD='(-0.01,0.01)';
      OUTPUT_LOAD='(1.0,-1.0)';
      PINUSE='BI';
    'RSVD'<5>:
      PIN_NUMBER='(0,0,0,0,0,0,0,0,0,0,0,0,0,0,0,0,0,0,0,0,0,EE82,0,0,0,0,0,0,0,~
0)';
      BIDIRECTIONAL='TRUE';
      INPUT_LOAD='(-0.01,0.01)';
      OUTPUT_LOAD='(1.0,-1.0)';
      PINUSE='BI';
    'RSVD'<4>:
      PIN_NUMBER='(0,0,0,0,0,0,0,0,0,0,0,0,0,0,0,0,0,0,0,0,0,EE84,0,0,0,0,0,0,0,~
0)';
      BIDIRECTIONAL='TRUE';
      INPUT_LOAD='(-0.01,0.01)';
      OUTPUT_LOAD='(1.0,-1.0)';
      PINUSE='BI';
    'RSVD'<3>:
      PIN_NUMBER='(0,0,0,0,0,0,0,0,0,0,0,0,0,0,0,0,0,0,0,0,0,EF47,0,0,0,0,0,0,0,~
0)';
      BIDIRECTIONAL='TRUE';
      INPUT_LOAD='(-0.01,0.01)';
      OUTPUT_LOAD='(1.0,-1.0)';
      PINUSE='BI';
    'RSVD'<2>:
      PIN_NUMBER='(0,0,0,0,0,0,0,0,0,0,0,0,0,0,0,0,0,0,0,0,0,EF77,0,0,0,0,0,0,0,~
0)';
      BIDIRECTIONAL='TRUE';
      INPUT_LOAD='(-0.01,0.01)';
      OUTPUT_LOAD='(1.0,-1.0)';
      PINUSE='BI';
    'RSVD'<1>:
      PIN_NUMBER='(0,0,0,0,0,0,0,0,0,0,0,0,0,0,0,0,0,0,0,0,0,EF81,0,0,0,0,0,0,0,~
0)';
      BIDIRECTIONAL='TRUE';
      INPUT_LOAD='(-0.01,0.01)';
      OUTPUT_LOAD='(1.0,-1.0)';
      PINUSE='BI';
    'RSVD'<0>:
      PIN_NUMBER='(0,0,0,0,0,0,0,0,0,0,0,0,0,0,0,0,0,0,0,0,0,EF83,0,0,0,0,0,0,0,~
0)';
      BIDIRECTIONAL='TRUE';
      INPUT_LOAD='(-0.01,0.01)';
      OUTPUT_LOAD='(1.0,-1.0)';
      PINUSE='BI';
    'SAFE_MODE_BOOT':
      PIN_NUMBER='(AR18,0,0,0,0,0,0,0,0,0,0,0,0,0,0,0,0,0,0,0,0,0,0,0,0,0,0,0,0,~
0)';
      INPUT_LOAD='(-0.01,0.01)';
      PINUSE='IN';
    'SKTOCC_N':
      PIN_NUMBER='(AB13,0,0,0,0,0,0,0,0,0,0,0,0,0,0,0,0,0,0,0,0,0,0,0,0,0,0,0,0,~
0)';
      OUTPUT_LOAD='(1.0,-1.0)';
      PINUSE='OUT';
    'SMBCLK':
      PIN_NUMBER='(CT59,0,0,0,0,0,0,0,0,0,0,0,0,0,0,0,0,0,0,0,0,0,0,0,0,0,0,0,0,~
0)';
      BIDIRECTIONAL='TRUE';
      INPUT_LOAD='(-0.01,0.01)';
      OUTPUT_LOAD='(1.0,-1.0)';
      PINUSE='BI';
    'SMBDAT':
      PIN_NUMBER='(CW58,0,0,0,0,0,0,0,0,0,0,0,0,0,0,0,0,0,0,0,0,0,0,0,0,0,0,0,0,~
0)';
      BIDIRECTIONAL='TRUE';
      INPUT_LOAD='(-0.01,0.01)';
      OUTPUT_LOAD='(1.0,-1.0)';
      PINUSE='BI';
    'SM_WP':
      PIN_NUMBER='(CV59,0,0,0,0,0,0,0,0,0,0,0,0,0,0,0,0,0,0,0,0,0,0,0,0,0,0,0,0,~
0)';
      INPUT_LOAD='(-0.01,0.01)';
      PINUSE='IN';
    'SOCKET_ID'<2>:
      PIN_NUMBER='(AU20,0,0,0,0,0,0,0,0,0,0,0,0,0,0,0,0,0,0,0,0,0,0,0,0,0,0,0,0,~
0)';
      INPUT_LOAD='(-0.01,0.01)';
      PINUSE='IN';
    'SOCKET_ID'<1>:
      PIN_NUMBER='(AU16,0,0,0,0,0,0,0,0,0,0,0,0,0,0,0,0,0,0,0,0,0,0,0,0,0,0,0,0,~
0)';
      INPUT_LOAD='(-0.01,0.01)';
      PINUSE='IN';
    'SOCKET_ID'<0>:
      PIN_NUMBER='(AU22,0,0,0,0,0,0,0,0,0,0,0,0,0,0,0,0,0,0,0,0,0,0,0,0,0,0,0,0,~
0)';
      INPUT_LOAD='(-0.01,0.01)';
      PINUSE='IN';
    'SVIDALERT_N'<1>:
      PIN_NUMBER='(DL44,0,0,0,0,0,0,0,0,0,0,0,0,0,0,0,0,0,0,0,0,0,0,0,0,0,0,0,0,~
0)';
      INPUT_LOAD='(-0.01,0.01)';
      PINUSE='IN';
    'SVIDALERT_N'<0>:
      PIN_NUMBER='(DE44,0,0,0,0,0,0,0,0,0,0,0,0,0,0,0,0,0,0,0,0,0,0,0,0,0,0,0,0,~
0)';
      INPUT_LOAD='(-0.01,0.01)';
      PINUSE='IN';
    'SVIDCLK'<1>:
      PIN_NUMBER='(DG44,0,0,0,0,0,0,0,0,0,0,0,0,0,0,0,0,0,0,0,0,0,0,0,0,0,0,0,0,~
0)';
      OUTPUT_LOAD='(1.0,-1.0)';
      PINUSE='OUT';
    'SVIDCLK'<0>:
      PIN_NUMBER='(DC44,0,0,0,0,0,0,0,0,0,0,0,0,0,0,0,0,0,0,0,0,0,0,0,0,0,0,0,0,~
0)';
      OUTPUT_LOAD='(1.0,-1.0)';
      PINUSE='OUT';
    'SVIDDATA'<1>:
      PIN_NUMBER='(DJ44,0,0,0,0,0,0,0,0,0,0,0,0,0,0,0,0,0,0,0,0,0,0,0,0,0,0,0,0,~
0)';
      BIDIRECTIONAL='TRUE';
      INPUT_LOAD='(-0.01,0.01)';
      OUTPUT_LOAD='(1.0,-1.0)';
      PINUSE='BI';
    'SVIDDATA'<0>:
      PIN_NUMBER='(DB45,0,0,0,0,0,0,0,0,0,0,0,0,0,0,0,0,0,0,0,0,0,0,0,0,0,0,0,0,~
0)';
      BIDIRECTIONAL='TRUE';
      INPUT_LOAD='(-0.01,0.01)';
      OUTPUT_LOAD='(1.0,-1.0)';
      PINUSE='BI';
    'TCK':
      PIN_NUMBER='(AA14,0,0,0,0,0,0,0,0,0,0,0,0,0,0,0,0,0,0,0,0,0,0,0,0,0,0,0,0,~
0)';
      INPUT_LOAD='(-0.01,0.01)';
      PINUSE='IN';
    'TDI':
      PIN_NUMBER='(AC14,0,0,0,0,0,0,0,0,0,0,0,0,0,0,0,0,0,0,0,0,0,0,0,0,0,0,0,0,~
0)';
      INPUT_LOAD='(-0.01,0.01)';
      PINUSE='IN';
    'TDO':
      PIN_NUMBER='(AE14,0,0,0,0,0,0,0,0,0,0,0,0,0,0,0,0,0,0,0,0,0,0,0,0,0,0,0,0,~
0)';
      OUTPUT_LOAD='(1.0,-1.0)';
      PINUSE='OUT';
    'TEST_1':
      PIN_NUMBER='(0,AF45,0,0,0,0,0,0,0,0,0,0,0,0,0,0,0,0,0,0,0,0,0,0,0,0,0,0,0,~
0)';
      BIDIRECTIONAL='TRUE';
      INPUT_LOAD='(-0.01,0.01)';
      OUTPUT_LOAD='(1.0,-1.0)';
      PINUSE='BI';
    'TEST_10':
      PIN_NUMBER='(0,0,0,0,0,0,0,0,0,0,0,0,0,0,0,0,AW22,0,0,0,0,0,0,0,0,0,0,0,0,~
0)';
      BIDIRECTIONAL='TRUE';
      INPUT_LOAD='(-0.01,0.01)';
      OUTPUT_LOAD='(1.0,-1.0)';
      PINUSE='BI';
    'TEST_11':
      PIN_NUMBER='(0,AY13,0,0,0,0,0,0,0,0,0,0,0,0,0,0,0,0,0,0,0,0,0,0,0,0,0,0,0,~
0)';
      BIDIRECTIONAL='TRUE';
      INPUT_LOAD='(-0.01,0.01)';
      OUTPUT_LOAD='(1.0,-1.0)';
      PINUSE='BI';
    'TEST_12':
      PIN_NUMBER='(AY19,0,0,0,0,0,0,0,0,0,0,0,0,0,0,0,0,0,0,0,0,0,0,0,0,0,0,0,0,~
0)';
      BIDIRECTIONAL='TRUE';
      INPUT_LOAD='(-0.01,0.01)';
      OUTPUT_LOAD='(1.0,-1.0)';
      PINUSE='BI';
    'TEST_13':
      PIN_NUMBER='(DB51,0,0,0,0,0,0,0,0,0,0,0,0,0,0,0,0,0,0,0,0,0,0,0,0,0,0,0,0,~
0)';
      BIDIRECTIONAL='TRUE';
      INPUT_LOAD='(-0.01,0.01)';
      OUTPUT_LOAD='(1.0,-1.0)';
      PINUSE='BI';
    'TEST_14':
      PIN_NUMBER='(DC50,0,0,0,0,0,0,0,0,0,0,0,0,0,0,0,0,0,0,0,0,0,0,0,0,0,0,0,0,~
0)';
      BIDIRECTIONAL='TRUE';
      INPUT_LOAD='(-0.01,0.01)';
      OUTPUT_LOAD='(1.0,-1.0)';
      PINUSE='BI';
    'TEST_15':
      PIN_NUMBER='(AW14,0,0,0,0,0,0,0,0,0,0,0,0,0,0,0,0,0,0,0,0,0,0,0,0,0,0,0,0,~
0)';
      BIDIRECTIONAL='TRUE';
      INPUT_LOAD='(-0.01,0.01)';
      OUTPUT_LOAD='(1.0,-1.0)';
      PINUSE='BI';
    'TEST_2':
      PIN_NUMBER='(0,AG46,0,0,0,0,0,0,0,0,0,0,0,0,0,0,0,0,0,0,0,0,0,0,0,0,0,0,0,~
0)';
      BIDIRECTIONAL='TRUE';
      INPUT_LOAD='(-0.01,0.01)';
      OUTPUT_LOAD='(1.0,-1.0)';
      PINUSE='BI';
    'TEST_3':
      PIN_NUMBER='(0,AM13,0,0,0,0,0,0,0,0,0,0,0,0,0,0,0,0,0,0,0,0,0,0,0,0,0,0,0,~
0)';
      BIDIRECTIONAL='TRUE';
      INPUT_LOAD='(-0.01,0.01)';
      OUTPUT_LOAD='(1.0,-1.0)';
      PINUSE='BI';
    'TEST_4':
      PIN_NUMBER='(0,AN12,0,0,0,0,0,0,0,0,0,0,0,0,0,0,0,0,0,0,0,0,0,0,0,0,0,0,0,~
0)';
      BIDIRECTIONAL='TRUE';
      INPUT_LOAD='(-0.01,0.01)';
      OUTPUT_LOAD='(1.0,-1.0)';
      PINUSE='BI';
    'TEST_5':
      PIN_NUMBER='(0,AN14,0,0,0,0,0,0,0,0,0,0,0,0,0,0,0,0,0,0,0,0,0,0,0,0,0,0,0,~
0)';
      BIDIRECTIONAL='TRUE';
      INPUT_LOAD='(-0.01,0.01)';
      OUTPUT_LOAD='(1.0,-1.0)';
      PINUSE='BI';
    'TEST_6':
      PIN_NUMBER='(0,0,0,0,0,0,0,0,0,0,0,0,0,0,0,0,AR16,0,0,0,0,0,0,0,0,0,0,0,0,~
0)';
      BIDIRECTIONAL='TRUE';
      INPUT_LOAD='(-0.01,0.01)';
      OUTPUT_LOAD='(1.0,-1.0)';
      PINUSE='BI';
    'TEST_7':
      PIN_NUMBER='(0,0,0,0,0,0,0,0,0,0,0,0,0,0,0,0,AU18,0,0,0,0,0,0,0,0,0,0,0,0,~
0)';
      BIDIRECTIONAL='TRUE';
      INPUT_LOAD='(-0.01,0.01)';
      OUTPUT_LOAD='(1.0,-1.0)';
      PINUSE='BI';
    'TEST_8':
      PIN_NUMBER='(0,0,0,0,0,0,0,0,0,0,0,0,0,0,0,0,AW16,0,0,0,0,0,0,0,0,0,0,0,0,~
0)';
      BIDIRECTIONAL='TRUE';
      INPUT_LOAD='(-0.01,0.01)';
      OUTPUT_LOAD='(1.0,-1.0)';
      PINUSE='BI';
    'TEST_9':
      PIN_NUMBER='(0,0,0,0,0,0,0,0,0,0,0,0,0,0,0,0,AW20,0,0,0,0,0,0,0,0,0,0,0,0,~
0)';
      BIDIRECTIONAL='TRUE';
      INPUT_LOAD='(-0.01,0.01)';
      OUTPUT_LOAD='(1.0,-1.0)';
      PINUSE='BI';
    'THERMTRIP_N':
      PIN_NUMBER='(AB15,0,0,0,0,0,0,0,0,0,0,0,0,0,0,0,0,0,0,0,0,0,0,0,0,0,0,0,0,~
0)';
      OUTPUT_LOAD='(1.0,-1.0)';
      PINUSE='OUT';
    'TMS':
      PIN_NUMBER='(W14,0,0,0,0,0,0,0,0,0,0,0,0,0,0,0,0,0,0,0,0,0,0,0,0,0,0,0,0,0~
)';
      INPUT_LOAD='(-0.01,0.01)';
      PINUSE='IN';
    'TRST_N':
      PIN_NUMBER='(Y13,0,0,0,0,0,0,0,0,0,0,0,0,0,0,0,0,0,0,0,0,0,0,0,0,0,0,0,0,0~
)';
      INPUT_LOAD='(-0.01,0.01)';
      PINUSE='IN';
    'TSC_SYNC':
      PIN_NUMBER='(AM11,0,0,0,0,0,0,0,0,0,0,0,0,0,0,0,0,0,0,0,0,0,0,0,0,0,0,0,0,~
0)';
      BIDIRECTIONAL='TRUE';
      INPUT_LOAD='(-0.01,0.01)';
      OUTPUT_LOAD='(1.0,-1.0)';
      PINUSE='BI';
    'TXT_AGENT':
      PIN_NUMBER='(AW18,0,0,0,0,0,0,0,0,0,0,0,0,0,0,0,0,0,0,0,0,0,0,0,0,0,0,0,0,~
0)';
      INPUT_LOAD='(-0.01,0.01)';
      PINUSE='IN';
    'TXT_PLTEN':
      PIN_NUMBER='(AV15,0,0,0,0,0,0,0,0,0,0,0,0,0,0,0,0,0,0,0,0,0,0,0,0,0,0,0,0,~
0)';
      INPUT_LOAD='(-0.01,0.01)';
      PINUSE='IN';
    'UPI01_RBIAS'<1>:
      PIN_NUMBER='(AP29,0,0,0,0,0,0,0,0,0,0,0,0,0,0,0,0,0,0,0,0,0,0,0,0,0,0,0,0,~
0)';
      INPUT_LOAD='(-0.01,0.01)';
      PINUSE='IN';
    'UPI01_RBIAS'<0>:
      PIN_NUMBER='(AT29,0,0,0,0,0,0,0,0,0,0,0,0,0,0,0,0,0,0,0,0,0,0,0,0,0,0,0,0,~
0)';
      INPUT_LOAD='(-0.01,0.01)';
      PINUSE='IN';
    'UPI0_RX_DN'<19>:
      PIN_NUMBER='(0,0,0,0,0,0,0,0,0,0,0,0,BB11,0,0,0,0,0,0,0,0,0,0,0,0,0,0,0,0,~
0)';
      INPUT_LOAD='(-0.01,0.01)';
      PINUSE='IN';
    'UPI0_RX_DN'<18>:
      PIN_NUMBER='(0,0,0,0,0,0,0,0,0,0,0,0,BD9,0,0,0,0,0,0,0,0,0,0,0,0,0,0,0,0,0~
)';
      INPUT_LOAD='(-0.01,0.01)';
      PINUSE='IN';
    'UPI0_RX_DN'<17>:
      PIN_NUMBER='(0,0,0,0,0,0,0,0,0,0,0,0,AY9,0,0,0,0,0,0,0,0,0,0,0,0,0,0,0,0,0~
)';
      INPUT_LOAD='(-0.01,0.01)';
      PINUSE='IN';
    'UPI0_RX_DN'<16>:
      PIN_NUMBER='(0,0,0,0,0,0,0,0,0,0,0,0,AW8,0,0,0,0,0,0,0,0,0,0,0,0,0,0,0,0,0~
)';
      INPUT_LOAD='(-0.01,0.01)';
      PINUSE='IN';
    'UPI0_RX_DN'<15>:
      PIN_NUMBER='(0,0,0,0,0,0,0,0,0,0,0,0,BD7,0,0,0,0,0,0,0,0,0,0,0,0,0,0,0,0,0~
)';
      INPUT_LOAD='(-0.01,0.01)';
      PINUSE='IN';
    'UPI0_RX_DN'<14>:
      PIN_NUMBER='(0,0,0,0,0,0,0,0,0,0,0,0,BC6,0,0,0,0,0,0,0,0,0,0,0,0,0,0,0,0,0~
)';
      INPUT_LOAD='(-0.01,0.01)';
      PINUSE='IN';
    'UPI0_RX_DN'<13>:
      PIN_NUMBER='(0,0,0,0,0,0,0,0,0,0,0,0,BA8,0,0,0,0,0,0,0,0,0,0,0,0,0,0,0,0,0~
)';
      INPUT_LOAD='(-0.01,0.01)';
      PINUSE='IN';
    'UPI0_RX_DN'<12>:
      PIN_NUMBER='(0,0,0,0,0,0,0,0,0,0,0,0,AU10,0,0,0,0,0,0,0,0,0,0,0,0,0,0,0,0,~
0)';
      INPUT_LOAD='(-0.01,0.01)';
      PINUSE='IN';
    'UPI0_RX_DN'<11>:
      PIN_NUMBER='(0,0,0,0,0,0,0,0,0,0,0,0,AR8,0,0,0,0,0,0,0,0,0,0,0,0,0,0,0,0,0~
)';
      INPUT_LOAD='(-0.01,0.01)';
      PINUSE='IN';
    'UPI0_RX_DN'<10>:
      PIN_NUMBER='(0,0,0,0,0,0,0,0,0,0,0,0,AP7,0,0,0,0,0,0,0,0,0,0,0,0,0,0,0,0,0~
)';
      INPUT_LOAD='(-0.01,0.01)';
      PINUSE='IN';
    'UPI0_RX_DN'<9>:
      PIN_NUMBER='(0,0,0,0,0,0,0,0,0,0,0,0,AM9,0,0,0,0,0,0,0,0,0,0,0,0,0,0,0,0,0~
)';
      INPUT_LOAD='(-0.01,0.01)';
      PINUSE='IN';
    'UPI0_RX_DN'<8>:
      PIN_NUMBER='(0,0,0,0,0,0,0,0,0,0,0,0,AK7,0,0,0,0,0,0,0,0,0,0,0,0,0,0,0,0,0~
)';
      INPUT_LOAD='(-0.01,0.01)';
      PINUSE='IN';
    'UPI0_RX_DN'<7>:
      PIN_NUMBER='(0,0,0,0,0,0,0,0,0,0,0,0,AL6,0,0,0,0,0,0,0,0,0,0,0,0,0,0,0,0,0~
)';
      INPUT_LOAD='(-0.01,0.01)';
      PINUSE='IN';
    'UPI0_RX_DN'<6>:
      PIN_NUMBER='(0,0,0,0,0,0,0,0,0,0,0,0,AJ6,0,0,0,0,0,0,0,0,0,0,0,0,0,0,0,0,0~
)';
      INPUT_LOAD='(-0.01,0.01)';
      PINUSE='IN';
    'UPI0_RX_DN'<5>:
      PIN_NUMBER='(0,0,0,0,0,0,0,0,0,0,0,0,AG8,0,0,0,0,0,0,0,0,0,0,0,0,0,0,0,0,0~
)';
      INPUT_LOAD='(-0.01,0.01)';
      PINUSE='IN';
    'UPI0_RX_DN'<4>:
      PIN_NUMBER='(0,0,0,0,0,0,0,0,0,0,0,0,AE6,0,0,0,0,0,0,0,0,0,0,0,0,0,0,0,0,0~
)';
      INPUT_LOAD='(-0.01,0.01)';
      PINUSE='IN';
    'UPI0_RX_DN'<3>:
      PIN_NUMBER='(0,0,0,0,0,0,0,0,0,0,0,0,AD5,0,0,0,0,0,0,0,0,0,0,0,0,0,0,0,0,0~
)';
      INPUT_LOAD='(-0.01,0.01)';
      PINUSE='IN';
    'UPI0_RX_DN'<2>:
      PIN_NUMBER='(0,0,0,0,0,0,0,0,0,0,0,0,AB7,0,0,0,0,0,0,0,0,0,0,0,0,0,0,0,0,0~
)';
      INPUT_LOAD='(-0.01,0.01)';
      PINUSE='IN';
    'UPI0_RX_DN'<1>:
      PIN_NUMBER='(0,0,0,0,0,0,0,0,0,0,0,0,AA8,0,0,0,0,0,0,0,0,0,0,0,0,0,0,0,0,0~
)';
      INPUT_LOAD='(-0.01,0.01)';
      PINUSE='IN';
    'UPI0_RX_DN'<0>:
      PIN_NUMBER='(0,0,0,0,0,0,0,0,0,0,0,0,AC10,0,0,0,0,0,0,0,0,0,0,0,0,0,0,0,0,~
0)';
      INPUT_LOAD='(-0.01,0.01)';
      PINUSE='IN';
    'UPI0_RX_DP'<19>:
      PIN_NUMBER='(0,0,0,0,0,0,0,0,0,0,0,0,BA10,0,0,0,0,0,0,0,0,0,0,0,0,0,0,0,0,~
0)';
      INPUT_LOAD='(-0.01,0.01)';
      PINUSE='IN';
    'UPI0_RX_DP'<18>:
      PIN_NUMBER='(0,0,0,0,0,0,0,0,0,0,0,0,BC10,0,0,0,0,0,0,0,0,0,0,0,0,0,0,0,0,~
0)';
      INPUT_LOAD='(-0.01,0.01)';
      PINUSE='IN';
    'UPI0_RX_DP'<17>:
      PIN_NUMBER='(0,0,0,0,0,0,0,0,0,0,0,0,BB9,0,0,0,0,0,0,0,0,0,0,0,0,0,0,0,0,0~
)';
      INPUT_LOAD='(-0.01,0.01)';
      PINUSE='IN';
    'UPI0_RX_DP'<16>:
      PIN_NUMBER='(0,0,0,0,0,0,0,0,0,0,0,0,AV9,0,0,0,0,0,0,0,0,0,0,0,0,0,0,0,0,0~
)';
      INPUT_LOAD='(-0.01,0.01)';
      PINUSE='IN';
    'UPI0_RX_DP'<15>:
      PIN_NUMBER='(0,0,0,0,0,0,0,0,0,0,0,0,BF7,0,0,0,0,0,0,0,0,0,0,0,0,0,0,0,0,0~
)';
      INPUT_LOAD='(-0.01,0.01)';
      PINUSE='IN';
    'UPI0_RX_DP'<14>:
      PIN_NUMBER='(0,0,0,0,0,0,0,0,0,0,0,0,BB7,0,0,0,0,0,0,0,0,0,0,0,0,0,0,0,0,0~
)';
      INPUT_LOAD='(-0.01,0.01)';
      PINUSE='IN';
    'UPI0_RX_DP'<13>:
      PIN_NUMBER='(0,0,0,0,0,0,0,0,0,0,0,0,AY7,0,0,0,0,0,0,0,0,0,0,0,0,0,0,0,0,0~
)';
      INPUT_LOAD='(-0.01,0.01)';
      PINUSE='IN';
    'UPI0_RX_DP'<12>:
      PIN_NUMBER='(0,0,0,0,0,0,0,0,0,0,0,0,AT9,0,0,0,0,0,0,0,0,0,0,0,0,0,0,0,0,0~
)';
      INPUT_LOAD='(-0.01,0.01)';
      PINUSE='IN';
    'UPI0_RX_DP'<11>:
      PIN_NUMBER='(0,0,0,0,0,0,0,0,0,0,0,0,AU8,0,0,0,0,0,0,0,0,0,0,0,0,0,0,0,0,0~
)';
      INPUT_LOAD='(-0.01,0.01)';
      PINUSE='IN';
    'UPI0_RX_DP'<10>:
      PIN_NUMBER='(0,0,0,0,0,0,0,0,0,0,0,0,AN8,0,0,0,0,0,0,0,0,0,0,0,0,0,0,0,0,0~
)';
      INPUT_LOAD='(-0.01,0.01)';
      PINUSE='IN';
    'UPI0_RX_DP'<9>:
      PIN_NUMBER='(0,0,0,0,0,0,0,0,0,0,0,0,AL8,0,0,0,0,0,0,0,0,0,0,0,0,0,0,0,0,0~
)';
      INPUT_LOAD='(-0.01,0.01)';
      PINUSE='IN';
    'UPI0_RX_DP'<8>:
      PIN_NUMBER='(0,0,0,0,0,0,0,0,0,0,0,0,AM7,0,0,0,0,0,0,0,0,0,0,0,0,0,0,0,0,0~
)';
      INPUT_LOAD='(-0.01,0.01)';
      PINUSE='IN';
    'UPI0_RX_DP'<7>:
      PIN_NUMBER='(0,0,0,0,0,0,0,0,0,0,0,0,AK5,0,0,0,0,0,0,0,0,0,0,0,0,0,0,0,0,0~
)';
      INPUT_LOAD='(-0.01,0.01)';
      PINUSE='IN';
    'UPI0_RX_DP'<6>:
      PIN_NUMBER='(0,0,0,0,0,0,0,0,0,0,0,0,AH7,0,0,0,0,0,0,0,0,0,0,0,0,0,0,0,0,0~
)';
      INPUT_LOAD='(-0.01,0.01)';
      PINUSE='IN';
    'UPI0_RX_DP'<5>:
      PIN_NUMBER='(0,0,0,0,0,0,0,0,0,0,0,0,AF7,0,0,0,0,0,0,0,0,0,0,0,0,0,0,0,0,0~
)';
      INPUT_LOAD='(-0.01,0.01)';
      PINUSE='IN';
    'UPI0_RX_DP'<4>:
      PIN_NUMBER='(0,0,0,0,0,0,0,0,0,0,0,0,AG6,0,0,0,0,0,0,0,0,0,0,0,0,0,0,0,0,0~
)';
      INPUT_LOAD='(-0.01,0.01)';
      PINUSE='IN';
    'UPI0_RX_DP'<3>:
      PIN_NUMBER='(0,0,0,0,0,0,0,0,0,0,0,0,AC6,0,0,0,0,0,0,0,0,0,0,0,0,0,0,0,0,0~
)';
      INPUT_LOAD='(-0.01,0.01)';
      PINUSE='IN';
    'UPI0_RX_DP'<2>:
      PIN_NUMBER='(0,0,0,0,0,0,0,0,0,0,0,0,AA6,0,0,0,0,0,0,0,0,0,0,0,0,0,0,0,0,0~
)';
      INPUT_LOAD='(-0.01,0.01)';
      PINUSE='IN';
    'UPI0_RX_DP'<1>:
      PIN_NUMBER='(0,0,0,0,0,0,0,0,0,0,0,0,AC8,0,0,0,0,0,0,0,0,0,0,0,0,0,0,0,0,0~
)';
      INPUT_LOAD='(-0.01,0.01)';
      PINUSE='IN';
    'UPI0_RX_DP'<0>:
      PIN_NUMBER='(0,0,0,0,0,0,0,0,0,0,0,0,AB9,0,0,0,0,0,0,0,0,0,0,0,0,0,0,0,0,0~
)';
      INPUT_LOAD='(-0.01,0.01)';
      PINUSE='IN';
    'UPI0_TX_DN'<19>:
      PIN_NUMBER='(0,0,0,0,0,0,0,0,0,0,0,0,BG4,0,0,0,0,0,0,0,0,0,0,0,0,0,0,0,0,0~
)';
      OUTPUT_LOAD='(1.0,-1.0)';
      PINUSE='OUT';
    'UPI0_TX_DN'<18>:
      PIN_NUMBER='(0,0,0,0,0,0,0,0,0,0,0,0,BF3,0,0,0,0,0,0,0,0,0,0,0,0,0,0,0,0,0~
)';
      OUTPUT_LOAD='(1.0,-1.0)';
      PINUSE='OUT';
    'UPI0_TX_DN'<17>:
      PIN_NUMBER='(0,0,0,0,0,0,0,0,0,0,0,0,BB3,0,0,0,0,0,0,0,0,0,0,0,0,0,0,0,0,0~
)';
      OUTPUT_LOAD='(1.0,-1.0)';
      PINUSE='OUT';
    'UPI0_TX_DN'<16>:
      PIN_NUMBER='(0,0,0,0,0,0,0,0,0,0,0,0,BA4,0,0,0,0,0,0,0,0,0,0,0,0,0,0,0,0,0~
)';
      OUTPUT_LOAD='(1.0,-1.0)';
      PINUSE='OUT';
    'UPI0_TX_DN'<15>:
      PIN_NUMBER='(0,0,0,0,0,0,0,0,0,0,0,0,AV5,0,0,0,0,0,0,0,0,0,0,0,0,0,0,0,0,0~
)';
      OUTPUT_LOAD='(1.0,-1.0)';
      PINUSE='OUT';
    'UPI0_TX_DN'<14>:
      PIN_NUMBER='(0,0,0,0,0,0,0,0,0,0,0,0,AU4,0,0,0,0,0,0,0,0,0,0,0,0,0,0,0,0,0~
)';
      OUTPUT_LOAD='(1.0,-1.0)';
      PINUSE='OUT';
    'UPI0_TX_DN'<13>:
      PIN_NUMBER='(0,0,0,0,0,0,0,0,0,0,0,0,AT3,0,0,0,0,0,0,0,0,0,0,0,0,0,0,0,0,0~
)';
      OUTPUT_LOAD='(1.0,-1.0)';
      PINUSE='OUT';
    'UPI0_TX_DN'<12>:
      PIN_NUMBER='(0,0,0,0,0,0,0,0,0,0,0,0,AT1,0,0,0,0,0,0,0,0,0,0,0,0,0,0,0,0,0~
)';
      OUTPUT_LOAD='(1.0,-1.0)';
      PINUSE='OUT';
    'UPI0_TX_DN'<11>:
      PIN_NUMBER='(0,0,0,0,0,0,0,0,0,0,0,0,AN4,0,0,0,0,0,0,0,0,0,0,0,0,0,0,0,0,0~
)';
      OUTPUT_LOAD='(1.0,-1.0)';
      PINUSE='OUT';
    'UPI0_TX_DN'<10>:
      PIN_NUMBER='(0,0,0,0,0,0,0,0,0,0,0,0,AM3,0,0,0,0,0,0,0,0,0,0,0,0,0,0,0,0,0~
)';
      OUTPUT_LOAD='(1.0,-1.0)';
      PINUSE='OUT';
    'UPI0_TX_DN'<9>:
      PIN_NUMBER='(0,0,0,0,0,0,0,0,0,0,0,0,AL2,0,0,0,0,0,0,0,0,0,0,0,0,0,0,0,0,0~
)';
      OUTPUT_LOAD='(1.0,-1.0)';
      PINUSE='OUT';
    'UPI0_TX_DN'<8>:
      PIN_NUMBER='(0,0,0,0,0,0,0,0,0,0,0,0,AH3,0,0,0,0,0,0,0,0,0,0,0,0,0,0,0,0,0~
)';
      OUTPUT_LOAD='(1.0,-1.0)';
      PINUSE='OUT';
    'UPI0_TX_DN'<7>:
      PIN_NUMBER='(0,0,0,0,0,0,0,0,0,0,0,0,AE2,0,0,0,0,0,0,0,0,0,0,0,0,0,0,0,0,0~
)';
      OUTPUT_LOAD='(1.0,-1.0)';
      PINUSE='OUT';
    'UPI0_TX_DN'<6>:
      PIN_NUMBER='(0,0,0,0,0,0,0,0,0,0,0,0,AG4,0,0,0,0,0,0,0,0,0,0,0,0,0,0,0,0,0~
)';
      OUTPUT_LOAD='(1.0,-1.0)';
      PINUSE='OUT';
    'UPI0_TX_DN'<5>:
      PIN_NUMBER='(0,0,0,0,0,0,0,0,0,0,0,0,AC2,0,0,0,0,0,0,0,0,0,0,0,0,0,0,0,0,0~
)';
      OUTPUT_LOAD='(1.0,-1.0)';
      PINUSE='OUT';
    'UPI0_TX_DN'<4>:
      PIN_NUMBER='(0,0,0,0,0,0,0,0,0,0,0,0,AB3,0,0,0,0,0,0,0,0,0,0,0,0,0,0,0,0,0~
)';
      OUTPUT_LOAD='(1.0,-1.0)';
      PINUSE='OUT';
    'UPI0_TX_DN'<3>:
      PIN_NUMBER='(0,0,0,0,0,0,0,0,0,0,0,0,Y1,0,0,0,0,0,0,0,0,0,0,0,0,0,0,0,0,0)~
';
      OUTPUT_LOAD='(1.0,-1.0)';
      PINUSE='OUT';
    'UPI0_TX_DN'<2>:
      PIN_NUMBER='(0,0,0,0,0,0,0,0,0,0,0,0,V3,0,0,0,0,0,0,0,0,0,0,0,0,0,0,0,0,0)~
';
      OUTPUT_LOAD='(1.0,-1.0)';
      PINUSE='OUT';
    'UPI0_TX_DN'<1>:
      PIN_NUMBER='(0,0,0,0,0,0,0,0,0,0,0,0,P1,0,0,0,0,0,0,0,0,0,0,0,0,0,0,0,0,0)~
';
      OUTPUT_LOAD='(1.0,-1.0)';
      PINUSE='OUT';
    'UPI0_TX_DN'<0>:
      PIN_NUMBER='(0,0,0,0,0,0,0,0,0,0,0,0,N2,0,0,0,0,0,0,0,0,0,0,0,0,0,0,0,0,0)~
';
      OUTPUT_LOAD='(1.0,-1.0)';
      PINUSE='OUT';
    'UPI0_TX_DP'<19>:
      PIN_NUMBER='(0,0,0,0,0,0,0,0,0,0,0,0,BH3,0,0,0,0,0,0,0,0,0,0,0,0,0,0,0,0,0~
)';
      OUTPUT_LOAD='(1.0,-1.0)';
      PINUSE='OUT';
    'UPI0_TX_DP'<18>:
      PIN_NUMBER='(0,0,0,0,0,0,0,0,0,0,0,0,BD3,0,0,0,0,0,0,0,0,0,0,0,0,0,0,0,0,0~
)';
      OUTPUT_LOAD='(1.0,-1.0)';
      PINUSE='OUT';
    'UPI0_TX_DP'<17>:
      PIN_NUMBER='(0,0,0,0,0,0,0,0,0,0,0,0,BC2,0,0,0,0,0,0,0,0,0,0,0,0,0,0,0,0,0~
)';
      OUTPUT_LOAD='(1.0,-1.0)';
      PINUSE='OUT';
    'UPI0_TX_DP'<16>:
      PIN_NUMBER='(0,0,0,0,0,0,0,0,0,0,0,0,AY3,0,0,0,0,0,0,0,0,0,0,0,0,0,0,0,0,0~
)';
      OUTPUT_LOAD='(1.0,-1.0)';
      PINUSE='OUT';
    'UPI0_TX_DP'<15>:
      PIN_NUMBER='(0,0,0,0,0,0,0,0,0,0,0,0,AW4,0,0,0,0,0,0,0,0,0,0,0,0,0,0,0,0,0~
)';
      OUTPUT_LOAD='(1.0,-1.0)';
      PINUSE='OUT';
    'UPI0_TX_DP'<14>:
      PIN_NUMBER='(0,0,0,0,0,0,0,0,0,0,0,0,AR4,0,0,0,0,0,0,0,0,0,0,0,0,0,0,0,0,0~
)';
      OUTPUT_LOAD='(1.0,-1.0)';
      PINUSE='OUT';
    'UPI0_TX_DP'<13>:
      PIN_NUMBER='(0,0,0,0,0,0,0,0,0,0,0,0,AR2,0,0,0,0,0,0,0,0,0,0,0,0,0,0,0,0,0~
)';
      OUTPUT_LOAD='(1.0,-1.0)';
      PINUSE='OUT';
    'UPI0_TX_DP'<12>:
      PIN_NUMBER='(0,0,0,0,0,0,0,0,0,0,0,0,AP1,0,0,0,0,0,0,0,0,0,0,0,0,0,0,0,0,0~
)';
      OUTPUT_LOAD='(1.0,-1.0)';
      PINUSE='OUT';
    'UPI0_TX_DP'<11>:
      PIN_NUMBER='(0,0,0,0,0,0,0,0,0,0,0,0,AP3,0,0,0,0,0,0,0,0,0,0,0,0,0,0,0,0,0~
)';
      OUTPUT_LOAD='(1.0,-1.0)';
      PINUSE='OUT';
    'UPI0_TX_DP'<10>:
      PIN_NUMBER='(0,0,0,0,0,0,0,0,0,0,0,0,AK3,0,0,0,0,0,0,0,0,0,0,0,0,0,0,0,0,0~
)';
      OUTPUT_LOAD='(1.0,-1.0)';
      PINUSE='OUT';
    'UPI0_TX_DP'<9>:
      PIN_NUMBER='(0,0,0,0,0,0,0,0,0,0,0,0,AK1,0,0,0,0,0,0,0,0,0,0,0,0,0,0,0,0,0~
)';
      OUTPUT_LOAD='(1.0,-1.0)';
      PINUSE='OUT';
    'UPI0_TX_DP'<8>:
      PIN_NUMBER='(0,0,0,0,0,0,0,0,0,0,0,0,AJ2,0,0,0,0,0,0,0,0,0,0,0,0,0,0,0,0,0~
)';
      OUTPUT_LOAD='(1.0,-1.0)';
      PINUSE='OUT';
    'UPI0_TX_DP'<7>:
      PIN_NUMBER='(0,0,0,0,0,0,0,0,0,0,0,0,AG2,0,0,0,0,0,0,0,0,0,0,0,0,0,0,0,0,0~
)';
      OUTPUT_LOAD='(1.0,-1.0)';
      PINUSE='OUT';
    'UPI0_TX_DP'<6>:
      PIN_NUMBER='(0,0,0,0,0,0,0,0,0,0,0,0,AF3,0,0,0,0,0,0,0,0,0,0,0,0,0,0,0,0,0~
)';
      OUTPUT_LOAD='(1.0,-1.0)';
      PINUSE='OUT';
    'UPI0_TX_DP'<5>:
      PIN_NUMBER='(0,0,0,0,0,0,0,0,0,0,0,0,AD1,0,0,0,0,0,0,0,0,0,0,0,0,0,0,0,0,0~
)';
      OUTPUT_LOAD='(1.0,-1.0)';
      PINUSE='OUT';
    'UPI0_TX_DP'<4>:
      PIN_NUMBER='(0,0,0,0,0,0,0,0,0,0,0,0,AA2,0,0,0,0,0,0,0,0,0,0,0,0,0,0,0,0,0~
)';
      OUTPUT_LOAD='(1.0,-1.0)';
      PINUSE='OUT';
    'UPI0_TX_DP'<3>:
      PIN_NUMBER='(0,0,0,0,0,0,0,0,0,0,0,0,W2,0,0,0,0,0,0,0,0,0,0,0,0,0,0,0,0,0)~
';
      OUTPUT_LOAD='(1.0,-1.0)';
      PINUSE='OUT';
    'UPI0_TX_DP'<2>:
      PIN_NUMBER='(0,0,0,0,0,0,0,0,0,0,0,0,Y3,0,0,0,0,0,0,0,0,0,0,0,0,0,0,0,0,0)~
';
      OUTPUT_LOAD='(1.0,-1.0)';
      PINUSE='OUT';
    'UPI0_TX_DP'<1>:
      PIN_NUMBER='(0,0,0,0,0,0,0,0,0,0,0,0,T1,0,0,0,0,0,0,0,0,0,0,0,0,0,0,0,0,0)~
';
      OUTPUT_LOAD='(1.0,-1.0)';
      PINUSE='OUT';
    'UPI0_TX_DP'<0>:
      PIN_NUMBER='(0,0,0,0,0,0,0,0,0,0,0,0,M1,0,0,0,0,0,0,0,0,0,0,0,0,0,0,0,0,0)~
';
      OUTPUT_LOAD='(1.0,-1.0)';
      PINUSE='OUT';
    'UPI1_RX_DN'<19>:
      PIN_NUMBER='(0,0,0,0,0,0,0,0,0,0,0,0,0,AB19,0,0,0,0,0,0,0,0,0,0,0,0,0,0,0,~
0)';
      INPUT_LOAD='(-0.01,0.01)';
      PINUSE='IN';
    'UPI1_RX_DN'<18>:
      PIN_NUMBER='(0,0,0,0,0,0,0,0,0,0,0,0,0,Y21,0,0,0,0,0,0,0,0,0,0,0,0,0,0,0,0~
)';
      INPUT_LOAD='(-0.01,0.01)';
      PINUSE='IN';
    'UPI1_RX_DN'<17>:
      PIN_NUMBER='(0,0,0,0,0,0,0,0,0,0,0,0,0,V19,0,0,0,0,0,0,0,0,0,0,0,0,0,0,0,0~
)';
      INPUT_LOAD='(-0.01,0.01)';
      PINUSE='IN';
    'UPI1_RX_DN'<16>:
      PIN_NUMBER='(0,0,0,0,0,0,0,0,0,0,0,0,0,P21,0,0,0,0,0,0,0,0,0,0,0,0,0,0,0,0~
)';
      INPUT_LOAD='(-0.01,0.01)';
      PINUSE='IN';
    'UPI1_RX_DN'<15>:
      PIN_NUMBER='(0,0,0,0,0,0,0,0,0,0,0,0,0,U18,0,0,0,0,0,0,0,0,0,0,0,0,0,0,0,0~
)';
      INPUT_LOAD='(-0.01,0.01)';
      PINUSE='IN';
    'UPI1_RX_DN'<14>:
      PIN_NUMBER='(0,0,0,0,0,0,0,0,0,0,0,0,0,R20,0,0,0,0,0,0,0,0,0,0,0,0,0,0,0,0~
)';
      INPUT_LOAD='(-0.01,0.01)';
      PINUSE='IN';
    'UPI1_RX_DN'<13>:
      PIN_NUMBER='(0,0,0,0,0,0,0,0,0,0,0,0,0,W18,0,0,0,0,0,0,0,0,0,0,0,0,0,0,0,0~
)';
      INPUT_LOAD='(-0.01,0.01)';
      PINUSE='IN';
    'UPI1_RX_DN'<12>:
      PIN_NUMBER='(0,0,0,0,0,0,0,0,0,0,0,0,0,U16,0,0,0,0,0,0,0,0,0,0,0,0,0,0,0,0~
)';
      INPUT_LOAD='(-0.01,0.01)';
      PINUSE='IN';
    'UPI1_RX_DN'<11>:
      PIN_NUMBER='(0,0,0,0,0,0,0,0,0,0,0,0,0,P17,0,0,0,0,0,0,0,0,0,0,0,0,0,0,0,0~
)';
      INPUT_LOAD='(-0.01,0.01)';
      PINUSE='IN';
    'UPI1_RX_DN'<10>:
      PIN_NUMBER='(0,0,0,0,0,0,0,0,0,0,0,0,0,R16,0,0,0,0,0,0,0,0,0,0,0,0,0,0,0,0~
)';
      INPUT_LOAD='(-0.01,0.01)';
      PINUSE='IN';
    'UPI1_RX_DN'<9>:
      PIN_NUMBER='(0,0,0,0,0,0,0,0,0,0,0,0,0,R12,0,0,0,0,0,0,0,0,0,0,0,0,0,0,0,0~
)';
      INPUT_LOAD='(-0.01,0.01)';
      PINUSE='IN';
    'UPI1_RX_DN'<8>:
      PIN_NUMBER='(0,0,0,0,0,0,0,0,0,0,0,0,0,N14,0,0,0,0,0,0,0,0,0,0,0,0,0,0,0,0~
)';
      INPUT_LOAD='(-0.01,0.01)';
      PINUSE='IN';
    'UPI1_RX_DN'<7>:
      PIN_NUMBER='(0,0,0,0,0,0,0,0,0,0,0,0,0,L12,0,0,0,0,0,0,0,0,0,0,0,0,0,0,0,0~
)';
      INPUT_LOAD='(-0.01,0.01)';
      PINUSE='IN';
    'UPI1_RX_DN'<6>:
      PIN_NUMBER='(0,0,0,0,0,0,0,0,0,0,0,0,0,U12,0,0,0,0,0,0,0,0,0,0,0,0,0,0,0,0~
)';
      INPUT_LOAD='(-0.01,0.01)';
      PINUSE='IN';
    'UPI1_RX_DN'<5>:
      PIN_NUMBER='(0,0,0,0,0,0,0,0,0,0,0,0,0,R10,0,0,0,0,0,0,0,0,0,0,0,0,0,0,0,0~
)';
      INPUT_LOAD='(-0.01,0.01)';
      PINUSE='IN';
    'UPI1_RX_DN'<4>:
      PIN_NUMBER='(0,0,0,0,0,0,0,0,0,0,0,0,0,P9,0,0,0,0,0,0,0,0,0,0,0,0,0,0,0,0)~
';
      INPUT_LOAD='(-0.01,0.01)';
      PINUSE='IN';
    'UPI1_RX_DN'<3>:
      PIN_NUMBER='(0,0,0,0,0,0,0,0,0,0,0,0,0,T9,0,0,0,0,0,0,0,0,0,0,0,0,0,0,0,0)~
';
      INPUT_LOAD='(-0.01,0.01)';
      PINUSE='IN';
    'UPI1_RX_DN'<2>:
      PIN_NUMBER='(0,0,0,0,0,0,0,0,0,0,0,0,0,V7,0,0,0,0,0,0,0,0,0,0,0,0,0,0,0,0)~
';
      INPUT_LOAD='(-0.01,0.01)';
      PINUSE='IN';
    'UPI1_RX_DN'<1>:
      PIN_NUMBER='(0,0,0,0,0,0,0,0,0,0,0,0,0,P7,0,0,0,0,0,0,0,0,0,0,0,0,0,0,0,0)~
';
      INPUT_LOAD='(-0.01,0.01)';
      PINUSE='IN';
    'UPI1_RX_DN'<0>:
      PIN_NUMBER='(0,0,0,0,0,0,0,0,0,0,0,0,0,T5,0,0,0,0,0,0,0,0,0,0,0,0,0,0,0,0)~
';
      INPUT_LOAD='(-0.01,0.01)';
      PINUSE='IN';
    'UPI1_RX_DP'<19>:
      PIN_NUMBER='(0,0,0,0,0,0,0,0,0,0,0,0,0,AA20,0,0,0,0,0,0,0,0,0,0,0,0,0,0,0,~
0)';
      INPUT_LOAD='(-0.01,0.01)';
      PINUSE='IN';
    'UPI1_RX_DP'<18>:
      PIN_NUMBER='(0,0,0,0,0,0,0,0,0,0,0,0,0,W20,0,0,0,0,0,0,0,0,0,0,0,0,0,0,0,0~
)';
      INPUT_LOAD='(-0.01,0.01)';
      PINUSE='IN';
    'UPI1_RX_DP'<17>:
      PIN_NUMBER='(0,0,0,0,0,0,0,0,0,0,0,0,0,Y19,0,0,0,0,0,0,0,0,0,0,0,0,0,0,0,0~
)';
      INPUT_LOAD='(-0.01,0.01)';
      PINUSE='IN';
    'UPI1_RX_DP'<16>:
      PIN_NUMBER='(0,0,0,0,0,0,0,0,0,0,0,0,0,T21,0,0,0,0,0,0,0,0,0,0,0,0,0,0,0,0~
)';
      INPUT_LOAD='(-0.01,0.01)';
      PINUSE='IN';
    'UPI1_RX_DP'<15>:
      PIN_NUMBER='(0,0,0,0,0,0,0,0,0,0,0,0,0,T19,0,0,0,0,0,0,0,0,0,0,0,0,0,0,0,0~
)';
      INPUT_LOAD='(-0.01,0.01)';
      PINUSE='IN';
    'UPI1_RX_DP'<14>:
      PIN_NUMBER='(0,0,0,0,0,0,0,0,0,0,0,0,0,P19,0,0,0,0,0,0,0,0,0,0,0,0,0,0,0,0~
)';
      INPUT_LOAD='(-0.01,0.01)';
      PINUSE='IN';
    'UPI1_RX_DP'<13>:
      PIN_NUMBER='(0,0,0,0,0,0,0,0,0,0,0,0,0,V17,0,0,0,0,0,0,0,0,0,0,0,0,0,0,0,0~
)';
      INPUT_LOAD='(-0.01,0.01)';
      PINUSE='IN';
    'UPI1_RX_DP'<12>:
      PIN_NUMBER='(0,0,0,0,0,0,0,0,0,0,0,0,0,W16,0,0,0,0,0,0,0,0,0,0,0,0,0,0,0,0~
)';
      INPUT_LOAD='(-0.01,0.01)';
      PINUSE='IN';
    'UPI1_RX_DP'<11>:
      PIN_NUMBER='(0,0,0,0,0,0,0,0,0,0,0,0,0,N16,0,0,0,0,0,0,0,0,0,0,0,0,0,0,0,0~
)';
      INPUT_LOAD='(-0.01,0.01)';
      PINUSE='IN';
    'UPI1_RX_DP'<10>:
      PIN_NUMBER='(0,0,0,0,0,0,0,0,0,0,0,0,0,T15,0,0,0,0,0,0,0,0,0,0,0,0,0,0,0,0~
)';
      INPUT_LOAD='(-0.01,0.01)';
      PINUSE='IN';
    'UPI1_RX_DP'<9>:
      PIN_NUMBER='(0,0,0,0,0,0,0,0,0,0,0,0,0,P13,0,0,0,0,0,0,0,0,0,0,0,0,0,0,0,0~
)';
      INPUT_LOAD='(-0.01,0.01)';
      PINUSE='IN';
    'UPI1_RX_DP'<8>:
      PIN_NUMBER='(0,0,0,0,0,0,0,0,0,0,0,0,0,M13,0,0,0,0,0,0,0,0,0,0,0,0,0,0,0,0~
)';
      INPUT_LOAD='(-0.01,0.01)';
      PINUSE='IN';
    'UPI1_RX_DP'<7>:
      PIN_NUMBER='(0,0,0,0,0,0,0,0,0,0,0,0,0,N12,0,0,0,0,0,0,0,0,0,0,0,0,0,0,0,0~
)';
      INPUT_LOAD='(-0.01,0.01)';
      PINUSE='IN';
    'UPI1_RX_DP'<6>:
      PIN_NUMBER='(0,0,0,0,0,0,0,0,0,0,0,0,0,T11,0,0,0,0,0,0,0,0,0,0,0,0,0,0,0,0~
)';
      INPUT_LOAD='(-0.01,0.01)';
      PINUSE='IN';
    'UPI1_RX_DP'<5>:
      PIN_NUMBER='(0,0,0,0,0,0,0,0,0,0,0,0,0,U10,0,0,0,0,0,0,0,0,0,0,0,0,0,0,0,0~
)';
      INPUT_LOAD='(-0.01,0.01)';
      PINUSE='IN';
    'UPI1_RX_DP'<4>:
      PIN_NUMBER='(0,0,0,0,0,0,0,0,0,0,0,0,0,N10,0,0,0,0,0,0,0,0,0,0,0,0,0,0,0,0~
)';
      INPUT_LOAD='(-0.01,0.01)';
      PINUSE='IN';
    'UPI1_RX_DP'<3>:
      PIN_NUMBER='(0,0,0,0,0,0,0,0,0,0,0,0,0,R8,0,0,0,0,0,0,0,0,0,0,0,0,0,0,0,0)~
';
      INPUT_LOAD='(-0.01,0.01)';
      PINUSE='IN';
    'UPI1_RX_DP'<2>:
      PIN_NUMBER='(0,0,0,0,0,0,0,0,0,0,0,0,0,U8,0,0,0,0,0,0,0,0,0,0,0,0,0,0,0,0)~
';
      INPUT_LOAD='(-0.01,0.01)';
      PINUSE='IN';
    'UPI1_RX_DP'<1>:
      PIN_NUMBER='(0,0,0,0,0,0,0,0,0,0,0,0,0,T7,0,0,0,0,0,0,0,0,0,0,0,0,0,0,0,0)~
';
      INPUT_LOAD='(-0.01,0.01)';
      PINUSE='IN';
    'UPI1_RX_DP'<0>:
      PIN_NUMBER='(0,0,0,0,0,0,0,0,0,0,0,0,0,R6,0,0,0,0,0,0,0,0,0,0,0,0,0,0,0,0)~
';
      INPUT_LOAD='(-0.01,0.01)';
      PINUSE='IN';
    'UPI1_TX_DN'<19>:
      PIN_NUMBER='(0,0,0,0,0,0,0,0,0,0,0,0,0,H21,0,0,0,0,0,0,0,0,0,0,0,0,0,0,0,0~
)';
      OUTPUT_LOAD='(1.0,-1.0)';
      PINUSE='OUT';
    'UPI1_TX_DN'<18>:
      PIN_NUMBER='(0,0,0,0,0,0,0,0,0,0,0,0,0,F21,0,0,0,0,0,0,0,0,0,0,0,0,0,0,0,0~
)';
      OUTPUT_LOAD='(1.0,-1.0)';
      PINUSE='OUT';
    'UPI1_TX_DN'<17>:
      PIN_NUMBER='(0,0,0,0,0,0,0,0,0,0,0,0,0,J20,0,0,0,0,0,0,0,0,0,0,0,0,0,0,0,0~
)';
      OUTPUT_LOAD='(1.0,-1.0)';
      PINUSE='OUT';
    'UPI1_TX_DN'<16>:
      PIN_NUMBER='(0,0,0,0,0,0,0,0,0,0,0,0,0,G18,0,0,0,0,0,0,0,0,0,0,0,0,0,0,0,0~
)';
      OUTPUT_LOAD='(1.0,-1.0)';
      PINUSE='OUT';
    'UPI1_TX_DN'<15>:
      PIN_NUMBER='(0,0,0,0,0,0,0,0,0,0,0,0,0,K19,0,0,0,0,0,0,0,0,0,0,0,0,0,0,0,0~
)';
      OUTPUT_LOAD='(1.0,-1.0)';
      PINUSE='OUT';
    'UPI1_TX_DN'<14>:
      PIN_NUMBER='(0,0,0,0,0,0,0,0,0,0,0,0,0,H17,0,0,0,0,0,0,0,0,0,0,0,0,0,0,0,0~
)';
      OUTPUT_LOAD='(1.0,-1.0)';
      PINUSE='OUT';
    'UPI1_TX_DN'<13>:
      PIN_NUMBER='(0,0,0,0,0,0,0,0,0,0,0,0,0,F15,0,0,0,0,0,0,0,0,0,0,0,0,0,0,0,0~
)';
      OUTPUT_LOAD='(1.0,-1.0)';
      PINUSE='OUT';
    'UPI1_TX_DN'<12>:
      PIN_NUMBER='(0,0,0,0,0,0,0,0,0,0,0,0,0,D15,0,0,0,0,0,0,0,0,0,0,0,0,0,0,0,0~
)';
      OUTPUT_LOAD='(1.0,-1.0)';
      PINUSE='OUT';
    'UPI1_TX_DN'<11>:
      PIN_NUMBER='(0,0,0,0,0,0,0,0,0,0,0,0,0,G14,0,0,0,0,0,0,0,0,0,0,0,0,0,0,0,0~
)';
      OUTPUT_LOAD='(1.0,-1.0)';
      PINUSE='OUT';
    'UPI1_TX_DN'<10>:
      PIN_NUMBER='(0,0,0,0,0,0,0,0,0,0,0,0,0,E12,0,0,0,0,0,0,0,0,0,0,0,0,0,0,0,0~
)';
      OUTPUT_LOAD='(1.0,-1.0)';
      PINUSE='OUT';
    'UPI1_TX_DN'<9>:
      PIN_NUMBER='(0,0,0,0,0,0,0,0,0,0,0,0,0,G10,0,0,0,0,0,0,0,0,0,0,0,0,0,0,0,0~
)';
      OUTPUT_LOAD='(1.0,-1.0)';
      PINUSE='OUT';
    'UPI1_TX_DN'<8>:
      PIN_NUMBER='(0,0,0,0,0,0,0,0,0,0,0,0,0,F11,0,0,0,0,0,0,0,0,0,0,0,0,0,0,0,0~
)';
      OUTPUT_LOAD='(1.0,-1.0)';
      PINUSE='OUT';
    'UPI1_TX_DN'<7>:
      PIN_NUMBER='(0,0,0,0,0,0,0,0,0,0,0,0,0,D9,0,0,0,0,0,0,0,0,0,0,0,0,0,0,0,0)~
';
      OUTPUT_LOAD='(1.0,-1.0)';
      PINUSE='OUT';
    'UPI1_TX_DN'<6>:
      PIN_NUMBER='(0,0,0,0,0,0,0,0,0,0,0,0,0,K9,0,0,0,0,0,0,0,0,0,0,0,0,0,0,0,0)~
';
      OUTPUT_LOAD='(1.0,-1.0)';
      PINUSE='OUT';
    'UPI1_TX_DN'<5>:
      PIN_NUMBER='(0,0,0,0,0,0,0,0,0,0,0,0,0,H7,0,0,0,0,0,0,0,0,0,0,0,0,0,0,0,0)~
';
      OUTPUT_LOAD='(1.0,-1.0)';
      PINUSE='OUT';
    'UPI1_TX_DN'<4>:
      PIN_NUMBER='(0,0,0,0,0,0,0,0,0,0,0,0,0,G6,0,0,0,0,0,0,0,0,0,0,0,0,0,0,0,0)~
';
      OUTPUT_LOAD='(1.0,-1.0)';
      PINUSE='OUT';
    'UPI1_TX_DN'<3>:
      PIN_NUMBER='(0,0,0,0,0,0,0,0,0,0,0,0,0,J6,0,0,0,0,0,0,0,0,0,0,0,0,0,0,0,0)~
';
      OUTPUT_LOAD='(1.0,-1.0)';
      PINUSE='OUT';
    'UPI1_TX_DN'<2>:
      PIN_NUMBER='(0,0,0,0,0,0,0,0,0,0,0,0,0,K5,0,0,0,0,0,0,0,0,0,0,0,0,0,0,0,0)~
';
      OUTPUT_LOAD='(1.0,-1.0)';
      PINUSE='OUT';
    'UPI1_TX_DN'<1>:
      PIN_NUMBER='(0,0,0,0,0,0,0,0,0,0,0,0,0,L4,0,0,0,0,0,0,0,0,0,0,0,0,0,0,0,0)~
';
      OUTPUT_LOAD='(1.0,-1.0)';
      PINUSE='OUT';
    'UPI1_TX_DN'<0>:
      PIN_NUMBER='(0,0,0,0,0,0,0,0,0,0,0,0,0,M3,0,0,0,0,0,0,0,0,0,0,0,0,0,0,0,0)~
';
      OUTPUT_LOAD='(1.0,-1.0)';
      PINUSE='OUT';
    'UPI1_TX_DP'<19>:
      PIN_NUMBER='(0,0,0,0,0,0,0,0,0,0,0,0,0,K21,0,0,0,0,0,0,0,0,0,0,0,0,0,0,0,0~
)';
      OUTPUT_LOAD='(1.0,-1.0)';
      PINUSE='OUT';
    'UPI1_TX_DP'<18>:
      PIN_NUMBER='(0,0,0,0,0,0,0,0,0,0,0,0,0,G20,0,0,0,0,0,0,0,0,0,0,0,0,0,0,0,0~
)';
      OUTPUT_LOAD='(1.0,-1.0)';
      PINUSE='OUT';
    'UPI1_TX_DP'<17>:
      PIN_NUMBER='(0,0,0,0,0,0,0,0,0,0,0,0,0,H19,0,0,0,0,0,0,0,0,0,0,0,0,0,0,0,0~
)';
      OUTPUT_LOAD='(1.0,-1.0)';
      PINUSE='OUT';
    'UPI1_TX_DP'<16>:
      PIN_NUMBER='(0,0,0,0,0,0,0,0,0,0,0,0,0,J18,0,0,0,0,0,0,0,0,0,0,0,0,0,0,0,0~
)';
      OUTPUT_LOAD='(1.0,-1.0)';
      PINUSE='OUT';
    'UPI1_TX_DP'<15>:
      PIN_NUMBER='(0,0,0,0,0,0,0,0,0,0,0,0,0,L18,0,0,0,0,0,0,0,0,0,0,0,0,0,0,0,0~
)';
      OUTPUT_LOAD='(1.0,-1.0)';
      PINUSE='OUT';
    'UPI1_TX_DP'<14>:
      PIN_NUMBER='(0,0,0,0,0,0,0,0,0,0,0,0,0,G16,0,0,0,0,0,0,0,0,0,0,0,0,0,0,0,0~
)';
      OUTPUT_LOAD='(1.0,-1.0)';
      PINUSE='OUT';
    'UPI1_TX_DP'<13>:
      PIN_NUMBER='(0,0,0,0,0,0,0,0,0,0,0,0,0,H15,0,0,0,0,0,0,0,0,0,0,0,0,0,0,0,0~
)';
      OUTPUT_LOAD='(1.0,-1.0)';
      PINUSE='OUT';
    'UPI1_TX_DP'<12>:
      PIN_NUMBER='(0,0,0,0,0,0,0,0,0,0,0,0,0,E14,0,0,0,0,0,0,0,0,0,0,0,0,0,0,0,0~
)';
      OUTPUT_LOAD='(1.0,-1.0)';
      PINUSE='OUT';
    'UPI1_TX_DP'<11>:
      PIN_NUMBER='(0,0,0,0,0,0,0,0,0,0,0,0,0,F13,0,0,0,0,0,0,0,0,0,0,0,0,0,0,0,0~
)';
      OUTPUT_LOAD='(1.0,-1.0)';
      PINUSE='OUT';
    'UPI1_TX_DP'<10>:
      PIN_NUMBER='(0,0,0,0,0,0,0,0,0,0,0,0,0,G12,0,0,0,0,0,0,0,0,0,0,0,0,0,0,0,0~
)';
      OUTPUT_LOAD='(1.0,-1.0)';
      PINUSE='OUT';
    'UPI1_TX_DP'<9>:
      PIN_NUMBER='(0,0,0,0,0,0,0,0,0,0,0,0,0,H9,0,0,0,0,0,0,0,0,0,0,0,0,0,0,0,0)~
';
      OUTPUT_LOAD='(1.0,-1.0)';
      PINUSE='OUT';
    'UPI1_TX_DP'<8>:
      PIN_NUMBER='(0,0,0,0,0,0,0,0,0,0,0,0,0,E10,0,0,0,0,0,0,0,0,0,0,0,0,0,0,0,0~
)';
      OUTPUT_LOAD='(1.0,-1.0)';
      PINUSE='OUT';
    'UPI1_TX_DP'<7>:
      PIN_NUMBER='(0,0,0,0,0,0,0,0,0,0,0,0,0,F9,0,0,0,0,0,0,0,0,0,0,0,0,0,0,0,0)~
';
      OUTPUT_LOAD='(1.0,-1.0)';
      PINUSE='OUT';
    'UPI1_TX_DP'<6>:
      PIN_NUMBER='(0,0,0,0,0,0,0,0,0,0,0,0,0,J8,0,0,0,0,0,0,0,0,0,0,0,0,0,0,0,0)~
';
      OUTPUT_LOAD='(1.0,-1.0)';
      PINUSE='OUT';
    'UPI1_TX_DP'<5>:
      PIN_NUMBER='(0,0,0,0,0,0,0,0,0,0,0,0,0,K7,0,0,0,0,0,0,0,0,0,0,0,0,0,0,0,0)~
';
      OUTPUT_LOAD='(1.0,-1.0)';
      PINUSE='OUT';
    'UPI1_TX_DP'<4>:
      PIN_NUMBER='(0,0,0,0,0,0,0,0,0,0,0,0,0,F7,0,0,0,0,0,0,0,0,0,0,0,0,0,0,0,0)~
';
      OUTPUT_LOAD='(1.0,-1.0)';
      PINUSE='OUT';
    'UPI1_TX_DP'<3>:
      PIN_NUMBER='(0,0,0,0,0,0,0,0,0,0,0,0,0,H5,0,0,0,0,0,0,0,0,0,0,0,0,0,0,0,0)~
';
      OUTPUT_LOAD='(1.0,-1.0)';
      PINUSE='OUT';
    'UPI1_TX_DP'<2>:
      PIN_NUMBER='(0,0,0,0,0,0,0,0,0,0,0,0,0,M5,0,0,0,0,0,0,0,0,0,0,0,0,0,0,0,0)~
';
      OUTPUT_LOAD='(1.0,-1.0)';
      PINUSE='OUT';
    'UPI1_TX_DP'<1>:
      PIN_NUMBER='(0,0,0,0,0,0,0,0,0,0,0,0,0,K3,0,0,0,0,0,0,0,0,0,0,0,0,0,0,0,0)~
';
      OUTPUT_LOAD='(1.0,-1.0)';
      PINUSE='OUT';
    'UPI1_TX_DP'<0>:
      PIN_NUMBER='(0,0,0,0,0,0,0,0,0,0,0,0,0,P3,0,0,0,0,0,0,0,0,0,0,0,0,0,0,0,0)~
';
      OUTPUT_LOAD='(1.0,-1.0)';
      PINUSE='OUT';
    'UPI2_RBIAS'<1>:
      PIN_NUMBER='(CK29,0,0,0,0,0,0,0,0,0,0,0,0,0,0,0,0,0,0,0,0,0,0,0,0,0,0,0,0,~
0)';
      INPUT_LOAD='(-0.01,0.01)';
      PINUSE='IN';
    'UPI2_RBIAS'<0>:
      PIN_NUMBER='(CL28,0,0,0,0,0,0,0,0,0,0,0,0,0,0,0,0,0,0,0,0,0,0,0,0,0,0,0,0,~
0)';
      INPUT_LOAD='(-0.01,0.01)';
      PINUSE='IN';
    'UPI2_RX_DN'<19>:
      PIN_NUMBER='(0,0,0,0,0,0,0,0,0,0,0,0,0,0,BY17,0,0,0,0,0,0,0,0,0,0,0,0,0,0,~
0)';
      INPUT_LOAD='(-0.01,0.01)';
      PINUSE='IN';
    'UPI2_RX_DN'<18>:
      PIN_NUMBER='(0,0,0,0,0,0,0,0,0,0,0,0,0,0,CB15,0,0,0,0,0,0,0,0,0,0,0,0,0,0,~
0)';
      INPUT_LOAD='(-0.01,0.01)';
      PINUSE='IN';
    'UPI2_RX_DN'<17>:
      PIN_NUMBER='(0,0,0,0,0,0,0,0,0,0,0,0,0,0,CF17,0,0,0,0,0,0,0,0,0,0,0,0,0,0,~
0)';
      INPUT_LOAD='(-0.01,0.01)';
      PINUSE='IN';
    'UPI2_RX_DN'<16>:
      PIN_NUMBER='(0,0,0,0,0,0,0,0,0,0,0,0,0,0,CD15,0,0,0,0,0,0,0,0,0,0,0,0,0,0,~
0)';
      INPUT_LOAD='(-0.01,0.01)';
      PINUSE='IN';
    'UPI2_RX_DN'<15>:
      PIN_NUMBER='(0,0,0,0,0,0,0,0,0,0,0,0,0,0,CE16,0,0,0,0,0,0,0,0,0,0,0,0,0,0,~
0)';
      INPUT_LOAD='(-0.01,0.01)';
      PINUSE='IN';
    'UPI2_RX_DN'<14>:
      PIN_NUMBER='(0,0,0,0,0,0,0,0,0,0,0,0,0,0,CH17,0,0,0,0,0,0,0,0,0,0,0,0,0,0,~
0)';
      INPUT_LOAD='(-0.01,0.01)';
      PINUSE='IN';
    'UPI2_RX_DN'<13>:
      PIN_NUMBER='(0,0,0,0,0,0,0,0,0,0,0,0,0,0,CJ18,0,0,0,0,0,0,0,0,0,0,0,0,0,0,~
0)';
      INPUT_LOAD='(-0.01,0.01)';
      PINUSE='IN';
    'UPI2_RX_DN'<12>:
      PIN_NUMBER='(0,0,0,0,0,0,0,0,0,0,0,0,0,0,CL16,0,0,0,0,0,0,0,0,0,0,0,0,0,0,~
0)';
      INPUT_LOAD='(-0.01,0.01)';
      PINUSE='IN';
    'UPI2_RX_DN'<11>:
      PIN_NUMBER='(0,0,0,0,0,0,0,0,0,0,0,0,0,0,CP21,0,0,0,0,0,0,0,0,0,0,0,0,0,0,~
0)';
      INPUT_LOAD='(-0.01,0.01)';
      PINUSE='IN';
    'UPI2_RX_DN'<10>:
      PIN_NUMBER='(0,0,0,0,0,0,0,0,0,0,0,0,0,0,CN20,0,0,0,0,0,0,0,0,0,0,0,0,0,0,~
0)';
      INPUT_LOAD='(-0.01,0.01)';
      PINUSE='IN';
    'UPI2_RX_DN'<9>:
      PIN_NUMBER='(0,0,0,0,0,0,0,0,0,0,0,0,0,0,CR18,0,0,0,0,0,0,0,0,0,0,0,0,0,0,~
0)';
      INPUT_LOAD='(-0.01,0.01)';
      PINUSE='IN';
    'UPI2_RX_DN'<8>:
      PIN_NUMBER='(0,0,0,0,0,0,0,0,0,0,0,0,0,0,CT21,0,0,0,0,0,0,0,0,0,0,0,0,0,0,~
0)';
      INPUT_LOAD='(-0.01,0.01)';
      PINUSE='IN';
    'UPI2_RX_DN'<7>:
      PIN_NUMBER='(0,0,0,0,0,0,0,0,0,0,0,0,0,0,CV19,0,0,0,0,0,0,0,0,0,0,0,0,0,0,~
0)';
      INPUT_LOAD='(-0.01,0.01)';
      PINUSE='IN';
    'UPI2_RX_DN'<6>:
      PIN_NUMBER='(0,0,0,0,0,0,0,0,0,0,0,0,0,0,CW20,0,0,0,0,0,0,0,0,0,0,0,0,0,0,~
0)';
      INPUT_LOAD='(-0.01,0.01)';
      PINUSE='IN';
    'UPI2_RX_DN'<5>:
      PIN_NUMBER='(0,0,0,0,0,0,0,0,0,0,0,0,0,0,DA20,0,0,0,0,0,0,0,0,0,0,0,0,0,0,~
0)';
      INPUT_LOAD='(-0.01,0.01)';
      PINUSE='IN';
    'UPI2_RX_DN'<4>:
      PIN_NUMBER='(0,0,0,0,0,0,0,0,0,0,0,0,0,0,DD19,0,0,0,0,0,0,0,0,0,0,0,0,0,0,~
0)';
      INPUT_LOAD='(-0.01,0.01)';
      PINUSE='IN';
    'UPI2_RX_DN'<3>:
      PIN_NUMBER='(0,0,0,0,0,0,0,0,0,0,0,0,0,0,DB21,0,0,0,0,0,0,0,0,0,0,0,0,0,0,~
0)';
      INPUT_LOAD='(-0.01,0.01)';
      PINUSE='IN';
    'UPI2_RX_DN'<2>:
      PIN_NUMBER='(0,0,0,0,0,0,0,0,0,0,0,0,0,0,DC22,0,0,0,0,0,0,0,0,0,0,0,0,0,0,~
0)';
      INPUT_LOAD='(-0.01,0.01)';
      PINUSE='IN';
    'UPI2_RX_DN'<1>:
      PIN_NUMBER='(0,0,0,0,0,0,0,0,0,0,0,0,0,0,DE22,0,0,0,0,0,0,0,0,0,0,0,0,0,0,~
0)';
      INPUT_LOAD='(-0.01,0.01)';
      PINUSE='IN';
    'UPI2_RX_DN'<0>:
      PIN_NUMBER='(0,0,0,0,0,0,0,0,0,0,0,0,0,0,DF23,0,0,0,0,0,0,0,0,0,0,0,0,0,0,~
0)';
      INPUT_LOAD='(-0.01,0.01)';
      PINUSE='IN';
    'UPI2_RX_DP'<19>:
      PIN_NUMBER='(0,0,0,0,0,0,0,0,0,0,0,0,0,0,CA16,0,0,0,0,0,0,0,0,0,0,0,0,0,0,~
0)';
      INPUT_LOAD='(-0.01,0.01)';
      PINUSE='IN';
    'UPI2_RX_DP'<18>:
      PIN_NUMBER='(0,0,0,0,0,0,0,0,0,0,0,0,0,0,BY15,0,0,0,0,0,0,0,0,0,0,0,0,0,0,~
0)';
      INPUT_LOAD='(-0.01,0.01)';
      PINUSE='IN';
    'UPI2_RX_DP'<17>:
      PIN_NUMBER='(0,0,0,0,0,0,0,0,0,0,0,0,0,0,CD17,0,0,0,0,0,0,0,0,0,0,0,0,0,0,~
0)';
      INPUT_LOAD='(-0.01,0.01)';
      PINUSE='IN';
    'UPI2_RX_DP'<16>:
      PIN_NUMBER='(0,0,0,0,0,0,0,0,0,0,0,0,0,0,CC14,0,0,0,0,0,0,0,0,0,0,0,0,0,0,~
0)';
      INPUT_LOAD='(-0.01,0.01)';
      PINUSE='IN';
    'UPI2_RX_DP'<15>:
      PIN_NUMBER='(0,0,0,0,0,0,0,0,0,0,0,0,0,0,CF15,0,0,0,0,0,0,0,0,0,0,0,0,0,0,~
0)';
      INPUT_LOAD='(-0.01,0.01)';
      PINUSE='IN';
    'UPI2_RX_DP'<14>:
      PIN_NUMBER='(0,0,0,0,0,0,0,0,0,0,0,0,0,0,CG16,0,0,0,0,0,0,0,0,0,0,0,0,0,0,~
0)';
      INPUT_LOAD='(-0.01,0.01)';
      PINUSE='IN';
    'UPI2_RX_DP'<13>:
      PIN_NUMBER='(0,0,0,0,0,0,0,0,0,0,0,0,0,0,CK17,0,0,0,0,0,0,0,0,0,0,0,0,0,0,~
0)';
      INPUT_LOAD='(-0.01,0.01)';
      PINUSE='IN';
    'UPI2_RX_DP'<12>:
      PIN_NUMBER='(0,0,0,0,0,0,0,0,0,0,0,0,0,0,CJ16,0,0,0,0,0,0,0,0,0,0,0,0,0,0,~
0)';
      INPUT_LOAD='(-0.01,0.01)';
      PINUSE='IN';
    'UPI2_RX_DP'<11>:
      PIN_NUMBER='(0,0,0,0,0,0,0,0,0,0,0,0,0,0,CM21,0,0,0,0,0,0,0,0,0,0,0,0,0,0,~
0)';
      INPUT_LOAD='(-0.01,0.01)';
      PINUSE='IN';
    'UPI2_RX_DP'<10>:
      PIN_NUMBER='(0,0,0,0,0,0,0,0,0,0,0,0,0,0,CP19,0,0,0,0,0,0,0,0,0,0,0,0,0,0,~
0)';
      INPUT_LOAD='(-0.01,0.01)';
      PINUSE='IN';
    'UPI2_RX_DP'<9>:
      PIN_NUMBER='(0,0,0,0,0,0,0,0,0,0,0,0,0,0,CN18,0,0,0,0,0,0,0,0,0,0,0,0,0,0,~
0)';
      INPUT_LOAD='(-0.01,0.01)';
      PINUSE='IN';
    'UPI2_RX_DP'<8>:
      PIN_NUMBER='(0,0,0,0,0,0,0,0,0,0,0,0,0,0,CR20,0,0,0,0,0,0,0,0,0,0,0,0,0,0,~
0)';
      INPUT_LOAD='(-0.01,0.01)';
      PINUSE='IN';
    'UPI2_RX_DP'<7>:
      PIN_NUMBER='(0,0,0,0,0,0,0,0,0,0,0,0,0,0,CW18,0,0,0,0,0,0,0,0,0,0,0,0,0,0,~
0)';
      INPUT_LOAD='(-0.01,0.01)';
      PINUSE='IN';
    'UPI2_RX_DP'<6>:
      PIN_NUMBER='(0,0,0,0,0,0,0,0,0,0,0,0,0,0,CU20,0,0,0,0,0,0,0,0,0,0,0,0,0,0,~
0)';
      INPUT_LOAD='(-0.01,0.01)';
      PINUSE='IN';
    'UPI2_RX_DP'<5>:
      PIN_NUMBER='(0,0,0,0,0,0,0,0,0,0,0,0,0,0,CY19,0,0,0,0,0,0,0,0,0,0,0,0,0,0,~
0)';
      INPUT_LOAD='(-0.01,0.01)';
      PINUSE='IN';
    'UPI2_RX_DP'<4>:
      PIN_NUMBER='(0,0,0,0,0,0,0,0,0,0,0,0,0,0,DB19,0,0,0,0,0,0,0,0,0,0,0,0,0,0,~
0)';
      INPUT_LOAD='(-0.01,0.01)';
      PINUSE='IN';
    'UPI2_RX_DP'<3>:
      PIN_NUMBER='(0,0,0,0,0,0,0,0,0,0,0,0,0,0,DC20,0,0,0,0,0,0,0,0,0,0,0,0,0,0,~
0)';
      INPUT_LOAD='(-0.01,0.01)';
      PINUSE='IN';
    'UPI2_RX_DP'<2>:
      PIN_NUMBER='(0,0,0,0,0,0,0,0,0,0,0,0,0,0,DA22,0,0,0,0,0,0,0,0,0,0,0,0,0,0,~
0)';
      INPUT_LOAD='(-0.01,0.01)';
      PINUSE='IN';
    'UPI2_RX_DP'<1>:
      PIN_NUMBER='(0,0,0,0,0,0,0,0,0,0,0,0,0,0,DD21,0,0,0,0,0,0,0,0,0,0,0,0,0,0,~
0)';
      INPUT_LOAD='(-0.01,0.01)';
      PINUSE='IN';
    'UPI2_RX_DP'<0>:
      PIN_NUMBER='(0,0,0,0,0,0,0,0,0,0,0,0,0,0,DG22,0,0,0,0,0,0,0,0,0,0,0,0,0,0,~
0)';
      INPUT_LOAD='(-0.01,0.01)';
      PINUSE='IN';
    'UPI2_TX_DN'<19>:
      PIN_NUMBER='(0,0,0,0,0,0,0,0,0,0,0,0,0,0,CC12,0,0,0,0,0,0,0,0,0,0,0,0,0,0,~
0)';
      OUTPUT_LOAD='(1.0,-1.0)';
      PINUSE='OUT';
    'UPI2_TX_DN'<18>:
      PIN_NUMBER='(0,0,0,0,0,0,0,0,0,0,0,0,0,0,CC10,0,0,0,0,0,0,0,0,0,0,0,0,0,0,~
0)';
      OUTPUT_LOAD='(1.0,-1.0)';
      PINUSE='OUT';
    'UPI2_TX_DN'<17>:
      PIN_NUMBER='(0,0,0,0,0,0,0,0,0,0,0,0,0,0,CE12,0,0,0,0,0,0,0,0,0,0,0,0,0,0,~
0)';
      OUTPUT_LOAD='(1.0,-1.0)';
      PINUSE='OUT';
    'UPI2_TX_DN'<16>:
      PIN_NUMBER='(0,0,0,0,0,0,0,0,0,0,0,0,0,0,CH11,0,0,0,0,0,0,0,0,0,0,0,0,0,0,~
0)';
      OUTPUT_LOAD='(1.0,-1.0)';
      PINUSE='OUT';
    'UPI2_TX_DN'<15>:
      PIN_NUMBER='(0,0,0,0,0,0,0,0,0,0,0,0,0,0,CF13,0,0,0,0,0,0,0,0,0,0,0,0,0,0,~
0)';
      OUTPUT_LOAD='(1.0,-1.0)';
      PINUSE='OUT';
    'UPI2_TX_DN'<14>:
      PIN_NUMBER='(0,0,0,0,0,0,0,0,0,0,0,0,0,0,CJ14,0,0,0,0,0,0,0,0,0,0,0,0,0,0,~
0)';
      OUTPUT_LOAD='(1.0,-1.0)';
      PINUSE='OUT';
    'UPI2_TX_DN'<13>:
      PIN_NUMBER='(0,0,0,0,0,0,0,0,0,0,0,0,0,0,CM13,0,0,0,0,0,0,0,0,0,0,0,0,0,0,~
0)';
      OUTPUT_LOAD='(1.0,-1.0)';
      PINUSE='OUT';
    'UPI2_TX_DN'<12>:
      PIN_NUMBER='(0,0,0,0,0,0,0,0,0,0,0,0,0,0,CU14,0,0,0,0,0,0,0,0,0,0,0,0,0,0,~
0)';
      OUTPUT_LOAD='(1.0,-1.0)';
      PINUSE='OUT';
    'UPI2_TX_DN'<11>:
      PIN_NUMBER='(0,0,0,0,0,0,0,0,0,0,0,0,0,0,CW14,0,0,0,0,0,0,0,0,0,0,0,0,0,0,~
0)';
      OUTPUT_LOAD='(1.0,-1.0)';
      PINUSE='OUT';
    'UPI2_TX_DN'<10>:
      PIN_NUMBER='(0,0,0,0,0,0,0,0,0,0,0,0,0,0,DA16,0,0,0,0,0,0,0,0,0,0,0,0,0,0,~
0)';
      OUTPUT_LOAD='(1.0,-1.0)';
      PINUSE='OUT';
    'UPI2_TX_DN'<9>:
      PIN_NUMBER='(0,0,0,0,0,0,0,0,0,0,0,0,0,0,DC16,0,0,0,0,0,0,0,0,0,0,0,0,0,0,~
0)';
      OUTPUT_LOAD='(1.0,-1.0)';
      PINUSE='OUT';
    'UPI2_TX_DN'<8>:
      PIN_NUMBER='(0,0,0,0,0,0,0,0,0,0,0,0,0,0,DF15,0,0,0,0,0,0,0,0,0,0,0,0,0,0,~
0)';
      OUTPUT_LOAD='(1.0,-1.0)';
      PINUSE='OUT';
    'UPI2_TX_DN'<7>:
      PIN_NUMBER='(0,0,0,0,0,0,0,0,0,0,0,0,0,0,DD17,0,0,0,0,0,0,0,0,0,0,0,0,0,0,~
0)';
      OUTPUT_LOAD='(1.0,-1.0)';
      PINUSE='OUT';
    'UPI2_TX_DN'<6>:
      PIN_NUMBER='(0,0,0,0,0,0,0,0,0,0,0,0,0,0,DG18,0,0,0,0,0,0,0,0,0,0,0,0,0,0,~
0)';
      OUTPUT_LOAD='(1.0,-1.0)';
      PINUSE='OUT';
    'UPI2_TX_DN'<5>:
      PIN_NUMBER='(0,0,0,0,0,0,0,0,0,0,0,0,0,0,DK17,0,0,0,0,0,0,0,0,0,0,0,0,0,0,~
0)';
      OUTPUT_LOAD='(1.0,-1.0)';
      PINUSE='OUT';
    'UPI2_TX_DN'<4>:
      PIN_NUMBER='(0,0,0,0,0,0,0,0,0,0,0,0,0,0,DH19,0,0,0,0,0,0,0,0,0,0,0,0,0,0,~
0)';
      OUTPUT_LOAD='(1.0,-1.0)';
      PINUSE='OUT';
    'UPI2_TX_DN'<3>:
      PIN_NUMBER='(0,0,0,0,0,0,0,0,0,0,0,0,0,0,DG20,0,0,0,0,0,0,0,0,0,0,0,0,0,0,~
0)';
      OUTPUT_LOAD='(1.0,-1.0)';
      PINUSE='OUT';
    'UPI2_TX_DN'<2>:
      PIN_NUMBER='(0,0,0,0,0,0,0,0,0,0,0,0,0,0,DL20,0,0,0,0,0,0,0,0,0,0,0,0,0,0,~
0)';
      OUTPUT_LOAD='(1.0,-1.0)';
      PINUSE='OUT';
    'UPI2_TX_DN'<1>:
      PIN_NUMBER='(0,0,0,0,0,0,0,0,0,0,0,0,0,0,DM21,0,0,0,0,0,0,0,0,0,0,0,0,0,0,~
0)';
      OUTPUT_LOAD='(1.0,-1.0)';
      PINUSE='OUT';
    'UPI2_TX_DN'<0>:
      PIN_NUMBER='(0,0,0,0,0,0,0,0,0,0,0,0,0,0,DT21,0,0,0,0,0,0,0,0,0,0,0,0,0,0,~
0)';
      OUTPUT_LOAD='(1.0,-1.0)';
      PINUSE='OUT';
    'UPI2_TX_DP'<19>:
      PIN_NUMBER='(0,0,0,0,0,0,0,0,0,0,0,0,0,0,CA12,0,0,0,0,0,0,0,0,0,0,0,0,0,0,~
0)';
      OUTPUT_LOAD='(1.0,-1.0)';
      PINUSE='OUT';
    'UPI2_TX_DP'<18>:
      PIN_NUMBER='(0,0,0,0,0,0,0,0,0,0,0,0,0,0,CB11,0,0,0,0,0,0,0,0,0,0,0,0,0,0,~
0)';
      OUTPUT_LOAD='(1.0,-1.0)';
      PINUSE='OUT';
    'UPI2_TX_DP'<17>:
      PIN_NUMBER='(0,0,0,0,0,0,0,0,0,0,0,0,0,0,CD11,0,0,0,0,0,0,0,0,0,0,0,0,0,0,~
0)';
      OUTPUT_LOAD='(1.0,-1.0)';
      PINUSE='OUT';
    'UPI2_TX_DP'<16>:
      PIN_NUMBER='(0,0,0,0,0,0,0,0,0,0,0,0,0,0,CF11,0,0,0,0,0,0,0,0,0,0,0,0,0,0,~
0)';
      OUTPUT_LOAD='(1.0,-1.0)';
      PINUSE='OUT';
    'UPI2_TX_DP'<15>:
      PIN_NUMBER='(0,0,0,0,0,0,0,0,0,0,0,0,0,0,CG12,0,0,0,0,0,0,0,0,0,0,0,0,0,0,~
0)';
      OUTPUT_LOAD='(1.0,-1.0)';
      PINUSE='OUT';
    'UPI2_TX_DP'<14>:
      PIN_NUMBER='(0,0,0,0,0,0,0,0,0,0,0,0,0,0,CH13,0,0,0,0,0,0,0,0,0,0,0,0,0,0,~
0)';
      OUTPUT_LOAD='(1.0,-1.0)';
      PINUSE='OUT';
    'UPI2_TX_DP'<13>:
      PIN_NUMBER='(0,0,0,0,0,0,0,0,0,0,0,0,0,0,CK13,0,0,0,0,0,0,0,0,0,0,0,0,0,0,~
0)';
      OUTPUT_LOAD='(1.0,-1.0)';
      PINUSE='OUT';
    'UPI2_TX_DP'<12>:
      PIN_NUMBER='(0,0,0,0,0,0,0,0,0,0,0,0,0,0,CR14,0,0,0,0,0,0,0,0,0,0,0,0,0,0,~
0)';
      OUTPUT_LOAD='(1.0,-1.0)';
      PINUSE='OUT';
    'UPI2_TX_DP'<11>:
      PIN_NUMBER='(0,0,0,0,0,0,0,0,0,0,0,0,0,0,CV13,0,0,0,0,0,0,0,0,0,0,0,0,0,0,~
0)';
      OUTPUT_LOAD='(1.0,-1.0)';
      PINUSE='OUT';
    'UPI2_TX_DP'<10>:
      PIN_NUMBER='(0,0,0,0,0,0,0,0,0,0,0,0,0,0,CW16,0,0,0,0,0,0,0,0,0,0,0,0,0,0,~
0)';
      OUTPUT_LOAD='(1.0,-1.0)';
      PINUSE='OUT';
    'UPI2_TX_DP'<9>:
      PIN_NUMBER='(0,0,0,0,0,0,0,0,0,0,0,0,0,0,DB15,0,0,0,0,0,0,0,0,0,0,0,0,0,0,~
0)';
      OUTPUT_LOAD='(1.0,-1.0)';
      PINUSE='OUT';
    'UPI2_TX_DP'<8>:
      PIN_NUMBER='(0,0,0,0,0,0,0,0,0,0,0,0,0,0,DD15,0,0,0,0,0,0,0,0,0,0,0,0,0,0,~
0)';
      OUTPUT_LOAD='(1.0,-1.0)';
      PINUSE='OUT';
    'UPI2_TX_DP'<7>:
      PIN_NUMBER='(0,0,0,0,0,0,0,0,0,0,0,0,0,0,DE16,0,0,0,0,0,0,0,0,0,0,0,0,0,0,~
0)';
      OUTPUT_LOAD='(1.0,-1.0)';
      PINUSE='OUT';
    'UPI2_TX_DP'<6>:
      PIN_NUMBER='(0,0,0,0,0,0,0,0,0,0,0,0,0,0,DF17,0,0,0,0,0,0,0,0,0,0,0,0,0,0,~
0)';
      OUTPUT_LOAD='(1.0,-1.0)';
      PINUSE='OUT';
    'UPI2_TX_DP'<5>:
      PIN_NUMBER='(0,0,0,0,0,0,0,0,0,0,0,0,0,0,DH17,0,0,0,0,0,0,0,0,0,0,0,0,0,0,~
0)';
      OUTPUT_LOAD='(1.0,-1.0)';
      PINUSE='OUT';
    'UPI2_TX_DP'<4>:
      PIN_NUMBER='(0,0,0,0,0,0,0,0,0,0,0,0,0,0,DJ18,0,0,0,0,0,0,0,0,0,0,0,0,0,0,~
0)';
      OUTPUT_LOAD='(1.0,-1.0)';
      PINUSE='OUT';
    'UPI2_TX_DP'<3>:
      PIN_NUMBER='(0,0,0,0,0,0,0,0,0,0,0,0,0,0,DJ20,0,0,0,0,0,0,0,0,0,0,0,0,0,0,~
0)';
      OUTPUT_LOAD='(1.0,-1.0)';
      PINUSE='OUT';
    'UPI2_TX_DP'<2>:
      PIN_NUMBER='(0,0,0,0,0,0,0,0,0,0,0,0,0,0,DK19,0,0,0,0,0,0,0,0,0,0,0,0,0,0,~
0)';
      OUTPUT_LOAD='(1.0,-1.0)';
      PINUSE='OUT';
    'UPI2_TX_DP'<1>:
      PIN_NUMBER='(0,0,0,0,0,0,0,0,0,0,0,0,0,0,DN20,0,0,0,0,0,0,0,0,0,0,0,0,0,0,~
0)';
      OUTPUT_LOAD='(1.0,-1.0)';
      PINUSE='OUT';
    'UPI2_TX_DP'<0>:
      PIN_NUMBER='(0,0,0,0,0,0,0,0,0,0,0,0,0,0,DP21,0,0,0,0,0,0,0,0,0,0,0,0,0,0,~
0)';
      OUTPUT_LOAD='(1.0,-1.0)';
      PINUSE='OUT';
    'VCC33':
      PIN_NUMBER='(0,0,0,0,0,0,0,0,0,0,0,0,0,0,0,0,0,0,0,0,CY55,0,0,0,0,0,0,0,0,~
0)';
      PINUSE='POWER';
      NO_LOAD_CHECK='Both';
      NO_IO_CHECK='Both';
      NO_ASSERT_CHECK='TRUE';
      NO_DIR_CHECK='TRUE';
      ALLOW_CONNECT='TRUE';
    'VCCD012'<51>:
      PIN_NUMBER='(0,0,0,0,0,0,0,0,0,0,0,0,0,0,0,0,0,0,0,B47,0,0,0,0,0,0,0,0,0,0~
)';
      PINUSE='POWER';
      NO_LOAD_CHECK='Both';
      NO_IO_CHECK='Both';
      NO_ASSERT_CHECK='TRUE';
      NO_DIR_CHECK='TRUE';
      ALLOW_CONNECT='TRUE';
    'VCCD012'<50>:
      PIN_NUMBER='(0,0,0,0,0,0,0,0,0,0,0,0,0,0,0,0,0,0,0,C46,0,0,0,0,0,0,0,0,0,0~
)';
      PINUSE='POWER';
      NO_LOAD_CHECK='Both';
      NO_IO_CHECK='Both';
      NO_ASSERT_CHECK='TRUE';
      NO_DIR_CHECK='TRUE';
      ALLOW_CONNECT='TRUE';
    'VCCD012'<49>:
      PIN_NUMBER='(0,0,0,0,0,0,0,0,0,0,0,0,0,0,0,0,0,0,0,D45,0,0,0,0,0,0,0,0,0,0~
)';
      PINUSE='POWER';
      NO_LOAD_CHECK='Both';
      NO_IO_CHECK='Both';
      NO_ASSERT_CHECK='TRUE';
      NO_DIR_CHECK='TRUE';
      ALLOW_CONNECT='TRUE';
    'VCCD012'<48>:
      PIN_NUMBER='(0,0,0,0,0,0,0,0,0,0,0,0,0,0,0,0,0,0,0,AF63,0,0,0,0,0,0,0,0,0,~
0)';
      PINUSE='POWER';
      NO_LOAD_CHECK='Both';
      NO_IO_CHECK='Both';
      NO_ASSERT_CHECK='TRUE';
      NO_DIR_CHECK='TRUE';
      ALLOW_CONNECT='TRUE';
    'VCCD012'<47>:
      PIN_NUMBER='(0,0,0,0,0,0,0,0,0,0,0,0,0,0,0,0,0,0,0,AF61,0,0,0,0,0,0,0,0,0,~
0)';
      PINUSE='POWER';
      NO_LOAD_CHECK='Both';
      NO_IO_CHECK='Both';
      NO_ASSERT_CHECK='TRUE';
      NO_DIR_CHECK='TRUE';
      ALLOW_CONNECT='TRUE';
    'VCCD012'<46>:
      PIN_NUMBER='(0,0,0,0,0,0,0,0,0,0,0,0,0,0,0,0,0,0,0,AF59,0,0,0,0,0,0,0,0,0,~
0)';
      PINUSE='POWER';
      NO_LOAD_CHECK='Both';
      NO_IO_CHECK='Both';
      NO_ASSERT_CHECK='TRUE';
      NO_DIR_CHECK='TRUE';
      ALLOW_CONNECT='TRUE';
    'VCCD012'<45>:
      PIN_NUMBER='(0,0,0,0,0,0,0,0,0,0,0,0,0,0,0,0,0,0,0,AF57,0,0,0,0,0,0,0,0,0,~
0)';
      PINUSE='POWER';
      NO_LOAD_CHECK='Both';
      NO_IO_CHECK='Both';
      NO_ASSERT_CHECK='TRUE';
      NO_DIR_CHECK='TRUE';
      ALLOW_CONNECT='TRUE';
    'VCCD012'<44>:
      PIN_NUMBER='(0,0,0,0,0,0,0,0,0,0,0,0,0,0,0,0,0,0,0,AF55,0,0,0,0,0,0,0,0,0,~
0)';
      PINUSE='POWER';
      NO_LOAD_CHECK='Both';
      NO_IO_CHECK='Both';
      NO_ASSERT_CHECK='TRUE';
      NO_DIR_CHECK='TRUE';
      ALLOW_CONNECT='TRUE';
    'VCCD012'<43>:
      PIN_NUMBER='(0,0,0,0,0,0,0,0,0,0,0,0,0,0,0,0,0,0,0,AD45,0,0,0,0,0,0,0,0,0,~
0)';
      PINUSE='POWER';
      NO_LOAD_CHECK='Both';
      NO_IO_CHECK='Both';
      NO_ASSERT_CHECK='TRUE';
      NO_DIR_CHECK='TRUE';
      ALLOW_CONNECT='TRUE';
    'VCCD012'<42>:
      PIN_NUMBER='(0,0,0,0,0,0,0,0,0,0,0,0,0,0,0,0,0,0,0,Y63,0,0,0,0,0,0,0,0,0,0~
)';
      PINUSE='POWER';
      NO_LOAD_CHECK='Both';
      NO_IO_CHECK='Both';
      NO_ASSERT_CHECK='TRUE';
      NO_DIR_CHECK='TRUE';
      ALLOW_CONNECT='TRUE';
    'VCCD012'<41>:
      PIN_NUMBER='(0,0,0,0,0,0,0,0,0,0,0,0,0,0,0,0,0,0,0,Y61,0,0,0,0,0,0,0,0,0,0~
)';
      PINUSE='POWER';
      NO_LOAD_CHECK='Both';
      NO_IO_CHECK='Both';
      NO_ASSERT_CHECK='TRUE';
      NO_DIR_CHECK='TRUE';
      ALLOW_CONNECT='TRUE';
    'VCCD012'<40>:
      PIN_NUMBER='(0,0,0,0,0,0,0,0,0,0,0,0,0,0,0,0,0,0,0,Y59,0,0,0,0,0,0,0,0,0,0~
)';
      PINUSE='POWER';
      NO_LOAD_CHECK='Both';
      NO_IO_CHECK='Both';
      NO_ASSERT_CHECK='TRUE';
      NO_DIR_CHECK='TRUE';
      ALLOW_CONNECT='TRUE';
    'VCCD012'<39>:
      PIN_NUMBER='(0,0,0,0,0,0,0,0,0,0,0,0,0,0,0,0,0,0,0,Y57,0,0,0,0,0,0,0,0,0,0~
)';
      PINUSE='POWER';
      NO_LOAD_CHECK='Both';
      NO_IO_CHECK='Both';
      NO_ASSERT_CHECK='TRUE';
      NO_DIR_CHECK='TRUE';
      ALLOW_CONNECT='TRUE';
    'VCCD012'<38>:
      PIN_NUMBER='(0,0,0,0,0,0,0,0,0,0,0,0,0,0,0,0,0,0,0,Y55,0,0,0,0,0,0,0,0,0,0~
)';
      PINUSE='POWER';
      NO_LOAD_CHECK='Both';
      NO_IO_CHECK='Both';
      NO_ASSERT_CHECK='TRUE';
      NO_DIR_CHECK='TRUE';
      ALLOW_CONNECT='TRUE';
    'VCCD012'<37>:
      PIN_NUMBER='(0,0,0,0,0,0,0,0,0,0,0,0,0,0,0,0,0,0,0,Y53,0,0,0,0,0,0,0,0,0,0~
)';
      PINUSE='POWER';
      NO_LOAD_CHECK='Both';
      NO_IO_CHECK='Both';
      NO_ASSERT_CHECK='TRUE';
      NO_DIR_CHECK='TRUE';
      ALLOW_CONNECT='TRUE';
    'VCCD012'<36>:
      PIN_NUMBER='(0,0,0,0,0,0,0,0,0,0,0,0,0,0,0,0,0,0,0,Y51,0,0,0,0,0,0,0,0,0,0~
)';
      PINUSE='POWER';
      NO_LOAD_CHECK='Both';
      NO_IO_CHECK='Both';
      NO_ASSERT_CHECK='TRUE';
      NO_DIR_CHECK='TRUE';
      ALLOW_CONNECT='TRUE';
    'VCCD012'<35>:
      PIN_NUMBER='(0,0,0,0,0,0,0,0,0,0,0,0,0,0,0,0,0,0,0,Y49,0,0,0,0,0,0,0,0,0,0~
)';
      PINUSE='POWER';
      NO_LOAD_CHECK='Both';
      NO_IO_CHECK='Both';
      NO_ASSERT_CHECK='TRUE';
      NO_DIR_CHECK='TRUE';
      ALLOW_CONNECT='TRUE';
    'VCCD012'<34>:
      PIN_NUMBER='(0,0,0,0,0,0,0,0,0,0,0,0,0,0,0,0,0,0,0,Y47,0,0,0,0,0,0,0,0,0,0~
)';
      PINUSE='POWER';
      NO_LOAD_CHECK='Both';
      NO_IO_CHECK='Both';
      NO_ASSERT_CHECK='TRUE';
      NO_DIR_CHECK='TRUE';
      ALLOW_CONNECT='TRUE';
    'VCCD012'<33>:
      PIN_NUMBER='(0,0,0,0,0,0,0,0,0,0,0,0,0,0,0,0,0,0,0,Y45,0,0,0,0,0,0,0,0,0,0~
)';
      PINUSE='POWER';
      NO_LOAD_CHECK='Both';
      NO_IO_CHECK='Both';
      NO_ASSERT_CHECK='TRUE';
      NO_DIR_CHECK='TRUE';
      ALLOW_CONNECT='TRUE';
    'VCCD012'<32>:
      PIN_NUMBER='(0,0,0,0,0,0,0,0,0,0,0,0,0,0,0,0,0,0,0,W64,0,0,0,0,0,0,0,0,0,0~
)';
      PINUSE='POWER';
      NO_LOAD_CHECK='Both';
      NO_IO_CHECK='Both';
      NO_ASSERT_CHECK='TRUE';
      NO_DIR_CHECK='TRUE';
      ALLOW_CONNECT='TRUE';
    'VCCD012'<31>:
      PIN_NUMBER='(0,0,0,0,0,0,0,0,0,0,0,0,0,0,0,0,0,0,0,U62,0,0,0,0,0,0,0,0,0,0~
)';
      PINUSE='POWER';
      NO_LOAD_CHECK='Both';
      NO_IO_CHECK='Both';
      NO_ASSERT_CHECK='TRUE';
      NO_DIR_CHECK='TRUE';
      ALLOW_CONNECT='TRUE';
    'VCCD012'<30>:
      PIN_NUMBER='(0,0,0,0,0,0,0,0,0,0,0,0,0,0,0,0,0,0,0,U60,0,0,0,0,0,0,0,0,0,0~
)';
      PINUSE='POWER';
      NO_LOAD_CHECK='Both';
      NO_IO_CHECK='Both';
      NO_ASSERT_CHECK='TRUE';
      NO_DIR_CHECK='TRUE';
      ALLOW_CONNECT='TRUE';
    'VCCD012'<29>:
      PIN_NUMBER='(0,0,0,0,0,0,0,0,0,0,0,0,0,0,0,0,0,0,0,U58,0,0,0,0,0,0,0,0,0,0~
)';
      PINUSE='POWER';
      NO_LOAD_CHECK='Both';
      NO_IO_CHECK='Both';
      NO_ASSERT_CHECK='TRUE';
      NO_DIR_CHECK='TRUE';
      ALLOW_CONNECT='TRUE';
    'VCCD012'<28>:
      PIN_NUMBER='(0,0,0,0,0,0,0,0,0,0,0,0,0,0,0,0,0,0,0,U56,0,0,0,0,0,0,0,0,0,0~
)';
      PINUSE='POWER';
      NO_LOAD_CHECK='Both';
      NO_IO_CHECK='Both';
      NO_ASSERT_CHECK='TRUE';
      NO_DIR_CHECK='TRUE';
      ALLOW_CONNECT='TRUE';
    'VCCD012'<27>:
      PIN_NUMBER='(0,0,0,0,0,0,0,0,0,0,0,0,0,0,0,0,0,0,0,U54,0,0,0,0,0,0,0,0,0,0~
)';
      PINUSE='POWER';
      NO_LOAD_CHECK='Both';
      NO_IO_CHECK='Both';
      NO_ASSERT_CHECK='TRUE';
      NO_DIR_CHECK='TRUE';
      ALLOW_CONNECT='TRUE';
    'VCCD012'<26>:
      PIN_NUMBER='(0,0,0,0,0,0,0,0,0,0,0,0,0,0,0,0,0,0,0,U52,0,0,0,0,0,0,0,0,0,0~
)';
      PINUSE='POWER';
      NO_LOAD_CHECK='Both';
      NO_IO_CHECK='Both';
      NO_ASSERT_CHECK='TRUE';
      NO_DIR_CHECK='TRUE';
      ALLOW_CONNECT='TRUE';
    'VCCD012'<25>:
      PIN_NUMBER='(0,0,0,0,0,0,0,0,0,0,0,0,0,0,0,0,0,0,0,U50,0,0,0,0,0,0,0,0,0,0~
)';
      PINUSE='POWER';
      NO_LOAD_CHECK='Both';
      NO_IO_CHECK='Both';
      NO_ASSERT_CHECK='TRUE';
      NO_DIR_CHECK='TRUE';
      ALLOW_CONNECT='TRUE';
    'VCCD012'<24>:
      PIN_NUMBER='(0,0,0,0,0,0,0,0,0,0,0,0,0,0,0,0,0,0,0,U48,0,0,0,0,0,0,0,0,0,0~
)';
      PINUSE='POWER';
      NO_LOAD_CHECK='Both';
      NO_IO_CHECK='Both';
      NO_ASSERT_CHECK='TRUE';
      NO_DIR_CHECK='TRUE';
      ALLOW_CONNECT='TRUE';
    'VCCD012'<23>:
      PIN_NUMBER='(0,0,0,0,0,0,0,0,0,0,0,0,0,0,0,0,0,0,0,U46,0,0,0,0,0,0,0,0,0,0~
)';
      PINUSE='POWER';
      NO_LOAD_CHECK='Both';
      NO_IO_CHECK='Both';
      NO_ASSERT_CHECK='TRUE';
      NO_DIR_CHECK='TRUE';
      ALLOW_CONNECT='TRUE';
    'VCCD012'<22>:
      PIN_NUMBER='(0,0,0,0,0,0,0,0,0,0,0,0,0,0,0,0,0,0,0,N64,0,0,0,0,0,0,0,0,0,0~
)';
      PINUSE='POWER';
      NO_LOAD_CHECK='Both';
      NO_IO_CHECK='Both';
      NO_ASSERT_CHECK='TRUE';
      NO_DIR_CHECK='TRUE';
      ALLOW_CONNECT='TRUE';
    'VCCD012'<21>:
      PIN_NUMBER='(0,0,0,0,0,0,0,0,0,0,0,0,0,0,0,0,0,0,0,L62,0,0,0,0,0,0,0,0,0,0~
)';
      PINUSE='POWER';
      NO_LOAD_CHECK='Both';
      NO_IO_CHECK='Both';
      NO_ASSERT_CHECK='TRUE';
      NO_DIR_CHECK='TRUE';
      ALLOW_CONNECT='TRUE';
    'VCCD012'<20>:
      PIN_NUMBER='(0,0,0,0,0,0,0,0,0,0,0,0,0,0,0,0,0,0,0,L60,0,0,0,0,0,0,0,0,0,0~
)';
      PINUSE='POWER';
      NO_LOAD_CHECK='Both';
      NO_IO_CHECK='Both';
      NO_ASSERT_CHECK='TRUE';
      NO_DIR_CHECK='TRUE';
      ALLOW_CONNECT='TRUE';
    'VCCD012'<19>:
      PIN_NUMBER='(0,0,0,0,0,0,0,0,0,0,0,0,0,0,0,0,0,0,0,L58,0,0,0,0,0,0,0,0,0,0~
)';
      PINUSE='POWER';
      NO_LOAD_CHECK='Both';
      NO_IO_CHECK='Both';
      NO_ASSERT_CHECK='TRUE';
      NO_DIR_CHECK='TRUE';
      ALLOW_CONNECT='TRUE';
    'VCCD012'<18>:
      PIN_NUMBER='(0,0,0,0,0,0,0,0,0,0,0,0,0,0,0,0,0,0,0,L56,0,0,0,0,0,0,0,0,0,0~
)';
      PINUSE='POWER';
      NO_LOAD_CHECK='Both';
      NO_IO_CHECK='Both';
      NO_ASSERT_CHECK='TRUE';
      NO_DIR_CHECK='TRUE';
      ALLOW_CONNECT='TRUE';
    'VCCD012'<17>:
      PIN_NUMBER='(0,0,0,0,0,0,0,0,0,0,0,0,0,0,0,0,0,0,0,L54,0,0,0,0,0,0,0,0,0,0~
)';
      PINUSE='POWER';
      NO_LOAD_CHECK='Both';
      NO_IO_CHECK='Both';
      NO_ASSERT_CHECK='TRUE';
      NO_DIR_CHECK='TRUE';
      ALLOW_CONNECT='TRUE';
    'VCCD012'<16>:
      PIN_NUMBER='(0,0,0,0,0,0,0,0,0,0,0,0,0,0,0,0,0,0,0,L52,0,0,0,0,0,0,0,0,0,0~
)';
      PINUSE='POWER';
      NO_LOAD_CHECK='Both';
      NO_IO_CHECK='Both';
      NO_ASSERT_CHECK='TRUE';
      NO_DIR_CHECK='TRUE';
      ALLOW_CONNECT='TRUE';
    'VCCD012'<15>:
      PIN_NUMBER='(0,0,0,0,0,0,0,0,0,0,0,0,0,0,0,0,0,0,0,L50,0,0,0,0,0,0,0,0,0,0~
)';
      PINUSE='POWER';
      NO_LOAD_CHECK='Both';
      NO_IO_CHECK='Both';
      NO_ASSERT_CHECK='TRUE';
      NO_DIR_CHECK='TRUE';
      ALLOW_CONNECT='TRUE';
    'VCCD012'<14>:
      PIN_NUMBER='(0,0,0,0,0,0,0,0,0,0,0,0,0,0,0,0,0,0,0,L48,0,0,0,0,0,0,0,0,0,0~
)';
      PINUSE='POWER';
      NO_LOAD_CHECK='Both';
      NO_IO_CHECK='Both';
      NO_ASSERT_CHECK='TRUE';
      NO_DIR_CHECK='TRUE';
      ALLOW_CONNECT='TRUE';
    'VCCD012'<13>:
      PIN_NUMBER='(0,0,0,0,0,0,0,0,0,0,0,0,0,0,0,0,0,0,0,L46,0,0,0,0,0,0,0,0,0,0~
)';
      PINUSE='POWER';
      NO_LOAD_CHECK='Both';
      NO_IO_CHECK='Both';
      NO_ASSERT_CHECK='TRUE';
      NO_DIR_CHECK='TRUE';
      ALLOW_CONNECT='TRUE';
    'VCCD012'<12>:
      PIN_NUMBER='(0,0,0,0,0,0,0,0,0,0,0,0,0,0,0,0,0,0,0,E64,0,0,0,0,0,0,0,0,0,0~
)';
      PINUSE='POWER';
      NO_LOAD_CHECK='Both';
      NO_IO_CHECK='Both';
      NO_ASSERT_CHECK='TRUE';
      NO_DIR_CHECK='TRUE';
      ALLOW_CONNECT='TRUE';
    'VCCD012'<11>:
      PIN_NUMBER='(0,0,0,0,0,0,0,0,0,0,0,0,0,0,0,0,0,0,0,E62,0,0,0,0,0,0,0,0,0,0~
)';
      PINUSE='POWER';
      NO_LOAD_CHECK='Both';
      NO_IO_CHECK='Both';
      NO_ASSERT_CHECK='TRUE';
      NO_DIR_CHECK='TRUE';
      ALLOW_CONNECT='TRUE';
    'VCCD012'<10>:
      PIN_NUMBER='(0,0,0,0,0,0,0,0,0,0,0,0,0,0,0,0,0,0,0,E60,0,0,0,0,0,0,0,0,0,0~
)';
      PINUSE='POWER';
      NO_LOAD_CHECK='Both';
      NO_IO_CHECK='Both';
      NO_ASSERT_CHECK='TRUE';
      NO_DIR_CHECK='TRUE';
      ALLOW_CONNECT='TRUE';
    'VCCD012'<9>:
      PIN_NUMBER='(0,0,0,0,0,0,0,0,0,0,0,0,0,0,0,0,0,0,0,E58,0,0,0,0,0,0,0,0,0,0~
)';
      PINUSE='POWER';
      NO_LOAD_CHECK='Both';
      NO_IO_CHECK='Both';
      NO_ASSERT_CHECK='TRUE';
      NO_DIR_CHECK='TRUE';
      ALLOW_CONNECT='TRUE';
    'VCCD012'<8>:
      PIN_NUMBER='(0,0,0,0,0,0,0,0,0,0,0,0,0,0,0,0,0,0,0,E56,0,0,0,0,0,0,0,0,0,0~
)';
      PINUSE='POWER';
      NO_LOAD_CHECK='Both';
      NO_IO_CHECK='Both';
      NO_ASSERT_CHECK='TRUE';
      NO_DIR_CHECK='TRUE';
      ALLOW_CONNECT='TRUE';
    'VCCD012'<7>:
      PIN_NUMBER='(0,0,0,0,0,0,0,0,0,0,0,0,0,0,0,0,0,0,0,E54,0,0,0,0,0,0,0,0,0,0~
)';
      PINUSE='POWER';
      NO_LOAD_CHECK='Both';
      NO_IO_CHECK='Both';
      NO_ASSERT_CHECK='TRUE';
      NO_DIR_CHECK='TRUE';
      ALLOW_CONNECT='TRUE';
    'VCCD012'<6>:
      PIN_NUMBER='(0,0,0,0,0,0,0,0,0,0,0,0,0,0,0,0,0,0,0,E52,0,0,0,0,0,0,0,0,0,0~
)';
      PINUSE='POWER';
      NO_LOAD_CHECK='Both';
      NO_IO_CHECK='Both';
      NO_ASSERT_CHECK='TRUE';
      NO_DIR_CHECK='TRUE';
      ALLOW_CONNECT='TRUE';
    'VCCD012'<5>:
      PIN_NUMBER='(0,0,0,0,0,0,0,0,0,0,0,0,0,0,0,0,0,0,0,E50,0,0,0,0,0,0,0,0,0,0~
)';
      PINUSE='POWER';
      NO_LOAD_CHECK='Both';
      NO_IO_CHECK='Both';
      NO_ASSERT_CHECK='TRUE';
      NO_DIR_CHECK='TRUE';
      ALLOW_CONNECT='TRUE';
    'VCCD012'<4>:
      PIN_NUMBER='(0,0,0,0,0,0,0,0,0,0,0,0,0,0,0,0,0,0,0,E48,0,0,0,0,0,0,0,0,0,0~
)';
      PINUSE='POWER';
      NO_LOAD_CHECK='Both';
      NO_IO_CHECK='Both';
      NO_ASSERT_CHECK='TRUE';
      NO_DIR_CHECK='TRUE';
      ALLOW_CONNECT='TRUE';
    'VCCD012'<3>:
      PIN_NUMBER='(0,0,0,0,0,0,0,0,0,0,0,0,0,0,0,0,0,0,0,E46,0,0,0,0,0,0,0,0,0,0~
)';
      PINUSE='POWER';
      NO_LOAD_CHECK='Both';
      NO_IO_CHECK='Both';
      NO_ASSERT_CHECK='TRUE';
      NO_DIR_CHECK='TRUE';
      ALLOW_CONNECT='TRUE';
    'VCCD012'<2>:
      PIN_NUMBER='(0,0,0,0,0,0,0,0,0,0,0,0,0,0,0,0,0,0,0,B59,0,0,0,0,0,0,0,0,0,0~
)';
      PINUSE='POWER';
      NO_LOAD_CHECK='Both';
      NO_IO_CHECK='Both';
      NO_ASSERT_CHECK='TRUE';
      NO_DIR_CHECK='TRUE';
      ALLOW_CONNECT='TRUE';
    'VCCD012'<1>:
      PIN_NUMBER='(0,0,0,0,0,0,0,0,0,0,0,0,0,0,0,0,0,0,0,B53,0,0,0,0,0,0,0,0,0,0~
)';
      PINUSE='POWER';
      NO_LOAD_CHECK='Both';
      NO_IO_CHECK='Both';
      NO_ASSERT_CHECK='TRUE';
      NO_DIR_CHECK='TRUE';
      ALLOW_CONNECT='TRUE';
    'VCCD012'<0>:
      PIN_NUMBER='(0,0,0,0,0,0,0,0,0,0,0,0,0,0,0,0,0,0,0,B49,0,0,0,0,0,0,0,0,0,0~
)';
      PINUSE='POWER';
      NO_LOAD_CHECK='Both';
      NO_IO_CHECK='Both';
      NO_ASSERT_CHECK='TRUE';
      NO_DIR_CHECK='TRUE';
      ALLOW_CONNECT='TRUE';
    'VCCD345'<50>:
      PIN_NUMBER='(0,0,0,0,0,0,0,0,0,0,0,0,0,0,0,0,0,0,0,EE44,0,0,0,0,0,0,0,0,0,~
0)';
      PINUSE='POWER';
      NO_LOAD_CHECK='Both';
      NO_IO_CHECK='Both';
      NO_ASSERT_CHECK='TRUE';
      NO_DIR_CHECK='TRUE';
      ALLOW_CONNECT='TRUE';
    'VCCD345'<49>:
      PIN_NUMBER='(0,0,0,0,0,0,0,0,0,0,0,0,0,0,0,0,0,0,0,EF45,0,0,0,0,0,0,0,0,0,~
0)';
      PINUSE='POWER';
      NO_LOAD_CHECK='Both';
      NO_IO_CHECK='Both';
      NO_ASSERT_CHECK='TRUE';
      NO_DIR_CHECK='TRUE';
      ALLOW_CONNECT='TRUE';
    'VCCD345'<48>:
      PIN_NUMBER='(0,0,0,0,0,0,0,0,0,0,0,0,0,0,0,0,0,0,0,DB53,0,0,0,0,0,0,0,0,0,~
0)';
      PINUSE='POWER';
      NO_LOAD_CHECK='Both';
      NO_IO_CHECK='Both';
      NO_ASSERT_CHECK='TRUE';
      NO_DIR_CHECK='TRUE';
      ALLOW_CONNECT='TRUE';
    'VCCD345'<47>:
      PIN_NUMBER='(0,0,0,0,0,0,0,0,0,0,0,0,0,0,0,0,0,0,0,DB55,0,0,0,0,0,0,0,0,0,~
0)';
      PINUSE='POWER';
      NO_LOAD_CHECK='Both';
      NO_IO_CHECK='Both';
      NO_ASSERT_CHECK='TRUE';
      NO_DIR_CHECK='TRUE';
      ALLOW_CONNECT='TRUE';
    'VCCD345'<46>:
      PIN_NUMBER='(0,0,0,0,0,0,0,0,0,0,0,0,0,0,0,0,0,0,0,DB57,0,0,0,0,0,0,0,0,0,~
0)';
      PINUSE='POWER';
      NO_LOAD_CHECK='Both';
      NO_IO_CHECK='Both';
      NO_ASSERT_CHECK='TRUE';
      NO_DIR_CHECK='TRUE';
      ALLOW_CONNECT='TRUE';
    'VCCD345'<45>:
      PIN_NUMBER='(0,0,0,0,0,0,0,0,0,0,0,0,0,0,0,0,0,0,0,DB59,0,0,0,0,0,0,0,0,0,~
0)';
      PINUSE='POWER';
      NO_LOAD_CHECK='Both';
      NO_IO_CHECK='Both';
      NO_ASSERT_CHECK='TRUE';
      NO_DIR_CHECK='TRUE';
      ALLOW_CONNECT='TRUE';
    'VCCD345'<44>:
      PIN_NUMBER='(0,0,0,0,0,0,0,0,0,0,0,0,0,0,0,0,0,0,0,DB61,0,0,0,0,0,0,0,0,0,~
0)';
      PINUSE='POWER';
      NO_LOAD_CHECK='Both';
      NO_IO_CHECK='Both';
      NO_ASSERT_CHECK='TRUE';
      NO_DIR_CHECK='TRUE';
      ALLOW_CONNECT='TRUE';
    'VCCD345'<43>:
      PIN_NUMBER='(0,0,0,0,0,0,0,0,0,0,0,0,0,0,0,0,0,0,0,DB63,0,0,0,0,0,0,0,0,0,~
0)';
      PINUSE='POWER';
      NO_LOAD_CHECK='Both';
      NO_IO_CHECK='Both';
      NO_ASSERT_CHECK='TRUE';
      NO_DIR_CHECK='TRUE';
      ALLOW_CONNECT='TRUE';
    'VCCD345'<42>:
      PIN_NUMBER='(0,0,0,0,0,0,0,0,0,0,0,0,0,0,0,0,0,0,0,DD45,0,0,0,0,0,0,0,0,0,~
0)';
      PINUSE='POWER';
      NO_LOAD_CHECK='Both';
      NO_IO_CHECK='Both';
      NO_ASSERT_CHECK='TRUE';
      NO_DIR_CHECK='TRUE';
      ALLOW_CONNECT='TRUE';
    'VCCD345'<41>:
      PIN_NUMBER='(0,0,0,0,0,0,0,0,0,0,0,0,0,0,0,0,0,0,0,DH45,0,0,0,0,0,0,0,0,0,~
0)';
      PINUSE='POWER';
      NO_LOAD_CHECK='Both';
      NO_IO_CHECK='Both';
      NO_ASSERT_CHECK='TRUE';
      NO_DIR_CHECK='TRUE';
      ALLOW_CONNECT='TRUE';
    'VCCD345'<40>:
      PIN_NUMBER='(0,0,0,0,0,0,0,0,0,0,0,0,0,0,0,0,0,0,0,DH47,0,0,0,0,0,0,0,0,0,~
0)';
      PINUSE='POWER';
      NO_LOAD_CHECK='Both';
      NO_IO_CHECK='Both';
      NO_ASSERT_CHECK='TRUE';
      NO_DIR_CHECK='TRUE';
      ALLOW_CONNECT='TRUE';
    'VCCD345'<39>:
      PIN_NUMBER='(0,0,0,0,0,0,0,0,0,0,0,0,0,0,0,0,0,0,0,DH49,0,0,0,0,0,0,0,0,0,~
0)';
      PINUSE='POWER';
      NO_LOAD_CHECK='Both';
      NO_IO_CHECK='Both';
      NO_ASSERT_CHECK='TRUE';
      NO_DIR_CHECK='TRUE';
      ALLOW_CONNECT='TRUE';
    'VCCD345'<38>:
      PIN_NUMBER='(0,0,0,0,0,0,0,0,0,0,0,0,0,0,0,0,0,0,0,DH51,0,0,0,0,0,0,0,0,0,~
0)';
      PINUSE='POWER';
      NO_LOAD_CHECK='Both';
      NO_IO_CHECK='Both';
      NO_ASSERT_CHECK='TRUE';
      NO_DIR_CHECK='TRUE';
      ALLOW_CONNECT='TRUE';
    'VCCD345'<37>:
      PIN_NUMBER='(0,0,0,0,0,0,0,0,0,0,0,0,0,0,0,0,0,0,0,DH53,0,0,0,0,0,0,0,0,0,~
0)';
      PINUSE='POWER';
      NO_LOAD_CHECK='Both';
      NO_IO_CHECK='Both';
      NO_ASSERT_CHECK='TRUE';
      NO_DIR_CHECK='TRUE';
      ALLOW_CONNECT='TRUE';
    'VCCD345'<36>:
      PIN_NUMBER='(0,0,0,0,0,0,0,0,0,0,0,0,0,0,0,0,0,0,0,DH55,0,0,0,0,0,0,0,0,0,~
0)';
      PINUSE='POWER';
      NO_LOAD_CHECK='Both';
      NO_IO_CHECK='Both';
      NO_ASSERT_CHECK='TRUE';
      NO_DIR_CHECK='TRUE';
      ALLOW_CONNECT='TRUE';
    'VCCD345'<35>:
      PIN_NUMBER='(0,0,0,0,0,0,0,0,0,0,0,0,0,0,0,0,0,0,0,DH57,0,0,0,0,0,0,0,0,0,~
0)';
      PINUSE='POWER';
      NO_LOAD_CHECK='Both';
      NO_IO_CHECK='Both';
      NO_ASSERT_CHECK='TRUE';
      NO_DIR_CHECK='TRUE';
      ALLOW_CONNECT='TRUE';
    'VCCD345'<34>:
      PIN_NUMBER='(0,0,0,0,0,0,0,0,0,0,0,0,0,0,0,0,0,0,0,DH59,0,0,0,0,0,0,0,0,0,~
0)';
      PINUSE='POWER';
      NO_LOAD_CHECK='Both';
      NO_IO_CHECK='Both';
      NO_ASSERT_CHECK='TRUE';
      NO_DIR_CHECK='TRUE';
      ALLOW_CONNECT='TRUE';
    'VCCD345'<33>:
      PIN_NUMBER='(0,0,0,0,0,0,0,0,0,0,0,0,0,0,0,0,0,0,0,DH61,0,0,0,0,0,0,0,0,0,~
0)';
      PINUSE='POWER';
      NO_LOAD_CHECK='Both';
      NO_IO_CHECK='Both';
      NO_ASSERT_CHECK='TRUE';
      NO_DIR_CHECK='TRUE';
      ALLOW_CONNECT='TRUE';
    'VCCD345'<32>:
      PIN_NUMBER='(0,0,0,0,0,0,0,0,0,0,0,0,0,0,0,0,0,0,0,DH63,0,0,0,0,0,0,0,0,0,~
0)';
      PINUSE='POWER';
      NO_LOAD_CHECK='Both';
      NO_IO_CHECK='Both';
      NO_ASSERT_CHECK='TRUE';
      NO_DIR_CHECK='TRUE';
      ALLOW_CONNECT='TRUE';
    'VCCD345'<31>:
      PIN_NUMBER='(0,0,0,0,0,0,0,0,0,0,0,0,0,0,0,0,0,0,0,DJ64,0,0,0,0,0,0,0,0,0,~
0)';
      PINUSE='POWER';
      NO_LOAD_CHECK='Both';
      NO_IO_CHECK='Both';
      NO_ASSERT_CHECK='TRUE';
      NO_DIR_CHECK='TRUE';
      ALLOW_CONNECT='TRUE';
    'VCCD345'<30>:
      PIN_NUMBER='(0,0,0,0,0,0,0,0,0,0,0,0,0,0,0,0,0,0,0,DL46,0,0,0,0,0,0,0,0,0,~
0)';
      PINUSE='POWER';
      NO_LOAD_CHECK='Both';
      NO_IO_CHECK='Both';
      NO_ASSERT_CHECK='TRUE';
      NO_DIR_CHECK='TRUE';
      ALLOW_CONNECT='TRUE';
    'VCCD345'<29>:
      PIN_NUMBER='(0,0,0,0,0,0,0,0,0,0,0,0,0,0,0,0,0,0,0,DL48,0,0,0,0,0,0,0,0,0,~
0)';
      PINUSE='POWER';
      NO_LOAD_CHECK='Both';
      NO_IO_CHECK='Both';
      NO_ASSERT_CHECK='TRUE';
      NO_DIR_CHECK='TRUE';
      ALLOW_CONNECT='TRUE';
    'VCCD345'<28>:
      PIN_NUMBER='(0,0,0,0,0,0,0,0,0,0,0,0,0,0,0,0,0,0,0,DL50,0,0,0,0,0,0,0,0,0,~
0)';
      PINUSE='POWER';
      NO_LOAD_CHECK='Both';
      NO_IO_CHECK='Both';
      NO_ASSERT_CHECK='TRUE';
      NO_DIR_CHECK='TRUE';
      ALLOW_CONNECT='TRUE';
    'VCCD345'<27>:
      PIN_NUMBER='(0,0,0,0,0,0,0,0,0,0,0,0,0,0,0,0,0,0,0,DL52,0,0,0,0,0,0,0,0,0,~
0)';
      PINUSE='POWER';
      NO_LOAD_CHECK='Both';
      NO_IO_CHECK='Both';
      NO_ASSERT_CHECK='TRUE';
      NO_DIR_CHECK='TRUE';
      ALLOW_CONNECT='TRUE';
    'VCCD345'<26>:
      PIN_NUMBER='(0,0,0,0,0,0,0,0,0,0,0,0,0,0,0,0,0,0,0,DL54,0,0,0,0,0,0,0,0,0,~
0)';
      PINUSE='POWER';
      NO_LOAD_CHECK='Both';
      NO_IO_CHECK='Both';
      NO_ASSERT_CHECK='TRUE';
      NO_DIR_CHECK='TRUE';
      ALLOW_CONNECT='TRUE';
    'VCCD345'<25>:
      PIN_NUMBER='(0,0,0,0,0,0,0,0,0,0,0,0,0,0,0,0,0,0,0,DL56,0,0,0,0,0,0,0,0,0,~
0)';
      PINUSE='POWER';
      NO_LOAD_CHECK='Both';
      NO_IO_CHECK='Both';
      NO_ASSERT_CHECK='TRUE';
      NO_DIR_CHECK='TRUE';
      ALLOW_CONNECT='TRUE';
    'VCCD345'<24>:
      PIN_NUMBER='(0,0,0,0,0,0,0,0,0,0,0,0,0,0,0,0,0,0,0,DL58,0,0,0,0,0,0,0,0,0,~
0)';
      PINUSE='POWER';
      NO_LOAD_CHECK='Both';
      NO_IO_CHECK='Both';
      NO_ASSERT_CHECK='TRUE';
      NO_DIR_CHECK='TRUE';
      ALLOW_CONNECT='TRUE';
    'VCCD345'<23>:
      PIN_NUMBER='(0,0,0,0,0,0,0,0,0,0,0,0,0,0,0,0,0,0,0,DL60,0,0,0,0,0,0,0,0,0,~
0)';
      PINUSE='POWER';
      NO_LOAD_CHECK='Both';
      NO_IO_CHECK='Both';
      NO_ASSERT_CHECK='TRUE';
      NO_DIR_CHECK='TRUE';
      ALLOW_CONNECT='TRUE';
    'VCCD345'<22>:
      PIN_NUMBER='(0,0,0,0,0,0,0,0,0,0,0,0,0,0,0,0,0,0,0,DL62,0,0,0,0,0,0,0,0,0,~
0)';
      PINUSE='POWER';
      NO_LOAD_CHECK='Both';
      NO_IO_CHECK='Both';
      NO_ASSERT_CHECK='TRUE';
      NO_DIR_CHECK='TRUE';
      ALLOW_CONNECT='TRUE';
    'VCCD345'<21>:
      PIN_NUMBER='(0,0,0,0,0,0,0,0,0,0,0,0,0,0,0,0,0,0,0,DU46,0,0,0,0,0,0,0,0,0,~
0)';
      PINUSE='POWER';
      NO_LOAD_CHECK='Both';
      NO_IO_CHECK='Both';
      NO_ASSERT_CHECK='TRUE';
      NO_DIR_CHECK='TRUE';
      ALLOW_CONNECT='TRUE';
    'VCCD345'<20>:
      PIN_NUMBER='(0,0,0,0,0,0,0,0,0,0,0,0,0,0,0,0,0,0,0,DU48,0,0,0,0,0,0,0,0,0,~
0)';
      PINUSE='POWER';
      NO_LOAD_CHECK='Both';
      NO_IO_CHECK='Both';
      NO_ASSERT_CHECK='TRUE';
      NO_DIR_CHECK='TRUE';
      ALLOW_CONNECT='TRUE';
    'VCCD345'<19>:
      PIN_NUMBER='(0,0,0,0,0,0,0,0,0,0,0,0,0,0,0,0,0,0,0,DU50,0,0,0,0,0,0,0,0,0,~
0)';
      PINUSE='POWER';
      NO_LOAD_CHECK='Both';
      NO_IO_CHECK='Both';
      NO_ASSERT_CHECK='TRUE';
      NO_DIR_CHECK='TRUE';
      ALLOW_CONNECT='TRUE';
    'VCCD345'<18>:
      PIN_NUMBER='(0,0,0,0,0,0,0,0,0,0,0,0,0,0,0,0,0,0,0,DU52,0,0,0,0,0,0,0,0,0,~
0)';
      PINUSE='POWER';
      NO_LOAD_CHECK='Both';
      NO_IO_CHECK='Both';
      NO_ASSERT_CHECK='TRUE';
      NO_DIR_CHECK='TRUE';
      ALLOW_CONNECT='TRUE';
    'VCCD345'<17>:
      PIN_NUMBER='(0,0,0,0,0,0,0,0,0,0,0,0,0,0,0,0,0,0,0,DU54,0,0,0,0,0,0,0,0,0,~
0)';
      PINUSE='POWER';
      NO_LOAD_CHECK='Both';
      NO_IO_CHECK='Both';
      NO_ASSERT_CHECK='TRUE';
      NO_DIR_CHECK='TRUE';
      ALLOW_CONNECT='TRUE';
    'VCCD345'<16>:
      PIN_NUMBER='(0,0,0,0,0,0,0,0,0,0,0,0,0,0,0,0,0,0,0,DU56,0,0,0,0,0,0,0,0,0,~
0)';
      PINUSE='POWER';
      NO_LOAD_CHECK='Both';
      NO_IO_CHECK='Both';
      NO_ASSERT_CHECK='TRUE';
      NO_DIR_CHECK='TRUE';
      ALLOW_CONNECT='TRUE';
    'VCCD345'<15>:
      PIN_NUMBER='(0,0,0,0,0,0,0,0,0,0,0,0,0,0,0,0,0,0,0,DU58,0,0,0,0,0,0,0,0,0,~
0)';
      PINUSE='POWER';
      NO_LOAD_CHECK='Both';
      NO_IO_CHECK='Both';
      NO_ASSERT_CHECK='TRUE';
      NO_DIR_CHECK='TRUE';
      ALLOW_CONNECT='TRUE';
    'VCCD345'<14>:
      PIN_NUMBER='(0,0,0,0,0,0,0,0,0,0,0,0,0,0,0,0,0,0,0,DU60,0,0,0,0,0,0,0,0,0,~
0)';
      PINUSE='POWER';
      NO_LOAD_CHECK='Both';
      NO_IO_CHECK='Both';
      NO_ASSERT_CHECK='TRUE';
      NO_DIR_CHECK='TRUE';
      ALLOW_CONNECT='TRUE';
    'VCCD345'<13>:
      PIN_NUMBER='(0,0,0,0,0,0,0,0,0,0,0,0,0,0,0,0,0,0,0,DU62,0,0,0,0,0,0,0,0,0,~
0)';
      PINUSE='POWER';
      NO_LOAD_CHECK='Both';
      NO_IO_CHECK='Both';
      NO_ASSERT_CHECK='TRUE';
      NO_DIR_CHECK='TRUE';
      ALLOW_CONNECT='TRUE';
    'VCCD345'<12>:
      PIN_NUMBER='(0,0,0,0,0,0,0,0,0,0,0,0,0,0,0,0,0,0,0,DU64,0,0,0,0,0,0,0,0,0,~
0)';
      PINUSE='POWER';
      NO_LOAD_CHECK='Both';
      NO_IO_CHECK='Both';
      NO_ASSERT_CHECK='TRUE';
      NO_DIR_CHECK='TRUE';
      ALLOW_CONNECT='TRUE';
    'VCCD345'<11>:
      PIN_NUMBER='(0,0,0,0,0,0,0,0,0,0,0,0,0,0,0,0,0,0,0,EC46,0,0,0,0,0,0,0,0,0,~
0)';
      PINUSE='POWER';
      NO_LOAD_CHECK='Both';
      NO_IO_CHECK='Both';
      NO_ASSERT_CHECK='TRUE';
      NO_DIR_CHECK='TRUE';
      ALLOW_CONNECT='TRUE';
    'VCCD345'<10>:
      PIN_NUMBER='(0,0,0,0,0,0,0,0,0,0,0,0,0,0,0,0,0,0,0,EC48,0,0,0,0,0,0,0,0,0,~
0)';
      PINUSE='POWER';
      NO_LOAD_CHECK='Both';
      NO_IO_CHECK='Both';
      NO_ASSERT_CHECK='TRUE';
      NO_DIR_CHECK='TRUE';
      ALLOW_CONNECT='TRUE';
    'VCCD345'<9>:
      PIN_NUMBER='(0,0,0,0,0,0,0,0,0,0,0,0,0,0,0,0,0,0,0,EC50,0,0,0,0,0,0,0,0,0,~
0)';
      PINUSE='POWER';
      NO_LOAD_CHECK='Both';
      NO_IO_CHECK='Both';
      NO_ASSERT_CHECK='TRUE';
      NO_DIR_CHECK='TRUE';
      ALLOW_CONNECT='TRUE';
    'VCCD345'<8>:
      PIN_NUMBER='(0,0,0,0,0,0,0,0,0,0,0,0,0,0,0,0,0,0,0,EC52,0,0,0,0,0,0,0,0,0,~
0)';
      PINUSE='POWER';
      NO_LOAD_CHECK='Both';
      NO_IO_CHECK='Both';
      NO_ASSERT_CHECK='TRUE';
      NO_DIR_CHECK='TRUE';
      ALLOW_CONNECT='TRUE';
    'VCCD345'<7>:
      PIN_NUMBER='(0,0,0,0,0,0,0,0,0,0,0,0,0,0,0,0,0,0,0,EC54,0,0,0,0,0,0,0,0,0,~
0)';
      PINUSE='POWER';
      NO_LOAD_CHECK='Both';
      NO_IO_CHECK='Both';
      NO_ASSERT_CHECK='TRUE';
      NO_DIR_CHECK='TRUE';
      ALLOW_CONNECT='TRUE';
    'VCCD345'<6>:
      PIN_NUMBER='(0,0,0,0,0,0,0,0,0,0,0,0,0,0,0,0,0,0,0,EC56,0,0,0,0,0,0,0,0,0,~
0)';
      PINUSE='POWER';
      NO_LOAD_CHECK='Both';
      NO_IO_CHECK='Both';
      NO_ASSERT_CHECK='TRUE';
      NO_DIR_CHECK='TRUE';
      ALLOW_CONNECT='TRUE';
    'VCCD345'<5>:
      PIN_NUMBER='(0,0,0,0,0,0,0,0,0,0,0,0,0,0,0,0,0,0,0,EC58,0,0,0,0,0,0,0,0,0,~
0)';
      PINUSE='POWER';
      NO_LOAD_CHECK='Both';
      NO_IO_CHECK='Both';
      NO_ASSERT_CHECK='TRUE';
      NO_DIR_CHECK='TRUE';
      ALLOW_CONNECT='TRUE';
    'VCCD345'<4>:
      PIN_NUMBER='(0,0,0,0,0,0,0,0,0,0,0,0,0,0,0,0,0,0,0,EC60,0,0,0,0,0,0,0,0,0,~
0)';
      PINUSE='POWER';
      NO_LOAD_CHECK='Both';
      NO_IO_CHECK='Both';
      NO_ASSERT_CHECK='TRUE';
      NO_DIR_CHECK='TRUE';
      ALLOW_CONNECT='TRUE';
    'VCCD345'<3>:
      PIN_NUMBER='(0,0,0,0,0,0,0,0,0,0,0,0,0,0,0,0,0,0,0,EC62,0,0,0,0,0,0,0,0,0,~
0)';
      PINUSE='POWER';
      NO_LOAD_CHECK='Both';
      NO_IO_CHECK='Both';
      NO_ASSERT_CHECK='TRUE';
      NO_DIR_CHECK='TRUE';
      ALLOW_CONNECT='TRUE';
    'VCCD345'<2>:
      PIN_NUMBER='(0,0,0,0,0,0,0,0,0,0,0,0,0,0,0,0,0,0,0,EF49,0,0,0,0,0,0,0,0,0,~
0)';
      PINUSE='POWER';
      NO_LOAD_CHECK='Both';
      NO_IO_CHECK='Both';
      NO_ASSERT_CHECK='TRUE';
      NO_DIR_CHECK='TRUE';
      ALLOW_CONNECT='TRUE';
    'VCCD345'<1>:
      PIN_NUMBER='(0,0,0,0,0,0,0,0,0,0,0,0,0,0,0,0,0,0,0,EF53,0,0,0,0,0,0,0,0,0,~
0)';
      PINUSE='POWER';
      NO_LOAD_CHECK='Both';
      NO_IO_CHECK='Both';
      NO_ASSERT_CHECK='TRUE';
      NO_DIR_CHECK='TRUE';
      ALLOW_CONNECT='TRUE';
    'VCCD345'<0>:
      PIN_NUMBER='(0,0,0,0,0,0,0,0,0,0,0,0,0,0,0,0,0,0,0,EF59,0,0,0,0,0,0,0,0,0,~
0)';
      PINUSE='POWER';
      NO_LOAD_CHECK='Both';
      NO_IO_CHECK='Both';
      NO_ASSERT_CHECK='TRUE';
      NO_DIR_CHECK='TRUE';
      ALLOW_CONNECT='TRUE';
    'VCCIN'<267>:
      PIN_NUMBER='(0,0,0,0,0,0,0,0,0,0,0,0,0,0,0,0,0,AF43,0,0,0,0,0,0,0,0,0,0,0,~
0)';
      PINUSE='POWER';
      NO_LOAD_CHECK='Both';
      NO_IO_CHECK='Both';
      NO_ASSERT_CHECK='TRUE';
      NO_DIR_CHECK='TRUE';
      ALLOW_CONNECT='TRUE';
    'VCCIN'<266>:
      PIN_NUMBER='(0,0,0,0,0,0,0,0,0,0,0,0,0,0,0,0,0,AG38,0,0,0,0,0,0,0,0,0,0,0,~
0)';
      PINUSE='POWER';
      NO_LOAD_CHECK='Both';
      NO_IO_CHECK='Both';
      NO_ASSERT_CHECK='TRUE';
      NO_DIR_CHECK='TRUE';
      ALLOW_CONNECT='TRUE';
    'VCCIN'<265>:
      PIN_NUMBER='(0,0,0,0,0,0,0,0,0,0,0,0,0,0,0,0,0,AG40,0,0,0,0,0,0,0,0,0,0,0,~
0)';
      PINUSE='POWER';
      NO_LOAD_CHECK='Both';
      NO_IO_CHECK='Both';
      NO_ASSERT_CHECK='TRUE';
      NO_DIR_CHECK='TRUE';
      ALLOW_CONNECT='TRUE';
    'VCCIN'<264>:
      PIN_NUMBER='(0,0,0,0,0,0,0,0,0,0,0,0,0,0,0,0,0,AG42,0,0,0,0,0,0,0,0,0,0,0,~
0)';
      PINUSE='POWER';
      NO_LOAD_CHECK='Both';
      NO_IO_CHECK='Both';
      NO_ASSERT_CHECK='TRUE';
      NO_DIR_CHECK='TRUE';
      ALLOW_CONNECT='TRUE';
    'VCCIN'<263>:
      PIN_NUMBER='(0,0,0,0,0,0,0,0,0,0,0,0,0,0,0,0,0,AH37,0,0,0,0,0,0,0,0,0,0,0,~
0)';
      PINUSE='POWER';
      NO_LOAD_CHECK='Both';
      NO_IO_CHECK='Both';
      NO_ASSERT_CHECK='TRUE';
      NO_DIR_CHECK='TRUE';
      ALLOW_CONNECT='TRUE';
    'VCCIN'<262>:
      PIN_NUMBER='(0,0,0,0,0,0,0,0,0,0,0,0,0,0,0,0,0,AH39,0,0,0,0,0,0,0,0,0,0,0,~
0)';
      PINUSE='POWER';
      NO_LOAD_CHECK='Both';
      NO_IO_CHECK='Both';
      NO_ASSERT_CHECK='TRUE';
      NO_DIR_CHECK='TRUE';
      ALLOW_CONNECT='TRUE';
    'VCCIN'<261>:
      PIN_NUMBER='(0,0,0,0,0,0,0,0,0,0,0,0,0,0,0,0,0,AH41,0,0,0,0,0,0,0,0,0,0,0,~
0)';
      PINUSE='POWER';
      NO_LOAD_CHECK='Both';
      NO_IO_CHECK='Both';
      NO_ASSERT_CHECK='TRUE';
      NO_DIR_CHECK='TRUE';
      ALLOW_CONNECT='TRUE';
    'VCCIN'<260>:
      PIN_NUMBER='(0,0,0,0,0,0,0,0,0,0,0,0,0,0,0,0,0,AJ36,0,0,0,0,0,0,0,0,0,0,0,~
0)';
      PINUSE='POWER';
      NO_LOAD_CHECK='Both';
      NO_IO_CHECK='Both';
      NO_ASSERT_CHECK='TRUE';
      NO_DIR_CHECK='TRUE';
      ALLOW_CONNECT='TRUE';
    'VCCIN'<259>:
      PIN_NUMBER='(0,0,0,0,0,0,0,0,0,0,0,0,0,0,0,0,0,AK35,0,0,0,0,0,0,0,0,0,0,0,~
0)';
      PINUSE='POWER';
      NO_LOAD_CHECK='Both';
      NO_IO_CHECK='Both';
      NO_ASSERT_CHECK='TRUE';
      NO_DIR_CHECK='TRUE';
      ALLOW_CONNECT='TRUE';
    'VCCIN'<258>:
      PIN_NUMBER='(0,0,0,0,0,0,0,0,0,0,0,0,0,0,0,0,0,AK45,0,0,0,0,0,0,0,0,0,0,0,~
0)';
      PINUSE='POWER';
      NO_LOAD_CHECK='Both';
      NO_IO_CHECK='Both';
      NO_ASSERT_CHECK='TRUE';
      NO_DIR_CHECK='TRUE';
      ALLOW_CONNECT='TRUE';
    'VCCIN'<257>:
      PIN_NUMBER='(0,0,0,0,0,0,0,0,0,0,0,0,0,0,0,0,0,AK47,0,0,0,0,0,0,0,0,0,0,0,~
0)';
      PINUSE='POWER';
      NO_LOAD_CHECK='Both';
      NO_IO_CHECK='Both';
      NO_ASSERT_CHECK='TRUE';
      NO_DIR_CHECK='TRUE';
      ALLOW_CONNECT='TRUE';
    'VCCIN'<256>:
      PIN_NUMBER='(0,0,0,0,0,0,0,0,0,0,0,0,0,0,0,0,0,AK49,0,0,0,0,0,0,0,0,0,0,0,~
0)';
      PINUSE='POWER';
      NO_LOAD_CHECK='Both';
      NO_IO_CHECK='Both';
      NO_ASSERT_CHECK='TRUE';
      NO_DIR_CHECK='TRUE';
      ALLOW_CONNECT='TRUE';
    'VCCIN'<255>:
      PIN_NUMBER='(0,0,0,0,0,0,0,0,0,0,0,0,0,0,0,0,0,AK51,0,0,0,0,0,0,0,0,0,0,0,~
0)';
      PINUSE='POWER';
      NO_LOAD_CHECK='Both';
      NO_IO_CHECK='Both';
      NO_ASSERT_CHECK='TRUE';
      NO_DIR_CHECK='TRUE';
      ALLOW_CONNECT='TRUE';
    'VCCIN'<254>:
      PIN_NUMBER='(0,0,0,0,0,0,0,0,0,0,0,0,0,0,0,0,0,AK53,0,0,0,0,0,0,0,0,0,0,0,~
0)';
      PINUSE='POWER';
      NO_LOAD_CHECK='Both';
      NO_IO_CHECK='Both';
      NO_ASSERT_CHECK='TRUE';
      NO_DIR_CHECK='TRUE';
      ALLOW_CONNECT='TRUE';
    'VCCIN'<253>:
      PIN_NUMBER='(0,0,0,0,0,0,0,0,0,0,0,0,0,0,0,0,0,AL34,0,0,0,0,0,0,0,0,0,0,0,~
0)';
      PINUSE='POWER';
      NO_LOAD_CHECK='Both';
      NO_IO_CHECK='Both';
      NO_ASSERT_CHECK='TRUE';
      NO_DIR_CHECK='TRUE';
      ALLOW_CONNECT='TRUE';
    'VCCIN'<252>:
      PIN_NUMBER='(0,0,0,0,0,0,0,0,0,0,0,0,0,0,0,0,0,AL46,0,0,0,0,0,0,0,0,0,0,0,~
0)';
      PINUSE='POWER';
      NO_LOAD_CHECK='Both';
      NO_IO_CHECK='Both';
      NO_ASSERT_CHECK='TRUE';
      NO_DIR_CHECK='TRUE';
      ALLOW_CONNECT='TRUE';
    'VCCIN'<251>:
      PIN_NUMBER='(0,0,0,0,0,0,0,0,0,0,0,0,0,0,0,0,0,AL48,0,0,0,0,0,0,0,0,0,0,0,~
0)';
      PINUSE='POWER';
      NO_LOAD_CHECK='Both';
      NO_IO_CHECK='Both';
      NO_ASSERT_CHECK='TRUE';
      NO_DIR_CHECK='TRUE';
      ALLOW_CONNECT='TRUE';
    'VCCIN'<250>:
      PIN_NUMBER='(0,0,0,0,0,0,0,0,0,0,0,0,0,0,0,0,0,AL50,0,0,0,0,0,0,0,0,0,0,0,~
0)';
      PINUSE='POWER';
      NO_LOAD_CHECK='Both';
      NO_IO_CHECK='Both';
      NO_ASSERT_CHECK='TRUE';
      NO_DIR_CHECK='TRUE';
      ALLOW_CONNECT='TRUE';
    'VCCIN'<249>:
      PIN_NUMBER='(0,0,0,0,0,0,0,0,0,0,0,0,0,0,0,0,0,AL52,0,0,0,0,0,0,0,0,0,0,0,~
0)';
      PINUSE='POWER';
      NO_LOAD_CHECK='Both';
      NO_IO_CHECK='Both';
      NO_ASSERT_CHECK='TRUE';
      NO_DIR_CHECK='TRUE';
      ALLOW_CONNECT='TRUE';
    'VCCIN'<248>:
      PIN_NUMBER='(0,0,0,0,0,0,0,0,0,0,0,0,0,0,0,0,0,AL54,0,0,0,0,0,0,0,0,0,0,0,~
0)';
      PINUSE='POWER';
      NO_LOAD_CHECK='Both';
      NO_IO_CHECK='Both';
      NO_ASSERT_CHECK='TRUE';
      NO_DIR_CHECK='TRUE';
      ALLOW_CONNECT='TRUE';
    'VCCIN'<247>:
      PIN_NUMBER='(0,0,0,0,0,0,0,0,0,0,0,0,0,0,0,0,0,AM33,0,0,0,0,0,0,0,0,0,0,0,~
0)';
      PINUSE='POWER';
      NO_LOAD_CHECK='Both';
      NO_IO_CHECK='Both';
      NO_ASSERT_CHECK='TRUE';
      NO_DIR_CHECK='TRUE';
      ALLOW_CONNECT='TRUE';
    'VCCIN'<246>:
      PIN_NUMBER='(0,0,0,0,0,0,0,0,0,0,0,0,0,0,0,0,0,AM53,0,0,0,0,0,0,0,0,0,0,0,~
0)';
      PINUSE='POWER';
      NO_LOAD_CHECK='Both';
      NO_IO_CHECK='Both';
      NO_ASSERT_CHECK='TRUE';
      NO_DIR_CHECK='TRUE';
      ALLOW_CONNECT='TRUE';
    'VCCIN'<245>:
      PIN_NUMBER='(0,0,0,0,0,0,0,0,0,0,0,0,0,0,0,0,0,AM55,0,0,0,0,0,0,0,0,0,0,0,~
0)';
      PINUSE='POWER';
      NO_LOAD_CHECK='Both';
      NO_IO_CHECK='Both';
      NO_ASSERT_CHECK='TRUE';
      NO_DIR_CHECK='TRUE';
      ALLOW_CONNECT='TRUE';
    'VCCIN'<244>:
      PIN_NUMBER='(0,0,0,0,0,0,0,0,0,0,0,0,0,0,0,0,0,AN32,0,0,0,0,0,0,0,0,0,0,0,~
0)';
      PINUSE='POWER';
      NO_LOAD_CHECK='Both';
      NO_IO_CHECK='Both';
      NO_ASSERT_CHECK='TRUE';
      NO_DIR_CHECK='TRUE';
      ALLOW_CONNECT='TRUE';
    'VCCIN'<243>:
      PIN_NUMBER='(0,0,0,0,0,0,0,0,0,0,0,0,0,0,0,0,0,AN54,0,0,0,0,0,0,0,0,0,0,0,~
0)';
      PINUSE='POWER';
      NO_LOAD_CHECK='Both';
      NO_IO_CHECK='Both';
      NO_ASSERT_CHECK='TRUE';
      NO_DIR_CHECK='TRUE';
      ALLOW_CONNECT='TRUE';
    'VCCIN'<242>:
      PIN_NUMBER='(0,0,0,0,0,0,0,0,0,0,0,0,0,0,0,0,0,AN56,0,0,0,0,0,0,0,0,0,0,0,~
0)';
      PINUSE='POWER';
      NO_LOAD_CHECK='Both';
      NO_IO_CHECK='Both';
      NO_ASSERT_CHECK='TRUE';
      NO_DIR_CHECK='TRUE';
      ALLOW_CONNECT='TRUE';
    'VCCIN'<241>:
      PIN_NUMBER='(0,0,0,0,0,0,0,0,0,0,0,0,0,0,0,0,0,AP55,0,0,0,0,0,0,0,0,0,0,0,~
0)';
      PINUSE='POWER';
      NO_LOAD_CHECK='Both';
      NO_IO_CHECK='Both';
      NO_ASSERT_CHECK='TRUE';
      NO_DIR_CHECK='TRUE';
      ALLOW_CONNECT='TRUE';
    'VCCIN'<240>:
      PIN_NUMBER='(0,0,0,0,0,0,0,0,0,0,0,0,0,0,0,0,0,AP57,0,0,0,0,0,0,0,0,0,0,0,~
0)';
      PINUSE='POWER';
      NO_LOAD_CHECK='Both';
      NO_IO_CHECK='Both';
      NO_ASSERT_CHECK='TRUE';
      NO_DIR_CHECK='TRUE';
      ALLOW_CONNECT='TRUE';
    'VCCIN'<239>:
      PIN_NUMBER='(0,0,0,0,0,0,0,0,0,0,0,0,0,0,0,0,0,AR56,0,0,0,0,0,0,0,0,0,0,0,~
0)';
      PINUSE='POWER';
      NO_LOAD_CHECK='Both';
      NO_IO_CHECK='Both';
      NO_ASSERT_CHECK='TRUE';
      NO_DIR_CHECK='TRUE';
      ALLOW_CONNECT='TRUE';
    'VCCIN'<238>:
      PIN_NUMBER='(0,0,0,0,0,0,0,0,0,0,0,0,0,0,0,0,0,AR58,0,0,0,0,0,0,0,0,0,0,0,~
0)';
      PINUSE='POWER';
      NO_LOAD_CHECK='Both';
      NO_IO_CHECK='Both';
      NO_ASSERT_CHECK='TRUE';
      NO_DIR_CHECK='TRUE';
      ALLOW_CONNECT='TRUE';
    'VCCIN'<237>:
      PIN_NUMBER='(0,0,0,0,0,0,0,0,0,0,0,0,0,0,0,0,0,AT57,0,0,0,0,0,0,0,0,0,0,0,~
0)';
      PINUSE='POWER';
      NO_LOAD_CHECK='Both';
      NO_IO_CHECK='Both';
      NO_ASSERT_CHECK='TRUE';
      NO_DIR_CHECK='TRUE';
      ALLOW_CONNECT='TRUE';
    'VCCIN'<236>:
      PIN_NUMBER='(0,0,0,0,0,0,0,0,0,0,0,0,0,0,0,0,0,AT59,0,0,0,0,0,0,0,0,0,0,0,~
0)';
      PINUSE='POWER';
      NO_LOAD_CHECK='Both';
      NO_IO_CHECK='Both';
      NO_ASSERT_CHECK='TRUE';
      NO_DIR_CHECK='TRUE';
      ALLOW_CONNECT='TRUE';
    'VCCIN'<235>:
      PIN_NUMBER='(0,0,0,0,0,0,0,0,0,0,0,0,0,0,0,0,0,AU58,0,0,0,0,0,0,0,0,0,0,0,~
0)';
      PINUSE='POWER';
      NO_LOAD_CHECK='Both';
      NO_IO_CHECK='Both';
      NO_ASSERT_CHECK='TRUE';
      NO_DIR_CHECK='TRUE';
      ALLOW_CONNECT='TRUE';
    'VCCIN'<234>:
      PIN_NUMBER='(0,0,0,0,0,0,0,0,0,0,0,0,0,0,0,0,0,AU60,0,0,0,0,0,0,0,0,0,0,0,~
0)';
      PINUSE='POWER';
      NO_LOAD_CHECK='Both';
      NO_IO_CHECK='Both';
      NO_ASSERT_CHECK='TRUE';
      NO_DIR_CHECK='TRUE';
      ALLOW_CONNECT='TRUE';
    'VCCIN'<233>:
      PIN_NUMBER='(0,0,0,0,0,0,0,0,0,0,0,0,0,0,0,0,0,AV59,0,0,0,0,0,0,0,0,0,0,0,~
0)';
      PINUSE='POWER';
      NO_LOAD_CHECK='Both';
      NO_IO_CHECK='Both';
      NO_ASSERT_CHECK='TRUE';
      NO_DIR_CHECK='TRUE';
      ALLOW_CONNECT='TRUE';
    'VCCIN'<232>:
      PIN_NUMBER='(0,0,0,0,0,0,0,0,0,0,0,0,0,0,0,0,0,AV61,0,0,0,0,0,0,0,0,0,0,0,~
0)';
      PINUSE='POWER';
      NO_LOAD_CHECK='Both';
      NO_IO_CHECK='Both';
      NO_ASSERT_CHECK='TRUE';
      NO_DIR_CHECK='TRUE';
      ALLOW_CONNECT='TRUE';
    'VCCIN'<231>:
      PIN_NUMBER='(0,0,0,0,0,0,0,0,0,0,0,0,0,0,0,0,0,AW60,0,0,0,0,0,0,0,0,0,0,0,~
0)';
      PINUSE='POWER';
      NO_LOAD_CHECK='Both';
      NO_IO_CHECK='Both';
      NO_ASSERT_CHECK='TRUE';
      NO_DIR_CHECK='TRUE';
      ALLOW_CONNECT='TRUE';
    'VCCIN'<230>:
      PIN_NUMBER='(0,0,0,0,0,0,0,0,0,0,0,0,0,0,0,0,0,AY61,0,0,0,0,0,0,0,0,0,0,0,~
0)';
      PINUSE='POWER';
      NO_LOAD_CHECK='Both';
      NO_IO_CHECK='Both';
      NO_ASSERT_CHECK='TRUE';
      NO_DIR_CHECK='TRUE';
      ALLOW_CONNECT='TRUE';
    'VCCIN'<229>:
      PIN_NUMBER='(0,0,0,0,0,0,0,0,0,0,0,0,0,0,0,0,0,BA60,0,0,0,0,0,0,0,0,0,0,0,~
0)';
      PINUSE='POWER';
      NO_LOAD_CHECK='Both';
      NO_IO_CHECK='Both';
      NO_ASSERT_CHECK='TRUE';
      NO_DIR_CHECK='TRUE';
      ALLOW_CONNECT='TRUE';
    'VCCIN'<228>:
      PIN_NUMBER='(0,0,0,0,0,0,0,0,0,0,0,0,0,0,0,0,0,BB61,0,0,0,0,0,0,0,0,0,0,0,~
0)';
      PINUSE='POWER';
      NO_LOAD_CHECK='Both';
      NO_IO_CHECK='Both';
      NO_ASSERT_CHECK='TRUE';
      NO_DIR_CHECK='TRUE';
      ALLOW_CONNECT='TRUE';
    'VCCIN'<227>:
      PIN_NUMBER='(0,0,0,0,0,0,0,0,0,0,0,0,0,0,0,0,0,BB85,0,0,0,0,0,0,0,0,0,0,0,~
0)';
      PINUSE='POWER';
      NO_LOAD_CHECK='Both';
      NO_IO_CHECK='Both';
      NO_ASSERT_CHECK='TRUE';
      NO_DIR_CHECK='TRUE';
      ALLOW_CONNECT='TRUE';
    'VCCIN'<226>:
      PIN_NUMBER='(0,0,0,0,0,0,0,0,0,0,0,0,0,0,0,0,0,BC60,0,0,0,0,0,0,0,0,0,0,0,~
0)';
      PINUSE='POWER';
      NO_LOAD_CHECK='Both';
      NO_IO_CHECK='Both';
      NO_ASSERT_CHECK='TRUE';
      NO_DIR_CHECK='TRUE';
      ALLOW_CONNECT='TRUE';
    'VCCIN'<225>:
      PIN_NUMBER='(0,0,0,0,0,0,0,0,0,0,0,0,0,0,0,0,0,BC62,0,0,0,0,0,0,0,0,0,0,0,~
0)';
      PINUSE='POWER';
      NO_LOAD_CHECK='Both';
      NO_IO_CHECK='Both';
      NO_ASSERT_CHECK='TRUE';
      NO_DIR_CHECK='TRUE';
      ALLOW_CONNECT='TRUE';
    'VCCIN'<224>:
      PIN_NUMBER='(0,0,0,0,0,0,0,0,0,0,0,0,0,0,0,0,0,BC84,0,0,0,0,0,0,0,0,0,0,0,~
0)';
      PINUSE='POWER';
      NO_LOAD_CHECK='Both';
      NO_IO_CHECK='Both';
      NO_ASSERT_CHECK='TRUE';
      NO_DIR_CHECK='TRUE';
      ALLOW_CONNECT='TRUE';
    'VCCIN'<223>:
      PIN_NUMBER='(0,0,0,0,0,0,0,0,0,0,0,0,0,0,0,0,0,BD61,0,0,0,0,0,0,0,0,0,0,0,~
0)';
      PINUSE='POWER';
      NO_LOAD_CHECK='Both';
      NO_IO_CHECK='Both';
      NO_ASSERT_CHECK='TRUE';
      NO_DIR_CHECK='TRUE';
      ALLOW_CONNECT='TRUE';
    'VCCIN'<222>:
      PIN_NUMBER='(0,0,0,0,0,0,0,0,0,0,0,0,0,0,0,0,0,BD73,0,0,0,0,0,0,0,0,0,0,0,~
0)';
      PINUSE='POWER';
      NO_LOAD_CHECK='Both';
      NO_IO_CHECK='Both';
      NO_ASSERT_CHECK='TRUE';
      NO_DIR_CHECK='TRUE';
      ALLOW_CONNECT='TRUE';
    'VCCIN'<221>:
      PIN_NUMBER='(0,0,0,0,0,0,0,0,0,0,0,0,0,0,0,0,0,BD75,0,0,0,0,0,0,0,0,0,0,0,~
0)';
      PINUSE='POWER';
      NO_LOAD_CHECK='Both';
      NO_IO_CHECK='Both';
      NO_ASSERT_CHECK='TRUE';
      NO_DIR_CHECK='TRUE';
      ALLOW_CONNECT='TRUE';
    'VCCIN'<220>:
      PIN_NUMBER='(0,0,0,0,0,0,0,0,0,0,0,0,0,0,0,0,0,BD77,0,0,0,0,0,0,0,0,0,0,0,~
0)';
      PINUSE='POWER';
      NO_LOAD_CHECK='Both';
      NO_IO_CHECK='Both';
      NO_ASSERT_CHECK='TRUE';
      NO_DIR_CHECK='TRUE';
      ALLOW_CONNECT='TRUE';
    'VCCIN'<219>:
      PIN_NUMBER='(0,0,0,0,0,0,0,0,0,0,0,0,0,0,0,0,0,BD79,0,0,0,0,0,0,0,0,0,0,0,~
0)';
      PINUSE='POWER';
      NO_LOAD_CHECK='Both';
      NO_IO_CHECK='Both';
      NO_ASSERT_CHECK='TRUE';
      NO_DIR_CHECK='TRUE';
      ALLOW_CONNECT='TRUE';
    'VCCIN'<218>:
      PIN_NUMBER='(0,0,0,0,0,0,0,0,0,0,0,0,0,0,0,0,0,BD81,0,0,0,0,0,0,0,0,0,0,0,~
0)';
      PINUSE='POWER';
      NO_LOAD_CHECK='Both';
      NO_IO_CHECK='Both';
      NO_ASSERT_CHECK='TRUE';
      NO_DIR_CHECK='TRUE';
      ALLOW_CONNECT='TRUE';
    'VCCIN'<217>:
      PIN_NUMBER='(0,0,0,0,0,0,0,0,0,0,0,0,0,0,0,0,0,BD83,0,0,0,0,0,0,0,0,0,0,0,~
0)';
      PINUSE='POWER';
      NO_LOAD_CHECK='Both';
      NO_IO_CHECK='Both';
      NO_ASSERT_CHECK='TRUE';
      NO_DIR_CHECK='TRUE';
      ALLOW_CONNECT='TRUE';
    'VCCIN'<216>:
      PIN_NUMBER='(0,0,0,0,0,0,0,0,0,0,0,0,0,0,0,0,0,BD85,0,0,0,0,0,0,0,0,0,0,0,~
0)';
      PINUSE='POWER';
      NO_LOAD_CHECK='Both';
      NO_IO_CHECK='Both';
      NO_ASSERT_CHECK='TRUE';
      NO_DIR_CHECK='TRUE';
      ALLOW_CONNECT='TRUE';
    'VCCIN'<215>:
      PIN_NUMBER='(0,0,0,0,0,0,0,0,0,0,0,0,0,0,0,0,0,BE60,0,0,0,0,0,0,0,0,0,0,0,~
0)';
      PINUSE='POWER';
      NO_LOAD_CHECK='Both';
      NO_IO_CHECK='Both';
      NO_ASSERT_CHECK='TRUE';
      NO_DIR_CHECK='TRUE';
      ALLOW_CONNECT='TRUE';
    'VCCIN'<214>:
      PIN_NUMBER='(0,0,0,0,0,0,0,0,0,0,0,0,0,0,0,0,0,BE62,0,0,0,0,0,0,0,0,0,0,0,~
0)';
      PINUSE='POWER';
      NO_LOAD_CHECK='Both';
      NO_IO_CHECK='Both';
      NO_ASSERT_CHECK='TRUE';
      NO_DIR_CHECK='TRUE';
      ALLOW_CONNECT='TRUE';
    'VCCIN'<213>:
      PIN_NUMBER='(0,0,0,0,0,0,0,0,0,0,0,0,0,0,0,0,0,BE72,0,0,0,0,0,0,0,0,0,0,0,~
0)';
      PINUSE='POWER';
      NO_LOAD_CHECK='Both';
      NO_IO_CHECK='Both';
      NO_ASSERT_CHECK='TRUE';
      NO_DIR_CHECK='TRUE';
      ALLOW_CONNECT='TRUE';
    'VCCIN'<212>:
      PIN_NUMBER='(0,0,0,0,0,0,0,0,0,0,0,0,0,0,0,0,0,BE74,0,0,0,0,0,0,0,0,0,0,0,~
0)';
      PINUSE='POWER';
      NO_LOAD_CHECK='Both';
      NO_IO_CHECK='Both';
      NO_ASSERT_CHECK='TRUE';
      NO_DIR_CHECK='TRUE';
      ALLOW_CONNECT='TRUE';
    'VCCIN'<211>:
      PIN_NUMBER='(0,0,0,0,0,0,0,0,0,0,0,0,0,0,0,0,0,BE76,0,0,0,0,0,0,0,0,0,0,0,~
0)';
      PINUSE='POWER';
      NO_LOAD_CHECK='Both';
      NO_IO_CHECK='Both';
      NO_ASSERT_CHECK='TRUE';
      NO_DIR_CHECK='TRUE';
      ALLOW_CONNECT='TRUE';
    'VCCIN'<210>:
      PIN_NUMBER='(0,0,0,0,0,0,0,0,0,0,0,0,0,0,0,0,0,BE78,0,0,0,0,0,0,0,0,0,0,0,~
0)';
      PINUSE='POWER';
      NO_LOAD_CHECK='Both';
      NO_IO_CHECK='Both';
      NO_ASSERT_CHECK='TRUE';
      NO_DIR_CHECK='TRUE';
      ALLOW_CONNECT='TRUE';
    'VCCIN'<209>:
      PIN_NUMBER='(0,0,0,0,0,0,0,0,0,0,0,0,0,0,0,0,0,BE80,0,0,0,0,0,0,0,0,0,0,0,~
0)';
      PINUSE='POWER';
      NO_LOAD_CHECK='Both';
      NO_IO_CHECK='Both';
      NO_ASSERT_CHECK='TRUE';
      NO_DIR_CHECK='TRUE';
      ALLOW_CONNECT='TRUE';
    'VCCIN'<208>:
      PIN_NUMBER='(0,0,0,0,0,0,0,0,0,0,0,0,0,0,0,0,0,BE82,0,0,0,0,0,0,0,0,0,0,0,~
0)';
      PINUSE='POWER';
      NO_LOAD_CHECK='Both';
      NO_IO_CHECK='Both';
      NO_ASSERT_CHECK='TRUE';
      NO_DIR_CHECK='TRUE';
      ALLOW_CONNECT='TRUE';
    'VCCIN'<207>:
      PIN_NUMBER='(0,0,0,0,0,0,0,0,0,0,0,0,0,0,0,0,0,BE84,0,0,0,0,0,0,0,0,0,0,0,~
0)';
      PINUSE='POWER';
      NO_LOAD_CHECK='Both';
      NO_IO_CHECK='Both';
      NO_ASSERT_CHECK='TRUE';
      NO_DIR_CHECK='TRUE';
      ALLOW_CONNECT='TRUE';
    'VCCIN'<206>:
      PIN_NUMBER='(0,0,0,0,0,0,0,0,0,0,0,0,0,0,0,0,0,BF61,0,0,0,0,0,0,0,0,0,0,0,~
0)';
      PINUSE='POWER';
      NO_LOAD_CHECK='Both';
      NO_IO_CHECK='Both';
      NO_ASSERT_CHECK='TRUE';
      NO_DIR_CHECK='TRUE';
      ALLOW_CONNECT='TRUE';
    'VCCIN'<205>:
      PIN_NUMBER='(0,0,0,0,0,0,0,0,0,0,0,0,0,0,0,0,0,BF73,0,0,0,0,0,0,0,0,0,0,0,~
0)';
      PINUSE='POWER';
      NO_LOAD_CHECK='Both';
      NO_IO_CHECK='Both';
      NO_ASSERT_CHECK='TRUE';
      NO_DIR_CHECK='TRUE';
      ALLOW_CONNECT='TRUE';
    'VCCIN'<204>:
      PIN_NUMBER='(0,0,0,0,0,0,0,0,0,0,0,0,0,0,0,0,0,BF75,0,0,0,0,0,0,0,0,0,0,0,~
0)';
      PINUSE='POWER';
      NO_LOAD_CHECK='Both';
      NO_IO_CHECK='Both';
      NO_ASSERT_CHECK='TRUE';
      NO_DIR_CHECK='TRUE';
      ALLOW_CONNECT='TRUE';
    'VCCIN'<203>:
      PIN_NUMBER='(0,0,0,0,0,0,0,0,0,0,0,0,0,0,0,0,0,BF77,0,0,0,0,0,0,0,0,0,0,0,~
0)';
      PINUSE='POWER';
      NO_LOAD_CHECK='Both';
      NO_IO_CHECK='Both';
      NO_ASSERT_CHECK='TRUE';
      NO_DIR_CHECK='TRUE';
      ALLOW_CONNECT='TRUE';
    'VCCIN'<202>:
      PIN_NUMBER='(0,0,0,0,0,0,0,0,0,0,0,0,0,0,0,0,0,BF79,0,0,0,0,0,0,0,0,0,0,0,~
0)';
      PINUSE='POWER';
      NO_LOAD_CHECK='Both';
      NO_IO_CHECK='Both';
      NO_ASSERT_CHECK='TRUE';
      NO_DIR_CHECK='TRUE';
      ALLOW_CONNECT='TRUE';
    'VCCIN'<201>:
      PIN_NUMBER='(0,0,0,0,0,0,0,0,0,0,0,0,0,0,0,0,0,BF81,0,0,0,0,0,0,0,0,0,0,0,~
0)';
      PINUSE='POWER';
      NO_LOAD_CHECK='Both';
      NO_IO_CHECK='Both';
      NO_ASSERT_CHECK='TRUE';
      NO_DIR_CHECK='TRUE';
      ALLOW_CONNECT='TRUE';
    'VCCIN'<200>:
      PIN_NUMBER='(0,0,0,0,0,0,0,0,0,0,0,0,0,0,0,0,0,BF83,0,0,0,0,0,0,0,0,0,0,0,~
0)';
      PINUSE='POWER';
      NO_LOAD_CHECK='Both';
      NO_IO_CHECK='Both';
      NO_ASSERT_CHECK='TRUE';
      NO_DIR_CHECK='TRUE';
      ALLOW_CONNECT='TRUE';
    'VCCIN'<199>:
      PIN_NUMBER='(0,0,0,0,0,0,0,0,0,0,0,0,0,0,0,0,0,BF85,0,0,0,0,0,0,0,0,0,0,0,~
0)';
      PINUSE='POWER';
      NO_LOAD_CHECK='Both';
      NO_IO_CHECK='Both';
      NO_ASSERT_CHECK='TRUE';
      NO_DIR_CHECK='TRUE';
      ALLOW_CONNECT='TRUE';
    'VCCIN'<198>:
      PIN_NUMBER='(0,0,0,0,0,0,0,0,0,0,0,0,0,0,0,0,0,BG60,0,0,0,0,0,0,0,0,0,0,0,~
0)';
      PINUSE='POWER';
      NO_LOAD_CHECK='Both';
      NO_IO_CHECK='Both';
      NO_ASSERT_CHECK='TRUE';
      NO_DIR_CHECK='TRUE';
      ALLOW_CONNECT='TRUE';
    'VCCIN'<197>:
      PIN_NUMBER='(0,0,0,0,0,0,0,0,0,0,0,0,0,0,0,0,0,BG62,0,0,0,0,0,0,0,0,0,0,0,~
0)';
      PINUSE='POWER';
      NO_LOAD_CHECK='Both';
      NO_IO_CHECK='Both';
      NO_ASSERT_CHECK='TRUE';
      NO_DIR_CHECK='TRUE';
      ALLOW_CONNECT='TRUE';
    'VCCIN'<196>:
      PIN_NUMBER='(0,0,0,0,0,0,0,0,0,0,0,0,0,0,0,0,0,BG64,0,0,0,0,0,0,0,0,0,0,0,~
0)';
      PINUSE='POWER';
      NO_LOAD_CHECK='Both';
      NO_IO_CHECK='Both';
      NO_ASSERT_CHECK='TRUE';
      NO_DIR_CHECK='TRUE';
      ALLOW_CONNECT='TRUE';
    'VCCIN'<195>:
      PIN_NUMBER='(0,0,0,0,0,0,0,0,0,0,0,0,0,0,0,0,0,BG66,0,0,0,0,0,0,0,0,0,0,0,~
0)';
      PINUSE='POWER';
      NO_LOAD_CHECK='Both';
      NO_IO_CHECK='Both';
      NO_ASSERT_CHECK='TRUE';
      NO_DIR_CHECK='TRUE';
      ALLOW_CONNECT='TRUE';
    'VCCIN'<194>:
      PIN_NUMBER='(0,0,0,0,0,0,0,0,0,0,0,0,0,0,0,0,0,BG68,0,0,0,0,0,0,0,0,0,0,0,~
0)';
      PINUSE='POWER';
      NO_LOAD_CHECK='Both';
      NO_IO_CHECK='Both';
      NO_ASSERT_CHECK='TRUE';
      NO_DIR_CHECK='TRUE';
      ALLOW_CONNECT='TRUE';
    'VCCIN'<193>:
      PIN_NUMBER='(0,0,0,0,0,0,0,0,0,0,0,0,0,0,0,0,0,BG70,0,0,0,0,0,0,0,0,0,0,0,~
0)';
      PINUSE='POWER';
      NO_LOAD_CHECK='Both';
      NO_IO_CHECK='Both';
      NO_ASSERT_CHECK='TRUE';
      NO_DIR_CHECK='TRUE';
      ALLOW_CONNECT='TRUE';
    'VCCIN'<192>:
      PIN_NUMBER='(0,0,0,0,0,0,0,0,0,0,0,0,0,0,0,0,0,BG84,0,0,0,0,0,0,0,0,0,0,0,~
0)';
      PINUSE='POWER';
      NO_LOAD_CHECK='Both';
      NO_IO_CHECK='Both';
      NO_ASSERT_CHECK='TRUE';
      NO_DIR_CHECK='TRUE';
      ALLOW_CONNECT='TRUE';
    'VCCIN'<191>:
      PIN_NUMBER='(0,0,0,0,0,0,0,0,0,0,0,0,0,0,0,0,0,BH61,0,0,0,0,0,0,0,0,0,0,0,~
0)';
      PINUSE='POWER';
      NO_LOAD_CHECK='Both';
      NO_IO_CHECK='Both';
      NO_ASSERT_CHECK='TRUE';
      NO_DIR_CHECK='TRUE';
      ALLOW_CONNECT='TRUE';
    'VCCIN'<190>:
      PIN_NUMBER='(0,0,0,0,0,0,0,0,0,0,0,0,0,0,0,0,0,BH63,0,0,0,0,0,0,0,0,0,0,0,~
0)';
      PINUSE='POWER';
      NO_LOAD_CHECK='Both';
      NO_IO_CHECK='Both';
      NO_ASSERT_CHECK='TRUE';
      NO_DIR_CHECK='TRUE';
      ALLOW_CONNECT='TRUE';
    'VCCIN'<189>:
      PIN_NUMBER='(0,0,0,0,0,0,0,0,0,0,0,0,0,0,0,0,0,BH65,0,0,0,0,0,0,0,0,0,0,0,~
0)';
      PINUSE='POWER';
      NO_LOAD_CHECK='Both';
      NO_IO_CHECK='Both';
      NO_ASSERT_CHECK='TRUE';
      NO_DIR_CHECK='TRUE';
      ALLOW_CONNECT='TRUE';
    'VCCIN'<188>:
      PIN_NUMBER='(0,0,0,0,0,0,0,0,0,0,0,0,0,0,0,0,0,BH67,0,0,0,0,0,0,0,0,0,0,0,~
0)';
      PINUSE='POWER';
      NO_LOAD_CHECK='Both';
      NO_IO_CHECK='Both';
      NO_ASSERT_CHECK='TRUE';
      NO_DIR_CHECK='TRUE';
      ALLOW_CONNECT='TRUE';
    'VCCIN'<187>:
      PIN_NUMBER='(0,0,0,0,0,0,0,0,0,0,0,0,0,0,0,0,0,BH69,0,0,0,0,0,0,0,0,0,0,0,~
0)';
      PINUSE='POWER';
      NO_LOAD_CHECK='Both';
      NO_IO_CHECK='Both';
      NO_ASSERT_CHECK='TRUE';
      NO_DIR_CHECK='TRUE';
      ALLOW_CONNECT='TRUE';
    'VCCIN'<186>:
      PIN_NUMBER='(0,0,0,0,0,0,0,0,0,0,0,0,0,0,0,0,0,BH71,0,0,0,0,0,0,0,0,0,0,0,~
0)';
      PINUSE='POWER';
      NO_LOAD_CHECK='Both';
      NO_IO_CHECK='Both';
      NO_ASSERT_CHECK='TRUE';
      NO_DIR_CHECK='TRUE';
      ALLOW_CONNECT='TRUE';
    'VCCIN'<185>:
      PIN_NUMBER='(0,0,0,0,0,0,0,0,0,0,0,0,0,0,0,0,0,BH73,0,0,0,0,0,0,0,0,0,0,0,~
0)';
      PINUSE='POWER';
      NO_LOAD_CHECK='Both';
      NO_IO_CHECK='Both';
      NO_ASSERT_CHECK='TRUE';
      NO_DIR_CHECK='TRUE';
      ALLOW_CONNECT='TRUE';
    'VCCIN'<184>:
      PIN_NUMBER='(0,0,0,0,0,0,0,0,0,0,0,0,0,0,0,0,0,BH75,0,0,0,0,0,0,0,0,0,0,0,~
0)';
      PINUSE='POWER';
      NO_LOAD_CHECK='Both';
      NO_IO_CHECK='Both';
      NO_ASSERT_CHECK='TRUE';
      NO_DIR_CHECK='TRUE';
      ALLOW_CONNECT='TRUE';
    'VCCIN'<183>:
      PIN_NUMBER='(0,0,0,0,0,0,0,0,0,0,0,0,0,0,0,0,0,BH77,0,0,0,0,0,0,0,0,0,0,0,~
0)';
      PINUSE='POWER';
      NO_LOAD_CHECK='Both';
      NO_IO_CHECK='Both';
      NO_ASSERT_CHECK='TRUE';
      NO_DIR_CHECK='TRUE';
      ALLOW_CONNECT='TRUE';
    'VCCIN'<182>:
      PIN_NUMBER='(0,0,0,0,0,0,0,0,0,0,0,0,0,0,0,0,0,BH79,0,0,0,0,0,0,0,0,0,0,0,~
0)';
      PINUSE='POWER';
      NO_LOAD_CHECK='Both';
      NO_IO_CHECK='Both';
      NO_ASSERT_CHECK='TRUE';
      NO_DIR_CHECK='TRUE';
      ALLOW_CONNECT='TRUE';
    'VCCIN'<181>:
      PIN_NUMBER='(0,0,0,0,0,0,0,0,0,0,0,0,0,0,0,0,0,BH81,0,0,0,0,0,0,0,0,0,0,0,~
0)';
      PINUSE='POWER';
      NO_LOAD_CHECK='Both';
      NO_IO_CHECK='Both';
      NO_ASSERT_CHECK='TRUE';
      NO_DIR_CHECK='TRUE';
      ALLOW_CONNECT='TRUE';
    'VCCIN'<180>:
      PIN_NUMBER='(0,0,0,0,0,0,0,0,0,0,0,0,0,0,0,0,0,BH83,0,0,0,0,0,0,0,0,0,0,0,~
0)';
      PINUSE='POWER';
      NO_LOAD_CHECK='Both';
      NO_IO_CHECK='Both';
      NO_ASSERT_CHECK='TRUE';
      NO_DIR_CHECK='TRUE';
      ALLOW_CONNECT='TRUE';
    'VCCIN'<179>:
      PIN_NUMBER='(0,0,0,0,0,0,0,0,0,0,0,0,0,0,0,0,0,BJ60,0,0,0,0,0,0,0,0,0,0,0,~
0)';
      PINUSE='POWER';
      NO_LOAD_CHECK='Both';
      NO_IO_CHECK='Both';
      NO_ASSERT_CHECK='TRUE';
      NO_DIR_CHECK='TRUE';
      ALLOW_CONNECT='TRUE';
    'VCCIN'<178>:
      PIN_NUMBER='(0,0,0,0,0,0,0,0,0,0,0,0,0,0,0,0,0,BJ62,0,0,0,0,0,0,0,0,0,0,0,~
0)';
      PINUSE='POWER';
      NO_LOAD_CHECK='Both';
      NO_IO_CHECK='Both';
      NO_ASSERT_CHECK='TRUE';
      NO_DIR_CHECK='TRUE';
      ALLOW_CONNECT='TRUE';
    'VCCIN'<177>:
      PIN_NUMBER='(0,0,0,0,0,0,0,0,0,0,0,0,0,0,0,0,0,BJ64,0,0,0,0,0,0,0,0,0,0,0,~
0)';
      PINUSE='POWER';
      NO_LOAD_CHECK='Both';
      NO_IO_CHECK='Both';
      NO_ASSERT_CHECK='TRUE';
      NO_DIR_CHECK='TRUE';
      ALLOW_CONNECT='TRUE';
    'VCCIN'<176>:
      PIN_NUMBER='(0,0,0,0,0,0,0,0,0,0,0,0,0,0,0,0,0,BJ66,0,0,0,0,0,0,0,0,0,0,0,~
0)';
      PINUSE='POWER';
      NO_LOAD_CHECK='Both';
      NO_IO_CHECK='Both';
      NO_ASSERT_CHECK='TRUE';
      NO_DIR_CHECK='TRUE';
      ALLOW_CONNECT='TRUE';
    'VCCIN'<175>:
      PIN_NUMBER='(0,0,0,0,0,0,0,0,0,0,0,0,0,0,0,0,0,BJ68,0,0,0,0,0,0,0,0,0,0,0,~
0)';
      PINUSE='POWER';
      NO_LOAD_CHECK='Both';
      NO_IO_CHECK='Both';
      NO_ASSERT_CHECK='TRUE';
      NO_DIR_CHECK='TRUE';
      ALLOW_CONNECT='TRUE';
    'VCCIN'<174>:
      PIN_NUMBER='(0,0,0,0,0,0,0,0,0,0,0,0,0,0,0,0,0,BJ70,0,0,0,0,0,0,0,0,0,0,0,~
0)';
      PINUSE='POWER';
      NO_LOAD_CHECK='Both';
      NO_IO_CHECK='Both';
      NO_ASSERT_CHECK='TRUE';
      NO_DIR_CHECK='TRUE';
      ALLOW_CONNECT='TRUE';
    'VCCIN'<173>:
      PIN_NUMBER='(0,0,0,0,0,0,0,0,0,0,0,0,0,0,0,0,0,BJ72,0,0,0,0,0,0,0,0,0,0,0,~
0)';
      PINUSE='POWER';
      NO_LOAD_CHECK='Both';
      NO_IO_CHECK='Both';
      NO_ASSERT_CHECK='TRUE';
      NO_DIR_CHECK='TRUE';
      ALLOW_CONNECT='TRUE';
    'VCCIN'<172>:
      PIN_NUMBER='(0,0,0,0,0,0,0,0,0,0,0,0,0,0,0,0,0,BJ74,0,0,0,0,0,0,0,0,0,0,0,~
0)';
      PINUSE='POWER';
      NO_LOAD_CHECK='Both';
      NO_IO_CHECK='Both';
      NO_ASSERT_CHECK='TRUE';
      NO_DIR_CHECK='TRUE';
      ALLOW_CONNECT='TRUE';
    'VCCIN'<171>:
      PIN_NUMBER='(0,0,0,0,0,0,0,0,0,0,0,0,0,0,0,0,0,BJ76,0,0,0,0,0,0,0,0,0,0,0,~
0)';
      PINUSE='POWER';
      NO_LOAD_CHECK='Both';
      NO_IO_CHECK='Both';
      NO_ASSERT_CHECK='TRUE';
      NO_DIR_CHECK='TRUE';
      ALLOW_CONNECT='TRUE';
    'VCCIN'<170>:
      PIN_NUMBER='(0,0,0,0,0,0,0,0,0,0,0,0,0,0,0,0,0,BJ78,0,0,0,0,0,0,0,0,0,0,0,~
0)';
      PINUSE='POWER';
      NO_LOAD_CHECK='Both';
      NO_IO_CHECK='Both';
      NO_ASSERT_CHECK='TRUE';
      NO_DIR_CHECK='TRUE';
      ALLOW_CONNECT='TRUE';
    'VCCIN'<169>:
      PIN_NUMBER='(0,0,0,0,0,0,0,0,0,0,0,0,0,0,0,0,0,BJ80,0,0,0,0,0,0,0,0,0,0,0,~
0)';
      PINUSE='POWER';
      NO_LOAD_CHECK='Both';
      NO_IO_CHECK='Both';
      NO_ASSERT_CHECK='TRUE';
      NO_DIR_CHECK='TRUE';
      ALLOW_CONNECT='TRUE';
    'VCCIN'<168>:
      PIN_NUMBER='(0,0,0,0,0,0,0,0,0,0,0,0,0,0,0,0,0,BJ82,0,0,0,0,0,0,0,0,0,0,0,~
0)';
      PINUSE='POWER';
      NO_LOAD_CHECK='Both';
      NO_IO_CHECK='Both';
      NO_ASSERT_CHECK='TRUE';
      NO_DIR_CHECK='TRUE';
      ALLOW_CONNECT='TRUE';
    'VCCIN'<167>:
      PIN_NUMBER='(0,0,0,0,0,0,0,0,0,0,0,0,0,0,0,0,0,BJ84,0,0,0,0,0,0,0,0,0,0,0,~
0)';
      PINUSE='POWER';
      NO_LOAD_CHECK='Both';
      NO_IO_CHECK='Both';
      NO_ASSERT_CHECK='TRUE';
      NO_DIR_CHECK='TRUE';
      ALLOW_CONNECT='TRUE';
    'VCCIN'<166>:
      PIN_NUMBER='(0,0,0,0,0,0,0,0,0,0,0,0,0,0,0,0,0,BK61,0,0,0,0,0,0,0,0,0,0,0,~
0)';
      PINUSE='POWER';
      NO_LOAD_CHECK='Both';
      NO_IO_CHECK='Both';
      NO_ASSERT_CHECK='TRUE';
      NO_DIR_CHECK='TRUE';
      ALLOW_CONNECT='TRUE';
    'VCCIN'<165>:
      PIN_NUMBER='(0,0,0,0,0,0,0,0,0,0,0,0,0,0,0,0,0,BK63,0,0,0,0,0,0,0,0,0,0,0,~
0)';
      PINUSE='POWER';
      NO_LOAD_CHECK='Both';
      NO_IO_CHECK='Both';
      NO_ASSERT_CHECK='TRUE';
      NO_DIR_CHECK='TRUE';
      ALLOW_CONNECT='TRUE';
    'VCCIN'<164>:
      PIN_NUMBER='(0,0,0,0,0,0,0,0,0,0,0,0,0,0,0,0,0,BK65,0,0,0,0,0,0,0,0,0,0,0,~
0)';
      PINUSE='POWER';
      NO_LOAD_CHECK='Both';
      NO_IO_CHECK='Both';
      NO_ASSERT_CHECK='TRUE';
      NO_DIR_CHECK='TRUE';
      ALLOW_CONNECT='TRUE';
    'VCCIN'<163>:
      PIN_NUMBER='(0,0,0,0,0,0,0,0,0,0,0,0,0,0,0,0,0,BK67,0,0,0,0,0,0,0,0,0,0,0,~
0)';
      PINUSE='POWER';
      NO_LOAD_CHECK='Both';
      NO_IO_CHECK='Both';
      NO_ASSERT_CHECK='TRUE';
      NO_DIR_CHECK='TRUE';
      ALLOW_CONNECT='TRUE';
    'VCCIN'<162>:
      PIN_NUMBER='(0,0,0,0,0,0,0,0,0,0,0,0,0,0,0,0,0,BK69,0,0,0,0,0,0,0,0,0,0,0,~
0)';
      PINUSE='POWER';
      NO_LOAD_CHECK='Both';
      NO_IO_CHECK='Both';
      NO_ASSERT_CHECK='TRUE';
      NO_DIR_CHECK='TRUE';
      ALLOW_CONNECT='TRUE';
    'VCCIN'<161>:
      PIN_NUMBER='(0,0,0,0,0,0,0,0,0,0,0,0,0,0,0,0,0,BK71,0,0,0,0,0,0,0,0,0,0,0,~
0)';
      PINUSE='POWER';
      NO_LOAD_CHECK='Both';
      NO_IO_CHECK='Both';
      NO_ASSERT_CHECK='TRUE';
      NO_DIR_CHECK='TRUE';
      ALLOW_CONNECT='TRUE';
    'VCCIN'<160>:
      PIN_NUMBER='(0,0,0,0,0,0,0,0,0,0,0,0,0,0,0,0,0,BK73,0,0,0,0,0,0,0,0,0,0,0,~
0)';
      PINUSE='POWER';
      NO_LOAD_CHECK='Both';
      NO_IO_CHECK='Both';
      NO_ASSERT_CHECK='TRUE';
      NO_DIR_CHECK='TRUE';
      ALLOW_CONNECT='TRUE';
    'VCCIN'<159>:
      PIN_NUMBER='(0,0,0,0,0,0,0,0,0,0,0,0,0,0,0,0,0,BK75,0,0,0,0,0,0,0,0,0,0,0,~
0)';
      PINUSE='POWER';
      NO_LOAD_CHECK='Both';
      NO_IO_CHECK='Both';
      NO_ASSERT_CHECK='TRUE';
      NO_DIR_CHECK='TRUE';
      ALLOW_CONNECT='TRUE';
    'VCCIN'<158>:
      PIN_NUMBER='(0,0,0,0,0,0,0,0,0,0,0,0,0,0,0,0,0,BK77,0,0,0,0,0,0,0,0,0,0,0,~
0)';
      PINUSE='POWER';
      NO_LOAD_CHECK='Both';
      NO_IO_CHECK='Both';
      NO_ASSERT_CHECK='TRUE';
      NO_DIR_CHECK='TRUE';
      ALLOW_CONNECT='TRUE';
    'VCCIN'<157>:
      PIN_NUMBER='(0,0,0,0,0,0,0,0,0,0,0,0,0,0,0,0,0,BK79,0,0,0,0,0,0,0,0,0,0,0,~
0)';
      PINUSE='POWER';
      NO_LOAD_CHECK='Both';
      NO_IO_CHECK='Both';
      NO_ASSERT_CHECK='TRUE';
      NO_DIR_CHECK='TRUE';
      ALLOW_CONNECT='TRUE';
    'VCCIN'<156>:
      PIN_NUMBER='(0,0,0,0,0,0,0,0,0,0,0,0,0,0,0,0,0,BK81,0,0,0,0,0,0,0,0,0,0,0,~
0)';
      PINUSE='POWER';
      NO_LOAD_CHECK='Both';
      NO_IO_CHECK='Both';
      NO_ASSERT_CHECK='TRUE';
      NO_DIR_CHECK='TRUE';
      ALLOW_CONNECT='TRUE';
    'VCCIN'<155>:
      PIN_NUMBER='(0,0,0,0,0,0,0,0,0,0,0,0,0,0,0,0,0,BK83,0,0,0,0,0,0,0,0,0,0,0,~
0)';
      PINUSE='POWER';
      NO_LOAD_CHECK='Both';
      NO_IO_CHECK='Both';
      NO_ASSERT_CHECK='TRUE';
      NO_DIR_CHECK='TRUE';
      ALLOW_CONNECT='TRUE';
    'VCCIN'<154>:
      PIN_NUMBER='(0,0,0,0,0,0,0,0,0,0,0,0,0,0,0,0,0,BL60,0,0,0,0,0,0,0,0,0,0,0,~
0)';
      PINUSE='POWER';
      NO_LOAD_CHECK='Both';
      NO_IO_CHECK='Both';
      NO_ASSERT_CHECK='TRUE';
      NO_DIR_CHECK='TRUE';
      ALLOW_CONNECT='TRUE';
    'VCCIN'<153>:
      PIN_NUMBER='(0,0,0,0,0,0,0,0,0,0,0,0,0,0,0,0,0,BL62,0,0,0,0,0,0,0,0,0,0,0,~
0)';
      PINUSE='POWER';
      NO_LOAD_CHECK='Both';
      NO_IO_CHECK='Both';
      NO_ASSERT_CHECK='TRUE';
      NO_DIR_CHECK='TRUE';
      ALLOW_CONNECT='TRUE';
    'VCCIN'<152>:
      PIN_NUMBER='(0,0,0,0,0,0,0,0,0,0,0,0,0,0,0,0,0,BL84,0,0,0,0,0,0,0,0,0,0,0,~
0)';
      PINUSE='POWER';
      NO_LOAD_CHECK='Both';
      NO_IO_CHECK='Both';
      NO_ASSERT_CHECK='TRUE';
      NO_DIR_CHECK='TRUE';
      ALLOW_CONNECT='TRUE';
    'VCCIN'<151>:
      PIN_NUMBER='(0,0,0,0,0,0,0,0,0,0,0,0,0,0,0,0,0,BM61,0,0,0,0,0,0,0,0,0,0,0,~
0)';
      PINUSE='POWER';
      NO_LOAD_CHECK='Both';
      NO_IO_CHECK='Both';
      NO_ASSERT_CHECK='TRUE';
      NO_DIR_CHECK='TRUE';
      ALLOW_CONNECT='TRUE';
    'VCCIN'<150>:
      PIN_NUMBER='(0,0,0,0,0,0,0,0,0,0,0,0,0,0,0,0,0,BM63,0,0,0,0,0,0,0,0,0,0,0,~
0)';
      PINUSE='POWER';
      NO_LOAD_CHECK='Both';
      NO_IO_CHECK='Both';
      NO_ASSERT_CHECK='TRUE';
      NO_DIR_CHECK='TRUE';
      ALLOW_CONNECT='TRUE';
    'VCCIN'<149>:
      PIN_NUMBER='(0,0,0,0,0,0,0,0,0,0,0,0,0,0,0,0,0,BM65,0,0,0,0,0,0,0,0,0,0,0,~
0)';
      PINUSE='POWER';
      NO_LOAD_CHECK='Both';
      NO_IO_CHECK='Both';
      NO_ASSERT_CHECK='TRUE';
      NO_DIR_CHECK='TRUE';
      ALLOW_CONNECT='TRUE';
    'VCCIN'<148>:
      PIN_NUMBER='(0,0,0,0,0,0,0,0,0,0,0,0,0,0,0,0,0,BM67,0,0,0,0,0,0,0,0,0,0,0,~
0)';
      PINUSE='POWER';
      NO_LOAD_CHECK='Both';
      NO_IO_CHECK='Both';
      NO_ASSERT_CHECK='TRUE';
      NO_DIR_CHECK='TRUE';
      ALLOW_CONNECT='TRUE';
    'VCCIN'<147>:
      PIN_NUMBER='(0,0,0,0,0,0,0,0,0,0,0,0,0,0,0,0,0,BM69,0,0,0,0,0,0,0,0,0,0,0,~
0)';
      PINUSE='POWER';
      NO_LOAD_CHECK='Both';
      NO_IO_CHECK='Both';
      NO_ASSERT_CHECK='TRUE';
      NO_DIR_CHECK='TRUE';
      ALLOW_CONNECT='TRUE';
    'VCCIN'<146>:
      PIN_NUMBER='(0,0,0,0,0,0,0,0,0,0,0,0,0,0,0,0,0,BM71,0,0,0,0,0,0,0,0,0,0,0,~
0)';
      PINUSE='POWER';
      NO_LOAD_CHECK='Both';
      NO_IO_CHECK='Both';
      NO_ASSERT_CHECK='TRUE';
      NO_DIR_CHECK='TRUE';
      ALLOW_CONNECT='TRUE';
    'VCCIN'<145>:
      PIN_NUMBER='(0,0,0,0,0,0,0,0,0,0,0,0,0,0,0,0,0,BM73,0,0,0,0,0,0,0,0,0,0,0,~
0)';
      PINUSE='POWER';
      NO_LOAD_CHECK='Both';
      NO_IO_CHECK='Both';
      NO_ASSERT_CHECK='TRUE';
      NO_DIR_CHECK='TRUE';
      ALLOW_CONNECT='TRUE';
    'VCCIN'<144>:
      PIN_NUMBER='(0,0,0,0,0,0,0,0,0,0,0,0,0,0,0,0,0,BM75,0,0,0,0,0,0,0,0,0,0,0,~
0)';
      PINUSE='POWER';
      NO_LOAD_CHECK='Both';
      NO_IO_CHECK='Both';
      NO_ASSERT_CHECK='TRUE';
      NO_DIR_CHECK='TRUE';
      ALLOW_CONNECT='TRUE';
    'VCCIN'<143>:
      PIN_NUMBER='(0,0,0,0,0,0,0,0,0,0,0,0,0,0,0,0,0,BM77,0,0,0,0,0,0,0,0,0,0,0,~
0)';
      PINUSE='POWER';
      NO_LOAD_CHECK='Both';
      NO_IO_CHECK='Both';
      NO_ASSERT_CHECK='TRUE';
      NO_DIR_CHECK='TRUE';
      ALLOW_CONNECT='TRUE';
    'VCCIN'<142>:
      PIN_NUMBER='(0,0,0,0,0,0,0,0,0,0,0,0,0,0,0,0,0,BM79,0,0,0,0,0,0,0,0,0,0,0,~
0)';
      PINUSE='POWER';
      NO_LOAD_CHECK='Both';
      NO_IO_CHECK='Both';
      NO_ASSERT_CHECK='TRUE';
      NO_DIR_CHECK='TRUE';
      ALLOW_CONNECT='TRUE';
    'VCCIN'<141>:
      PIN_NUMBER='(0,0,0,0,0,0,0,0,0,0,0,0,0,0,0,0,0,BM81,0,0,0,0,0,0,0,0,0,0,0,~
0)';
      PINUSE='POWER';
      NO_LOAD_CHECK='Both';
      NO_IO_CHECK='Both';
      NO_ASSERT_CHECK='TRUE';
      NO_DIR_CHECK='TRUE';
      ALLOW_CONNECT='TRUE';
    'VCCIN'<140>:
      PIN_NUMBER='(0,0,0,0,0,0,0,0,0,0,0,0,0,0,0,0,0,BM83,0,0,0,0,0,0,0,0,0,0,0,~
0)';
      PINUSE='POWER';
      NO_LOAD_CHECK='Both';
      NO_IO_CHECK='Both';
      NO_ASSERT_CHECK='TRUE';
      NO_DIR_CHECK='TRUE';
      ALLOW_CONNECT='TRUE';
    'VCCIN'<139>:
      PIN_NUMBER='(0,0,0,0,0,0,0,0,0,0,0,0,0,0,0,0,0,BN60,0,0,0,0,0,0,0,0,0,0,0,~
0)';
      PINUSE='POWER';
      NO_LOAD_CHECK='Both';
      NO_IO_CHECK='Both';
      NO_ASSERT_CHECK='TRUE';
      NO_DIR_CHECK='TRUE';
      ALLOW_CONNECT='TRUE';
    'VCCIN'<138>:
      PIN_NUMBER='(0,0,0,0,0,0,0,0,0,0,0,0,0,0,0,0,0,BN62,0,0,0,0,0,0,0,0,0,0,0,~
0)';
      PINUSE='POWER';
      NO_LOAD_CHECK='Both';
      NO_IO_CHECK='Both';
      NO_ASSERT_CHECK='TRUE';
      NO_DIR_CHECK='TRUE';
      ALLOW_CONNECT='TRUE';
    'VCCIN'<137>:
      PIN_NUMBER='(0,0,0,0,0,0,0,0,0,0,0,0,0,0,0,0,0,BN64,0,0,0,0,0,0,0,0,0,0,0,~
0)';
      PINUSE='POWER';
      NO_LOAD_CHECK='Both';
      NO_IO_CHECK='Both';
      NO_ASSERT_CHECK='TRUE';
      NO_DIR_CHECK='TRUE';
      ALLOW_CONNECT='TRUE';
    'VCCIN'<136>:
      PIN_NUMBER='(0,0,0,0,0,0,0,0,0,0,0,0,0,0,0,0,0,BN66,0,0,0,0,0,0,0,0,0,0,0,~
0)';
      PINUSE='POWER';
      NO_LOAD_CHECK='Both';
      NO_IO_CHECK='Both';
      NO_ASSERT_CHECK='TRUE';
      NO_DIR_CHECK='TRUE';
      ALLOW_CONNECT='TRUE';
    'VCCIN'<135>:
      PIN_NUMBER='(0,0,0,0,0,0,0,0,0,0,0,0,0,0,0,0,0,BN68,0,0,0,0,0,0,0,0,0,0,0,~
0)';
      PINUSE='POWER';
      NO_LOAD_CHECK='Both';
      NO_IO_CHECK='Both';
      NO_ASSERT_CHECK='TRUE';
      NO_DIR_CHECK='TRUE';
      ALLOW_CONNECT='TRUE';
    'VCCIN'<134>:
      PIN_NUMBER='(0,0,0,0,0,0,0,0,0,0,0,0,0,0,0,0,0,BN70,0,0,0,0,0,0,0,0,0,0,0,~
0)';
      PINUSE='POWER';
      NO_LOAD_CHECK='Both';
      NO_IO_CHECK='Both';
      NO_ASSERT_CHECK='TRUE';
      NO_DIR_CHECK='TRUE';
      ALLOW_CONNECT='TRUE';
    'VCCIN'<133>:
      PIN_NUMBER='(0,0,0,0,0,0,0,0,0,0,0,0,0,0,0,0,0,BN72,0,0,0,0,0,0,0,0,0,0,0,~
0)';
      PINUSE='POWER';
      NO_LOAD_CHECK='Both';
      NO_IO_CHECK='Both';
      NO_ASSERT_CHECK='TRUE';
      NO_DIR_CHECK='TRUE';
      ALLOW_CONNECT='TRUE';
    'VCCIN'<132>:
      PIN_NUMBER='(0,0,0,0,0,0,0,0,0,0,0,0,0,0,0,0,0,BN74,0,0,0,0,0,0,0,0,0,0,0,~
0)';
      PINUSE='POWER';
      NO_LOAD_CHECK='Both';
      NO_IO_CHECK='Both';
      NO_ASSERT_CHECK='TRUE';
      NO_DIR_CHECK='TRUE';
      ALLOW_CONNECT='TRUE';
    'VCCIN'<131>:
      PIN_NUMBER='(0,0,0,0,0,0,0,0,0,0,0,0,0,0,0,0,0,BN76,0,0,0,0,0,0,0,0,0,0,0,~
0)';
      PINUSE='POWER';
      NO_LOAD_CHECK='Both';
      NO_IO_CHECK='Both';
      NO_ASSERT_CHECK='TRUE';
      NO_DIR_CHECK='TRUE';
      ALLOW_CONNECT='TRUE';
    'VCCIN'<130>:
      PIN_NUMBER='(0,0,0,0,0,0,0,0,0,0,0,0,0,0,0,0,0,BN78,0,0,0,0,0,0,0,0,0,0,0,~
0)';
      PINUSE='POWER';
      NO_LOAD_CHECK='Both';
      NO_IO_CHECK='Both';
      NO_ASSERT_CHECK='TRUE';
      NO_DIR_CHECK='TRUE';
      ALLOW_CONNECT='TRUE';
    'VCCIN'<129>:
      PIN_NUMBER='(0,0,0,0,0,0,0,0,0,0,0,0,0,0,0,0,0,0,BN80,0,0,0,0,0,0,0,0,0,0,~
0)';
      PINUSE='POWER';
      NO_LOAD_CHECK='Both';
      NO_IO_CHECK='Both';
      NO_ASSERT_CHECK='TRUE';
      NO_DIR_CHECK='TRUE';
      ALLOW_CONNECT='TRUE';
    'VCCIN'<128>:
      PIN_NUMBER='(0,0,0,0,0,0,0,0,0,0,0,0,0,0,0,0,0,0,BN82,0,0,0,0,0,0,0,0,0,0,~
0)';
      PINUSE='POWER';
      NO_LOAD_CHECK='Both';
      NO_IO_CHECK='Both';
      NO_ASSERT_CHECK='TRUE';
      NO_DIR_CHECK='TRUE';
      ALLOW_CONNECT='TRUE';
    'VCCIN'<127>:
      PIN_NUMBER='(0,0,0,0,0,0,0,0,0,0,0,0,0,0,0,0,0,0,BN84,0,0,0,0,0,0,0,0,0,0,~
0)';
      PINUSE='POWER';
      NO_LOAD_CHECK='Both';
      NO_IO_CHECK='Both';
      NO_ASSERT_CHECK='TRUE';
      NO_DIR_CHECK='TRUE';
      ALLOW_CONNECT='TRUE';
    'VCCIN'<126>:
      PIN_NUMBER='(0,0,0,0,0,0,0,0,0,0,0,0,0,0,0,0,0,0,BP61,0,0,0,0,0,0,0,0,0,0,~
0)';
      PINUSE='POWER';
      NO_LOAD_CHECK='Both';
      NO_IO_CHECK='Both';
      NO_ASSERT_CHECK='TRUE';
      NO_DIR_CHECK='TRUE';
      ALLOW_CONNECT='TRUE';
    'VCCIN'<125>:
      PIN_NUMBER='(0,0,0,0,0,0,0,0,0,0,0,0,0,0,0,0,0,0,BP63,0,0,0,0,0,0,0,0,0,0,~
0)';
      PINUSE='POWER';
      NO_LOAD_CHECK='Both';
      NO_IO_CHECK='Both';
      NO_ASSERT_CHECK='TRUE';
      NO_DIR_CHECK='TRUE';
      ALLOW_CONNECT='TRUE';
    'VCCIN'<124>:
      PIN_NUMBER='(0,0,0,0,0,0,0,0,0,0,0,0,0,0,0,0,0,0,BP65,0,0,0,0,0,0,0,0,0,0,~
0)';
      PINUSE='POWER';
      NO_LOAD_CHECK='Both';
      NO_IO_CHECK='Both';
      NO_ASSERT_CHECK='TRUE';
      NO_DIR_CHECK='TRUE';
      ALLOW_CONNECT='TRUE';
    'VCCIN'<123>:
      PIN_NUMBER='(0,0,0,0,0,0,0,0,0,0,0,0,0,0,0,0,0,0,BP67,0,0,0,0,0,0,0,0,0,0,~
0)';
      PINUSE='POWER';
      NO_LOAD_CHECK='Both';
      NO_IO_CHECK='Both';
      NO_ASSERT_CHECK='TRUE';
      NO_DIR_CHECK='TRUE';
      ALLOW_CONNECT='TRUE';
    'VCCIN'<122>:
      PIN_NUMBER='(0,0,0,0,0,0,0,0,0,0,0,0,0,0,0,0,0,0,BP69,0,0,0,0,0,0,0,0,0,0,~
0)';
      PINUSE='POWER';
      NO_LOAD_CHECK='Both';
      NO_IO_CHECK='Both';
      NO_ASSERT_CHECK='TRUE';
      NO_DIR_CHECK='TRUE';
      ALLOW_CONNECT='TRUE';
    'VCCIN'<121>:
      PIN_NUMBER='(0,0,0,0,0,0,0,0,0,0,0,0,0,0,0,0,0,0,BP71,0,0,0,0,0,0,0,0,0,0,~
0)';
      PINUSE='POWER';
      NO_LOAD_CHECK='Both';
      NO_IO_CHECK='Both';
      NO_ASSERT_CHECK='TRUE';
      NO_DIR_CHECK='TRUE';
      ALLOW_CONNECT='TRUE';
    'VCCIN'<120>:
      PIN_NUMBER='(0,0,0,0,0,0,0,0,0,0,0,0,0,0,0,0,0,0,BP73,0,0,0,0,0,0,0,0,0,0,~
0)';
      PINUSE='POWER';
      NO_LOAD_CHECK='Both';
      NO_IO_CHECK='Both';
      NO_ASSERT_CHECK='TRUE';
      NO_DIR_CHECK='TRUE';
      ALLOW_CONNECT='TRUE';
    'VCCIN'<119>:
      PIN_NUMBER='(0,0,0,0,0,0,0,0,0,0,0,0,0,0,0,0,0,0,BP75,0,0,0,0,0,0,0,0,0,0,~
0)';
      PINUSE='POWER';
      NO_LOAD_CHECK='Both';
      NO_IO_CHECK='Both';
      NO_ASSERT_CHECK='TRUE';
      NO_DIR_CHECK='TRUE';
      ALLOW_CONNECT='TRUE';
    'VCCIN'<118>:
      PIN_NUMBER='(0,0,0,0,0,0,0,0,0,0,0,0,0,0,0,0,0,0,BP77,0,0,0,0,0,0,0,0,0,0,~
0)';
      PINUSE='POWER';
      NO_LOAD_CHECK='Both';
      NO_IO_CHECK='Both';
      NO_ASSERT_CHECK='TRUE';
      NO_DIR_CHECK='TRUE';
      ALLOW_CONNECT='TRUE';
    'VCCIN'<117>:
      PIN_NUMBER='(0,0,0,0,0,0,0,0,0,0,0,0,0,0,0,0,0,0,BP79,0,0,0,0,0,0,0,0,0,0,~
0)';
      PINUSE='POWER';
      NO_LOAD_CHECK='Both';
      NO_IO_CHECK='Both';
      NO_ASSERT_CHECK='TRUE';
      NO_DIR_CHECK='TRUE';
      ALLOW_CONNECT='TRUE';
    'VCCIN'<116>:
      PIN_NUMBER='(0,0,0,0,0,0,0,0,0,0,0,0,0,0,0,0,0,0,BP81,0,0,0,0,0,0,0,0,0,0,~
0)';
      PINUSE='POWER';
      NO_LOAD_CHECK='Both';
      NO_IO_CHECK='Both';
      NO_ASSERT_CHECK='TRUE';
      NO_DIR_CHECK='TRUE';
      ALLOW_CONNECT='TRUE';
    'VCCIN'<115>:
      PIN_NUMBER='(0,0,0,0,0,0,0,0,0,0,0,0,0,0,0,0,0,0,BP83,0,0,0,0,0,0,0,0,0,0,~
0)';
      PINUSE='POWER';
      NO_LOAD_CHECK='Both';
      NO_IO_CHECK='Both';
      NO_ASSERT_CHECK='TRUE';
      NO_DIR_CHECK='TRUE';
      ALLOW_CONNECT='TRUE';
    'VCCIN'<114>:
      PIN_NUMBER='(0,0,0,0,0,0,0,0,0,0,0,0,0,0,0,0,0,0,BR60,0,0,0,0,0,0,0,0,0,0,~
0)';
      PINUSE='POWER';
      NO_LOAD_CHECK='Both';
      NO_IO_CHECK='Both';
      NO_ASSERT_CHECK='TRUE';
      NO_DIR_CHECK='TRUE';
      ALLOW_CONNECT='TRUE';
    'VCCIN'<113>:
      PIN_NUMBER='(0,0,0,0,0,0,0,0,0,0,0,0,0,0,0,0,0,0,BR62,0,0,0,0,0,0,0,0,0,0,~
0)';
      PINUSE='POWER';
      NO_LOAD_CHECK='Both';
      NO_IO_CHECK='Both';
      NO_ASSERT_CHECK='TRUE';
      NO_DIR_CHECK='TRUE';
      ALLOW_CONNECT='TRUE';
    'VCCIN'<112>:
      PIN_NUMBER='(0,0,0,0,0,0,0,0,0,0,0,0,0,0,0,0,0,0,BR84,0,0,0,0,0,0,0,0,0,0,~
0)';
      PINUSE='POWER';
      NO_LOAD_CHECK='Both';
      NO_IO_CHECK='Both';
      NO_ASSERT_CHECK='TRUE';
      NO_DIR_CHECK='TRUE';
      ALLOW_CONNECT='TRUE';
    'VCCIN'<111>:
      PIN_NUMBER='(0,0,0,0,0,0,0,0,0,0,0,0,0,0,0,0,0,0,BT61,0,0,0,0,0,0,0,0,0,0,~
0)';
      PINUSE='POWER';
      NO_LOAD_CHECK='Both';
      NO_IO_CHECK='Both';
      NO_ASSERT_CHECK='TRUE';
      NO_DIR_CHECK='TRUE';
      ALLOW_CONNECT='TRUE';
    'VCCIN'<110>:
      PIN_NUMBER='(0,0,0,0,0,0,0,0,0,0,0,0,0,0,0,0,0,0,BT63,0,0,0,0,0,0,0,0,0,0,~
0)';
      PINUSE='POWER';
      NO_LOAD_CHECK='Both';
      NO_IO_CHECK='Both';
      NO_ASSERT_CHECK='TRUE';
      NO_DIR_CHECK='TRUE';
      ALLOW_CONNECT='TRUE';
    'VCCIN'<109>:
      PIN_NUMBER='(0,0,0,0,0,0,0,0,0,0,0,0,0,0,0,0,0,0,BT65,0,0,0,0,0,0,0,0,0,0,~
0)';
      PINUSE='POWER';
      NO_LOAD_CHECK='Both';
      NO_IO_CHECK='Both';
      NO_ASSERT_CHECK='TRUE';
      NO_DIR_CHECK='TRUE';
      ALLOW_CONNECT='TRUE';
    'VCCIN'<108>:
      PIN_NUMBER='(0,0,0,0,0,0,0,0,0,0,0,0,0,0,0,0,0,0,BT67,0,0,0,0,0,0,0,0,0,0,~
0)';
      PINUSE='POWER';
      NO_LOAD_CHECK='Both';
      NO_IO_CHECK='Both';
      NO_ASSERT_CHECK='TRUE';
      NO_DIR_CHECK='TRUE';
      ALLOW_CONNECT='TRUE';
    'VCCIN'<107>:
      PIN_NUMBER='(0,0,0,0,0,0,0,0,0,0,0,0,0,0,0,0,0,0,BT69,0,0,0,0,0,0,0,0,0,0,~
0)';
      PINUSE='POWER';
      NO_LOAD_CHECK='Both';
      NO_IO_CHECK='Both';
      NO_ASSERT_CHECK='TRUE';
      NO_DIR_CHECK='TRUE';
      ALLOW_CONNECT='TRUE';
    'VCCIN'<106>:
      PIN_NUMBER='(0,0,0,0,0,0,0,0,0,0,0,0,0,0,0,0,0,0,BT71,0,0,0,0,0,0,0,0,0,0,~
0)';
      PINUSE='POWER';
      NO_LOAD_CHECK='Both';
      NO_IO_CHECK='Both';
      NO_ASSERT_CHECK='TRUE';
      NO_DIR_CHECK='TRUE';
      ALLOW_CONNECT='TRUE';
    'VCCIN'<105>:
      PIN_NUMBER='(0,0,0,0,0,0,0,0,0,0,0,0,0,0,0,0,0,0,BT73,0,0,0,0,0,0,0,0,0,0,~
0)';
      PINUSE='POWER';
      NO_LOAD_CHECK='Both';
      NO_IO_CHECK='Both';
      NO_ASSERT_CHECK='TRUE';
      NO_DIR_CHECK='TRUE';
      ALLOW_CONNECT='TRUE';
    'VCCIN'<104>:
      PIN_NUMBER='(0,0,0,0,0,0,0,0,0,0,0,0,0,0,0,0,0,0,BT75,0,0,0,0,0,0,0,0,0,0,~
0)';
      PINUSE='POWER';
      NO_LOAD_CHECK='Both';
      NO_IO_CHECK='Both';
      NO_ASSERT_CHECK='TRUE';
      NO_DIR_CHECK='TRUE';
      ALLOW_CONNECT='TRUE';
    'VCCIN'<103>:
      PIN_NUMBER='(0,0,0,0,0,0,0,0,0,0,0,0,0,0,0,0,0,0,BT77,0,0,0,0,0,0,0,0,0,0,~
0)';
      PINUSE='POWER';
      NO_LOAD_CHECK='Both';
      NO_IO_CHECK='Both';
      NO_ASSERT_CHECK='TRUE';
      NO_DIR_CHECK='TRUE';
      ALLOW_CONNECT='TRUE';
    'VCCIN'<102>:
      PIN_NUMBER='(0,0,0,0,0,0,0,0,0,0,0,0,0,0,0,0,0,0,BT79,0,0,0,0,0,0,0,0,0,0,~
0)';
      PINUSE='POWER';
      NO_LOAD_CHECK='Both';
      NO_IO_CHECK='Both';
      NO_ASSERT_CHECK='TRUE';
      NO_DIR_CHECK='TRUE';
      ALLOW_CONNECT='TRUE';
    'VCCIN'<101>:
      PIN_NUMBER='(0,0,0,0,0,0,0,0,0,0,0,0,0,0,0,0,0,0,BT81,0,0,0,0,0,0,0,0,0,0,~
0)';
      PINUSE='POWER';
      NO_LOAD_CHECK='Both';
      NO_IO_CHECK='Both';
      NO_ASSERT_CHECK='TRUE';
      NO_DIR_CHECK='TRUE';
      ALLOW_CONNECT='TRUE';
    'VCCIN'<100>:
      PIN_NUMBER='(0,0,0,0,0,0,0,0,0,0,0,0,0,0,0,0,0,0,BT83,0,0,0,0,0,0,0,0,0,0,~
0)';
      PINUSE='POWER';
      NO_LOAD_CHECK='Both';
      NO_IO_CHECK='Both';
      NO_ASSERT_CHECK='TRUE';
      NO_DIR_CHECK='TRUE';
      ALLOW_CONNECT='TRUE';
    'VCCIN'<99>:
      PIN_NUMBER='(0,0,0,0,0,0,0,0,0,0,0,0,0,0,0,0,0,0,BU60,0,0,0,0,0,0,0,0,0,0,~
0)';
      PINUSE='POWER';
      NO_LOAD_CHECK='Both';
      NO_IO_CHECK='Both';
      NO_ASSERT_CHECK='TRUE';
      NO_DIR_CHECK='TRUE';
      ALLOW_CONNECT='TRUE';
    'VCCIN'<98>:
      PIN_NUMBER='(0,0,0,0,0,0,0,0,0,0,0,0,0,0,0,0,0,0,BU62,0,0,0,0,0,0,0,0,0,0,~
0)';
      PINUSE='POWER';
      NO_LOAD_CHECK='Both';
      NO_IO_CHECK='Both';
      NO_ASSERT_CHECK='TRUE';
      NO_DIR_CHECK='TRUE';
      ALLOW_CONNECT='TRUE';
    'VCCIN'<97>:
      PIN_NUMBER='(0,0,0,0,0,0,0,0,0,0,0,0,0,0,0,0,0,0,BU64,0,0,0,0,0,0,0,0,0,0,~
0)';
      PINUSE='POWER';
      NO_LOAD_CHECK='Both';
      NO_IO_CHECK='Both';
      NO_ASSERT_CHECK='TRUE';
      NO_DIR_CHECK='TRUE';
      ALLOW_CONNECT='TRUE';
    'VCCIN'<96>:
      PIN_NUMBER='(0,0,0,0,0,0,0,0,0,0,0,0,0,0,0,0,0,0,BU66,0,0,0,0,0,0,0,0,0,0,~
0)';
      PINUSE='POWER';
      NO_LOAD_CHECK='Both';
      NO_IO_CHECK='Both';
      NO_ASSERT_CHECK='TRUE';
      NO_DIR_CHECK='TRUE';
      ALLOW_CONNECT='TRUE';
    'VCCIN'<95>:
      PIN_NUMBER='(0,0,0,0,0,0,0,0,0,0,0,0,0,0,0,0,0,0,BU68,0,0,0,0,0,0,0,0,0,0,~
0)';
      PINUSE='POWER';
      NO_LOAD_CHECK='Both';
      NO_IO_CHECK='Both';
      NO_ASSERT_CHECK='TRUE';
      NO_DIR_CHECK='TRUE';
      ALLOW_CONNECT='TRUE';
    'VCCIN'<94>:
      PIN_NUMBER='(0,0,0,0,0,0,0,0,0,0,0,0,0,0,0,0,0,0,BU70,0,0,0,0,0,0,0,0,0,0,~
0)';
      PINUSE='POWER';
      NO_LOAD_CHECK='Both';
      NO_IO_CHECK='Both';
      NO_ASSERT_CHECK='TRUE';
      NO_DIR_CHECK='TRUE';
      ALLOW_CONNECT='TRUE';
    'VCCIN'<93>:
      PIN_NUMBER='(0,0,0,0,0,0,0,0,0,0,0,0,0,0,0,0,0,0,BU72,0,0,0,0,0,0,0,0,0,0,~
0)';
      PINUSE='POWER';
      NO_LOAD_CHECK='Both';
      NO_IO_CHECK='Both';
      NO_ASSERT_CHECK='TRUE';
      NO_DIR_CHECK='TRUE';
      ALLOW_CONNECT='TRUE';
    'VCCIN'<92>:
      PIN_NUMBER='(0,0,0,0,0,0,0,0,0,0,0,0,0,0,0,0,0,0,BU74,0,0,0,0,0,0,0,0,0,0,~
0)';
      PINUSE='POWER';
      NO_LOAD_CHECK='Both';
      NO_IO_CHECK='Both';
      NO_ASSERT_CHECK='TRUE';
      NO_DIR_CHECK='TRUE';
      ALLOW_CONNECT='TRUE';
    'VCCIN'<91>:
      PIN_NUMBER='(0,0,0,0,0,0,0,0,0,0,0,0,0,0,0,0,0,0,BU76,0,0,0,0,0,0,0,0,0,0,~
0)';
      PINUSE='POWER';
      NO_LOAD_CHECK='Both';
      NO_IO_CHECK='Both';
      NO_ASSERT_CHECK='TRUE';
      NO_DIR_CHECK='TRUE';
      ALLOW_CONNECT='TRUE';
    'VCCIN'<90>:
      PIN_NUMBER='(0,0,0,0,0,0,0,0,0,0,0,0,0,0,0,0,0,0,BU78,0,0,0,0,0,0,0,0,0,0,~
0)';
      PINUSE='POWER';
      NO_LOAD_CHECK='Both';
      NO_IO_CHECK='Both';
      NO_ASSERT_CHECK='TRUE';
      NO_DIR_CHECK='TRUE';
      ALLOW_CONNECT='TRUE';
    'VCCIN'<89>:
      PIN_NUMBER='(0,0,0,0,0,0,0,0,0,0,0,0,0,0,0,0,0,0,BU80,0,0,0,0,0,0,0,0,0,0,~
0)';
      PINUSE='POWER';
      NO_LOAD_CHECK='Both';
      NO_IO_CHECK='Both';
      NO_ASSERT_CHECK='TRUE';
      NO_DIR_CHECK='TRUE';
      ALLOW_CONNECT='TRUE';
    'VCCIN'<88>:
      PIN_NUMBER='(0,0,0,0,0,0,0,0,0,0,0,0,0,0,0,0,0,0,BU82,0,0,0,0,0,0,0,0,0,0,~
0)';
      PINUSE='POWER';
      NO_LOAD_CHECK='Both';
      NO_IO_CHECK='Both';
      NO_ASSERT_CHECK='TRUE';
      NO_DIR_CHECK='TRUE';
      ALLOW_CONNECT='TRUE';
    'VCCIN'<87>:
      PIN_NUMBER='(0,0,0,0,0,0,0,0,0,0,0,0,0,0,0,0,0,0,BU84,0,0,0,0,0,0,0,0,0,0,~
0)';
      PINUSE='POWER';
      NO_LOAD_CHECK='Both';
      NO_IO_CHECK='Both';
      NO_ASSERT_CHECK='TRUE';
      NO_DIR_CHECK='TRUE';
      ALLOW_CONNECT='TRUE';
    'VCCIN'<86>:
      PIN_NUMBER='(0,0,0,0,0,0,0,0,0,0,0,0,0,0,0,0,0,0,BV61,0,0,0,0,0,0,0,0,0,0,~
0)';
      PINUSE='POWER';
      NO_LOAD_CHECK='Both';
      NO_IO_CHECK='Both';
      NO_ASSERT_CHECK='TRUE';
      NO_DIR_CHECK='TRUE';
      ALLOW_CONNECT='TRUE';
    'VCCIN'<85>:
      PIN_NUMBER='(0,0,0,0,0,0,0,0,0,0,0,0,0,0,0,0,0,0,BV63,0,0,0,0,0,0,0,0,0,0,~
0)';
      PINUSE='POWER';
      NO_LOAD_CHECK='Both';
      NO_IO_CHECK='Both';
      NO_ASSERT_CHECK='TRUE';
      NO_DIR_CHECK='TRUE';
      ALLOW_CONNECT='TRUE';
    'VCCIN'<84>:
      PIN_NUMBER='(0,0,0,0,0,0,0,0,0,0,0,0,0,0,0,0,0,0,BV65,0,0,0,0,0,0,0,0,0,0,~
0)';
      PINUSE='POWER';
      NO_LOAD_CHECK='Both';
      NO_IO_CHECK='Both';
      NO_ASSERT_CHECK='TRUE';
      NO_DIR_CHECK='TRUE';
      ALLOW_CONNECT='TRUE';
    'VCCIN'<83>:
      PIN_NUMBER='(0,0,0,0,0,0,0,0,0,0,0,0,0,0,0,0,0,0,BV67,0,0,0,0,0,0,0,0,0,0,~
0)';
      PINUSE='POWER';
      NO_LOAD_CHECK='Both';
      NO_IO_CHECK='Both';
      NO_ASSERT_CHECK='TRUE';
      NO_DIR_CHECK='TRUE';
      ALLOW_CONNECT='TRUE';
    'VCCIN'<82>:
      PIN_NUMBER='(0,0,0,0,0,0,0,0,0,0,0,0,0,0,0,0,0,0,BV69,0,0,0,0,0,0,0,0,0,0,~
0)';
      PINUSE='POWER';
      NO_LOAD_CHECK='Both';
      NO_IO_CHECK='Both';
      NO_ASSERT_CHECK='TRUE';
      NO_DIR_CHECK='TRUE';
      ALLOW_CONNECT='TRUE';
    'VCCIN'<81>:
      PIN_NUMBER='(0,0,0,0,0,0,0,0,0,0,0,0,0,0,0,0,0,0,BV71,0,0,0,0,0,0,0,0,0,0,~
0)';
      PINUSE='POWER';
      NO_LOAD_CHECK='Both';
      NO_IO_CHECK='Both';
      NO_ASSERT_CHECK='TRUE';
      NO_DIR_CHECK='TRUE';
      ALLOW_CONNECT='TRUE';
    'VCCIN'<80>:
      PIN_NUMBER='(0,0,0,0,0,0,0,0,0,0,0,0,0,0,0,0,0,0,BV73,0,0,0,0,0,0,0,0,0,0,~
0)';
      PINUSE='POWER';
      NO_LOAD_CHECK='Both';
      NO_IO_CHECK='Both';
      NO_ASSERT_CHECK='TRUE';
      NO_DIR_CHECK='TRUE';
      ALLOW_CONNECT='TRUE';
    'VCCIN'<79>:
      PIN_NUMBER='(0,0,0,0,0,0,0,0,0,0,0,0,0,0,0,0,0,0,BV75,0,0,0,0,0,0,0,0,0,0,~
0)';
      PINUSE='POWER';
      NO_LOAD_CHECK='Both';
      NO_IO_CHECK='Both';
      NO_ASSERT_CHECK='TRUE';
      NO_DIR_CHECK='TRUE';
      ALLOW_CONNECT='TRUE';
    'VCCIN'<78>:
      PIN_NUMBER='(0,0,0,0,0,0,0,0,0,0,0,0,0,0,0,0,0,0,BV77,0,0,0,0,0,0,0,0,0,0,~
0)';
      PINUSE='POWER';
      NO_LOAD_CHECK='Both';
      NO_IO_CHECK='Both';
      NO_ASSERT_CHECK='TRUE';
      NO_DIR_CHECK='TRUE';
      ALLOW_CONNECT='TRUE';
    'VCCIN'<77>:
      PIN_NUMBER='(0,0,0,0,0,0,0,0,0,0,0,0,0,0,0,0,0,0,BV79,0,0,0,0,0,0,0,0,0,0,~
0)';
      PINUSE='POWER';
      NO_LOAD_CHECK='Both';
      NO_IO_CHECK='Both';
      NO_ASSERT_CHECK='TRUE';
      NO_DIR_CHECK='TRUE';
      ALLOW_CONNECT='TRUE';
    'VCCIN'<76>:
      PIN_NUMBER='(0,0,0,0,0,0,0,0,0,0,0,0,0,0,0,0,0,0,BV81,0,0,0,0,0,0,0,0,0,0,~
0)';
      PINUSE='POWER';
      NO_LOAD_CHECK='Both';
      NO_IO_CHECK='Both';
      NO_ASSERT_CHECK='TRUE';
      NO_DIR_CHECK='TRUE';
      ALLOW_CONNECT='TRUE';
    'VCCIN'<75>:
      PIN_NUMBER='(0,0,0,0,0,0,0,0,0,0,0,0,0,0,0,0,0,0,BV83,0,0,0,0,0,0,0,0,0,0,~
0)';
      PINUSE='POWER';
      NO_LOAD_CHECK='Both';
      NO_IO_CHECK='Both';
      NO_ASSERT_CHECK='TRUE';
      NO_DIR_CHECK='TRUE';
      ALLOW_CONNECT='TRUE';
    'VCCIN'<74>:
      PIN_NUMBER='(0,0,0,0,0,0,0,0,0,0,0,0,0,0,0,0,0,0,BW60,0,0,0,0,0,0,0,0,0,0,~
0)';
      PINUSE='POWER';
      NO_LOAD_CHECK='Both';
      NO_IO_CHECK='Both';
      NO_ASSERT_CHECK='TRUE';
      NO_DIR_CHECK='TRUE';
      ALLOW_CONNECT='TRUE';
    'VCCIN'<73>:
      PIN_NUMBER='(0,0,0,0,0,0,0,0,0,0,0,0,0,0,0,0,0,0,BW62,0,0,0,0,0,0,0,0,0,0,~
0)';
      PINUSE='POWER';
      NO_LOAD_CHECK='Both';
      NO_IO_CHECK='Both';
      NO_ASSERT_CHECK='TRUE';
      NO_DIR_CHECK='TRUE';
      ALLOW_CONNECT='TRUE';
    'VCCIN'<72>:
      PIN_NUMBER='(0,0,0,0,0,0,0,0,0,0,0,0,0,0,0,0,0,0,BW64,0,0,0,0,0,0,0,0,0,0,~
0)';
      PINUSE='POWER';
      NO_LOAD_CHECK='Both';
      NO_IO_CHECK='Both';
      NO_ASSERT_CHECK='TRUE';
      NO_DIR_CHECK='TRUE';
      ALLOW_CONNECT='TRUE';
    'VCCIN'<71>:
      PIN_NUMBER='(0,0,0,0,0,0,0,0,0,0,0,0,0,0,0,0,0,0,BW66,0,0,0,0,0,0,0,0,0,0,~
0)';
      PINUSE='POWER';
      NO_LOAD_CHECK='Both';
      NO_IO_CHECK='Both';
      NO_ASSERT_CHECK='TRUE';
      NO_DIR_CHECK='TRUE';
      ALLOW_CONNECT='TRUE';
    'VCCIN'<70>:
      PIN_NUMBER='(0,0,0,0,0,0,0,0,0,0,0,0,0,0,0,0,0,0,BW68,0,0,0,0,0,0,0,0,0,0,~
0)';
      PINUSE='POWER';
      NO_LOAD_CHECK='Both';
      NO_IO_CHECK='Both';
      NO_ASSERT_CHECK='TRUE';
      NO_DIR_CHECK='TRUE';
      ALLOW_CONNECT='TRUE';
    'VCCIN'<69>:
      PIN_NUMBER='(0,0,0,0,0,0,0,0,0,0,0,0,0,0,0,0,0,0,BW70,0,0,0,0,0,0,0,0,0,0,~
0)';
      PINUSE='POWER';
      NO_LOAD_CHECK='Both';
      NO_IO_CHECK='Both';
      NO_ASSERT_CHECK='TRUE';
      NO_DIR_CHECK='TRUE';
      ALLOW_CONNECT='TRUE';
    'VCCIN'<68>:
      PIN_NUMBER='(0,0,0,0,0,0,0,0,0,0,0,0,0,0,0,0,0,0,BW84,0,0,0,0,0,0,0,0,0,0,~
0)';
      PINUSE='POWER';
      NO_LOAD_CHECK='Both';
      NO_IO_CHECK='Both';
      NO_ASSERT_CHECK='TRUE';
      NO_DIR_CHECK='TRUE';
      ALLOW_CONNECT='TRUE';
    'VCCIN'<67>:
      PIN_NUMBER='(0,0,0,0,0,0,0,0,0,0,0,0,0,0,0,0,0,0,BY61,0,0,0,0,0,0,0,0,0,0,~
0)';
      PINUSE='POWER';
      NO_LOAD_CHECK='Both';
      NO_IO_CHECK='Both';
      NO_ASSERT_CHECK='TRUE';
      NO_DIR_CHECK='TRUE';
      ALLOW_CONNECT='TRUE';
    'VCCIN'<66>:
      PIN_NUMBER='(0,0,0,0,0,0,0,0,0,0,0,0,0,0,0,0,0,0,BY73,0,0,0,0,0,0,0,0,0,0,~
0)';
      PINUSE='POWER';
      NO_LOAD_CHECK='Both';
      NO_IO_CHECK='Both';
      NO_ASSERT_CHECK='TRUE';
      NO_DIR_CHECK='TRUE';
      ALLOW_CONNECT='TRUE';
    'VCCIN'<65>:
      PIN_NUMBER='(0,0,0,0,0,0,0,0,0,0,0,0,0,0,0,0,0,0,BY75,0,0,0,0,0,0,0,0,0,0,~
0)';
      PINUSE='POWER';
      NO_LOAD_CHECK='Both';
      NO_IO_CHECK='Both';
      NO_ASSERT_CHECK='TRUE';
      NO_DIR_CHECK='TRUE';
      ALLOW_CONNECT='TRUE';
    'VCCIN'<64>:
      PIN_NUMBER='(0,0,0,0,0,0,0,0,0,0,0,0,0,0,0,0,0,0,BY77,0,0,0,0,0,0,0,0,0,0,~
0)';
      PINUSE='POWER';
      NO_LOAD_CHECK='Both';
      NO_IO_CHECK='Both';
      NO_ASSERT_CHECK='TRUE';
      NO_DIR_CHECK='TRUE';
      ALLOW_CONNECT='TRUE';
    'VCCIN'<63>:
      PIN_NUMBER='(0,0,0,0,0,0,0,0,0,0,0,0,0,0,0,0,0,0,BY79,0,0,0,0,0,0,0,0,0,0,~
0)';
      PINUSE='POWER';
      NO_LOAD_CHECK='Both';
      NO_IO_CHECK='Both';
      NO_ASSERT_CHECK='TRUE';
      NO_DIR_CHECK='TRUE';
      ALLOW_CONNECT='TRUE';
    'VCCIN'<62>:
      PIN_NUMBER='(0,0,0,0,0,0,0,0,0,0,0,0,0,0,0,0,0,0,BY81,0,0,0,0,0,0,0,0,0,0,~
0)';
      PINUSE='POWER';
      NO_LOAD_CHECK='Both';
      NO_IO_CHECK='Both';
      NO_ASSERT_CHECK='TRUE';
      NO_DIR_CHECK='TRUE';
      ALLOW_CONNECT='TRUE';
    'VCCIN'<61>:
      PIN_NUMBER='(0,0,0,0,0,0,0,0,0,0,0,0,0,0,0,0,0,0,BY83,0,0,0,0,0,0,0,0,0,0,~
0)';
      PINUSE='POWER';
      NO_LOAD_CHECK='Both';
      NO_IO_CHECK='Both';
      NO_ASSERT_CHECK='TRUE';
      NO_DIR_CHECK='TRUE';
      ALLOW_CONNECT='TRUE';
    'VCCIN'<60>:
      PIN_NUMBER='(0,0,0,0,0,0,0,0,0,0,0,0,0,0,0,0,0,0,CA60,0,0,0,0,0,0,0,0,0,0,~
0)';
      PINUSE='POWER';
      NO_LOAD_CHECK='Both';
      NO_IO_CHECK='Both';
      NO_ASSERT_CHECK='TRUE';
      NO_DIR_CHECK='TRUE';
      ALLOW_CONNECT='TRUE';
    'VCCIN'<59>:
      PIN_NUMBER='(0,0,0,0,0,0,0,0,0,0,0,0,0,0,0,0,0,0,CA62,0,0,0,0,0,0,0,0,0,0,~
0)';
      PINUSE='POWER';
      NO_LOAD_CHECK='Both';
      NO_IO_CHECK='Both';
      NO_ASSERT_CHECK='TRUE';
      NO_DIR_CHECK='TRUE';
      ALLOW_CONNECT='TRUE';
    'VCCIN'<58>:
      PIN_NUMBER='(0,0,0,0,0,0,0,0,0,0,0,0,0,0,0,0,0,0,CA72,0,0,0,0,0,0,0,0,0,0,~
0)';
      PINUSE='POWER';
      NO_LOAD_CHECK='Both';
      NO_IO_CHECK='Both';
      NO_ASSERT_CHECK='TRUE';
      NO_DIR_CHECK='TRUE';
      ALLOW_CONNECT='TRUE';
    'VCCIN'<57>:
      PIN_NUMBER='(0,0,0,0,0,0,0,0,0,0,0,0,0,0,0,0,0,0,CA74,0,0,0,0,0,0,0,0,0,0,~
0)';
      PINUSE='POWER';
      NO_LOAD_CHECK='Both';
      NO_IO_CHECK='Both';
      NO_ASSERT_CHECK='TRUE';
      NO_DIR_CHECK='TRUE';
      ALLOW_CONNECT='TRUE';
    'VCCIN'<56>:
      PIN_NUMBER='(0,0,0,0,0,0,0,0,0,0,0,0,0,0,0,0,0,0,CA76,0,0,0,0,0,0,0,0,0,0,~
0)';
      PINUSE='POWER';
      NO_LOAD_CHECK='Both';
      NO_IO_CHECK='Both';
      NO_ASSERT_CHECK='TRUE';
      NO_DIR_CHECK='TRUE';
      ALLOW_CONNECT='TRUE';
    'VCCIN'<55>:
      PIN_NUMBER='(0,0,0,0,0,0,0,0,0,0,0,0,0,0,0,0,0,0,CA78,0,0,0,0,0,0,0,0,0,0,~
0)';
      PINUSE='POWER';
      NO_LOAD_CHECK='Both';
      NO_IO_CHECK='Both';
      NO_ASSERT_CHECK='TRUE';
      NO_DIR_CHECK='TRUE';
      ALLOW_CONNECT='TRUE';
    'VCCIN'<54>:
      PIN_NUMBER='(0,0,0,0,0,0,0,0,0,0,0,0,0,0,0,0,0,0,CA80,0,0,0,0,0,0,0,0,0,0,~
0)';
      PINUSE='POWER';
      NO_LOAD_CHECK='Both';
      NO_IO_CHECK='Both';
      NO_ASSERT_CHECK='TRUE';
      NO_DIR_CHECK='TRUE';
      ALLOW_CONNECT='TRUE';
    'VCCIN'<53>:
      PIN_NUMBER='(0,0,0,0,0,0,0,0,0,0,0,0,0,0,0,0,0,0,CA82,0,0,0,0,0,0,0,0,0,0,~
0)';
      PINUSE='POWER';
      NO_LOAD_CHECK='Both';
      NO_IO_CHECK='Both';
      NO_ASSERT_CHECK='TRUE';
      NO_DIR_CHECK='TRUE';
      ALLOW_CONNECT='TRUE';
    'VCCIN'<52>:
      PIN_NUMBER='(0,0,0,0,0,0,0,0,0,0,0,0,0,0,0,0,0,0,CA84,0,0,0,0,0,0,0,0,0,0,~
0)';
      PINUSE='POWER';
      NO_LOAD_CHECK='Both';
      NO_IO_CHECK='Both';
      NO_ASSERT_CHECK='TRUE';
      NO_DIR_CHECK='TRUE';
      ALLOW_CONNECT='TRUE';
    'VCCIN'<51>:
      PIN_NUMBER='(0,0,0,0,0,0,0,0,0,0,0,0,0,0,0,0,0,0,CB61,0,0,0,0,0,0,0,0,0,0,~
0)';
      PINUSE='POWER';
      NO_LOAD_CHECK='Both';
      NO_IO_CHECK='Both';
      NO_ASSERT_CHECK='TRUE';
      NO_DIR_CHECK='TRUE';
      ALLOW_CONNECT='TRUE';
    'VCCIN'<50>:
      PIN_NUMBER='(0,0,0,0,0,0,0,0,0,0,0,0,0,0,0,0,0,0,CB73,0,0,0,0,0,0,0,0,0,0,~
0)';
      PINUSE='POWER';
      NO_LOAD_CHECK='Both';
      NO_IO_CHECK='Both';
      NO_ASSERT_CHECK='TRUE';
      NO_DIR_CHECK='TRUE';
      ALLOW_CONNECT='TRUE';
    'VCCIN'<49>:
      PIN_NUMBER='(0,0,0,0,0,0,0,0,0,0,0,0,0,0,0,0,0,0,CB75,0,0,0,0,0,0,0,0,0,0,~
0)';
      PINUSE='POWER';
      NO_LOAD_CHECK='Both';
      NO_IO_CHECK='Both';
      NO_ASSERT_CHECK='TRUE';
      NO_DIR_CHECK='TRUE';
      ALLOW_CONNECT='TRUE';
    'VCCIN'<48>:
      PIN_NUMBER='(0,0,0,0,0,0,0,0,0,0,0,0,0,0,0,0,0,0,CB77,0,0,0,0,0,0,0,0,0,0,~
0)';
      PINUSE='POWER';
      NO_LOAD_CHECK='Both';
      NO_IO_CHECK='Both';
      NO_ASSERT_CHECK='TRUE';
      NO_DIR_CHECK='TRUE';
      ALLOW_CONNECT='TRUE';
    'VCCIN'<47>:
      PIN_NUMBER='(0,0,0,0,0,0,0,0,0,0,0,0,0,0,0,0,0,0,CB79,0,0,0,0,0,0,0,0,0,0,~
0)';
      PINUSE='POWER';
      NO_LOAD_CHECK='Both';
      NO_IO_CHECK='Both';
      NO_ASSERT_CHECK='TRUE';
      NO_DIR_CHECK='TRUE';
      ALLOW_CONNECT='TRUE';
    'VCCIN'<46>:
      PIN_NUMBER='(0,0,0,0,0,0,0,0,0,0,0,0,0,0,0,0,0,0,CB81,0,0,0,0,0,0,0,0,0,0,~
0)';
      PINUSE='POWER';
      NO_LOAD_CHECK='Both';
      NO_IO_CHECK='Both';
      NO_ASSERT_CHECK='TRUE';
      NO_DIR_CHECK='TRUE';
      ALLOW_CONNECT='TRUE';
    'VCCIN'<45>:
      PIN_NUMBER='(0,0,0,0,0,0,0,0,0,0,0,0,0,0,0,0,0,0,CB83,0,0,0,0,0,0,0,0,0,0,~
0)';
      PINUSE='POWER';
      NO_LOAD_CHECK='Both';
      NO_IO_CHECK='Both';
      NO_ASSERT_CHECK='TRUE';
      NO_DIR_CHECK='TRUE';
      ALLOW_CONNECT='TRUE';
    'VCCIN'<44>:
      PIN_NUMBER='(0,0,0,0,0,0,0,0,0,0,0,0,0,0,0,0,0,0,CC60,0,0,0,0,0,0,0,0,0,0,~
0)';
      PINUSE='POWER';
      NO_LOAD_CHECK='Both';
      NO_IO_CHECK='Both';
      NO_ASSERT_CHECK='TRUE';
      NO_DIR_CHECK='TRUE';
      ALLOW_CONNECT='TRUE';
    'VCCIN'<43>:
      PIN_NUMBER='(0,0,0,0,0,0,0,0,0,0,0,0,0,0,0,0,0,0,CC62,0,0,0,0,0,0,0,0,0,0,~
0)';
      PINUSE='POWER';
      NO_LOAD_CHECK='Both';
      NO_IO_CHECK='Both';
      NO_ASSERT_CHECK='TRUE';
      NO_DIR_CHECK='TRUE';
      ALLOW_CONNECT='TRUE';
    'VCCIN'<42>:
      PIN_NUMBER='(0,0,0,0,0,0,0,0,0,0,0,0,0,0,0,0,0,0,CC84,0,0,0,0,0,0,0,0,0,0,~
0)';
      PINUSE='POWER';
      NO_LOAD_CHECK='Both';
      NO_IO_CHECK='Both';
      NO_ASSERT_CHECK='TRUE';
      NO_DIR_CHECK='TRUE';
      ALLOW_CONNECT='TRUE';
    'VCCIN'<41>:
      PIN_NUMBER='(0,0,0,0,0,0,0,0,0,0,0,0,0,0,0,0,0,0,CD61,0,0,0,0,0,0,0,0,0,0,~
0)';
      PINUSE='POWER';
      NO_LOAD_CHECK='Both';
      NO_IO_CHECK='Both';
      NO_ASSERT_CHECK='TRUE';
      NO_DIR_CHECK='TRUE';
      ALLOW_CONNECT='TRUE';
    'VCCIN'<40>:
      PIN_NUMBER='(0,0,0,0,0,0,0,0,0,0,0,0,0,0,0,0,0,0,CD83,0,0,0,0,0,0,0,0,0,0,~
0)';
      PINUSE='POWER';
      NO_LOAD_CHECK='Both';
      NO_IO_CHECK='Both';
      NO_ASSERT_CHECK='TRUE';
      NO_DIR_CHECK='TRUE';
      ALLOW_CONNECT='TRUE';
    'VCCIN'<39>:
      PIN_NUMBER='(0,0,0,0,0,0,0,0,0,0,0,0,0,0,0,0,0,0,CD85,0,0,0,0,0,0,0,0,0,0,~
0)';
      PINUSE='POWER';
      NO_LOAD_CHECK='Both';
      NO_IO_CHECK='Both';
      NO_ASSERT_CHECK='TRUE';
      NO_DIR_CHECK='TRUE';
      ALLOW_CONNECT='TRUE';
    'VCCIN'<38>:
      PIN_NUMBER='(0,0,0,0,0,0,0,0,0,0,0,0,0,0,0,0,0,0,CE60,0,0,0,0,0,0,0,0,0,0,~
0)';
      PINUSE='POWER';
      NO_LOAD_CHECK='Both';
      NO_IO_CHECK='Both';
      NO_ASSERT_CHECK='TRUE';
      NO_DIR_CHECK='TRUE';
      ALLOW_CONNECT='TRUE';
    'VCCIN'<37>:
      PIN_NUMBER='(0,0,0,0,0,0,0,0,0,0,0,0,0,0,0,0,0,0,CE84,0,0,0,0,0,0,0,0,0,0,~
0)';
      PINUSE='POWER';
      NO_LOAD_CHECK='Both';
      NO_IO_CHECK='Both';
      NO_ASSERT_CHECK='TRUE';
      NO_DIR_CHECK='TRUE';
      ALLOW_CONNECT='TRUE';
    'VCCIN'<36>:
      PIN_NUMBER='(0,0,0,0,0,0,0,0,0,0,0,0,0,0,0,0,0,0,CF61,0,0,0,0,0,0,0,0,0,0,~
0)';
      PINUSE='POWER';
      NO_LOAD_CHECK='Both';
      NO_IO_CHECK='Both';
      NO_ASSERT_CHECK='TRUE';
      NO_DIR_CHECK='TRUE';
      ALLOW_CONNECT='TRUE';
    'VCCIN'<35>:
      PIN_NUMBER='(0,0,0,0,0,0,0,0,0,0,0,0,0,0,0,0,0,0,CF85,0,0,0,0,0,0,0,0,0,0,~
0)';
      PINUSE='POWER';
      NO_LOAD_CHECK='Both';
      NO_IO_CHECK='Both';
      NO_ASSERT_CHECK='TRUE';
      NO_DIR_CHECK='TRUE';
      ALLOW_CONNECT='TRUE';
    'VCCIN'<34>:
      PIN_NUMBER='(0,0,0,0,0,0,0,0,0,0,0,0,0,0,0,0,0,0,CG60,0,0,0,0,0,0,0,0,0,0,~
0)';
      PINUSE='POWER';
      NO_LOAD_CHECK='Both';
      NO_IO_CHECK='Both';
      NO_ASSERT_CHECK='TRUE';
      NO_DIR_CHECK='TRUE';
      ALLOW_CONNECT='TRUE';
    'VCCIN'<33>:
      PIN_NUMBER='(0,0,0,0,0,0,0,0,0,0,0,0,0,0,0,0,0,0,CG84,0,0,0,0,0,0,0,0,0,0,~
0)';
      PINUSE='POWER';
      NO_LOAD_CHECK='Both';
      NO_IO_CHECK='Both';
      NO_ASSERT_CHECK='TRUE';
      NO_DIR_CHECK='TRUE';
      ALLOW_CONNECT='TRUE';
    'VCCIN'<32>:
      PIN_NUMBER='(0,0,0,0,0,0,0,0,0,0,0,0,0,0,0,0,0,0,CH61,0,0,0,0,0,0,0,0,0,0,~
0)';
      PINUSE='POWER';
      NO_LOAD_CHECK='Both';
      NO_IO_CHECK='Both';
      NO_ASSERT_CHECK='TRUE';
      NO_DIR_CHECK='TRUE';
      ALLOW_CONNECT='TRUE';
    'VCCIN'<31>:
      PIN_NUMBER='(0,0,0,0,0,0,0,0,0,0,0,0,0,0,0,0,0,0,CH85,0,0,0,0,0,0,0,0,0,0,~
0)';
      PINUSE='POWER';
      NO_LOAD_CHECK='Both';
      NO_IO_CHECK='Both';
      NO_ASSERT_CHECK='TRUE';
      NO_DIR_CHECK='TRUE';
      ALLOW_CONNECT='TRUE';
    'VCCIN'<30>:
      PIN_NUMBER='(0,0,0,0,0,0,0,0,0,0,0,0,0,0,0,0,0,0,CJ60,0,0,0,0,0,0,0,0,0,0,~
0)';
      PINUSE='POWER';
      NO_LOAD_CHECK='Both';
      NO_IO_CHECK='Both';
      NO_ASSERT_CHECK='TRUE';
      NO_DIR_CHECK='TRUE';
      ALLOW_CONNECT='TRUE';
    'VCCIN'<29>:
      PIN_NUMBER='(0,0,0,0,0,0,0,0,0,0,0,0,0,0,0,0,0,0,CK59,0,0,0,0,0,0,0,0,0,0,~
0)';
      PINUSE='POWER';
      NO_LOAD_CHECK='Both';
      NO_IO_CHECK='Both';
      NO_ASSERT_CHECK='TRUE';
      NO_DIR_CHECK='TRUE';
      ALLOW_CONNECT='TRUE';
    'VCCIN'<28>:
      PIN_NUMBER='(0,0,0,0,0,0,0,0,0,0,0,0,0,0,0,0,0,0,CK61,0,0,0,0,0,0,0,0,0,0,~
0)';
      PINUSE='POWER';
      NO_LOAD_CHECK='Both';
      NO_IO_CHECK='Both';
      NO_ASSERT_CHECK='TRUE';
      NO_DIR_CHECK='TRUE';
      ALLOW_CONNECT='TRUE';
    'VCCIN'<27>:
      PIN_NUMBER='(0,0,0,0,0,0,0,0,0,0,0,0,0,0,0,0,0,0,CL58,0,0,0,0,0,0,0,0,0,0,~
0)';
      PINUSE='POWER';
      NO_LOAD_CHECK='Both';
      NO_IO_CHECK='Both';
      NO_ASSERT_CHECK='TRUE';
      NO_DIR_CHECK='TRUE';
      ALLOW_CONNECT='TRUE';
    'VCCIN'<26>:
      PIN_NUMBER='(0,0,0,0,0,0,0,0,0,0,0,0,0,0,0,0,0,0,CL60,0,0,0,0,0,0,0,0,0,0,~
0)';
      PINUSE='POWER';
      NO_LOAD_CHECK='Both';
      NO_IO_CHECK='Both';
      NO_ASSERT_CHECK='TRUE';
      NO_DIR_CHECK='TRUE';
      ALLOW_CONNECT='TRUE';
    'VCCIN'<25>:
      PIN_NUMBER='(0,0,0,0,0,0,0,0,0,0,0,0,0,0,0,0,0,0,CM57,0,0,0,0,0,0,0,0,0,0,~
0)';
      PINUSE='POWER';
      NO_LOAD_CHECK='Both';
      NO_IO_CHECK='Both';
      NO_ASSERT_CHECK='TRUE';
      NO_DIR_CHECK='TRUE';
      ALLOW_CONNECT='TRUE';
    'VCCIN'<24>:
      PIN_NUMBER='(0,0,0,0,0,0,0,0,0,0,0,0,0,0,0,0,0,0,CM59,0,0,0,0,0,0,0,0,0,0,~
0)';
      PINUSE='POWER';
      NO_LOAD_CHECK='Both';
      NO_IO_CHECK='Both';
      NO_ASSERT_CHECK='TRUE';
      NO_DIR_CHECK='TRUE';
      ALLOW_CONNECT='TRUE';
    'VCCIN'<23>:
      PIN_NUMBER='(0,0,0,0,0,0,0,0,0,0,0,0,0,0,0,0,0,0,CN56,0,0,0,0,0,0,0,0,0,0,~
0)';
      PINUSE='POWER';
      NO_LOAD_CHECK='Both';
      NO_IO_CHECK='Both';
      NO_ASSERT_CHECK='TRUE';
      NO_DIR_CHECK='TRUE';
      ALLOW_CONNECT='TRUE';
    'VCCIN'<22>:
      PIN_NUMBER='(0,0,0,0,0,0,0,0,0,0,0,0,0,0,0,0,0,0,CN58,0,0,0,0,0,0,0,0,0,0,~
0)';
      PINUSE='POWER';
      NO_LOAD_CHECK='Both';
      NO_IO_CHECK='Both';
      NO_ASSERT_CHECK='TRUE';
      NO_DIR_CHECK='TRUE';
      ALLOW_CONNECT='TRUE';
    'VCCIN'<21>:
      PIN_NUMBER='(0,0,0,0,0,0,0,0,0,0,0,0,0,0,0,0,0,0,CP33,0,0,0,0,0,0,0,0,0,0,~
0)';
      PINUSE='POWER';
      NO_LOAD_CHECK='Both';
      NO_IO_CHECK='Both';
      NO_ASSERT_CHECK='TRUE';
      NO_DIR_CHECK='TRUE';
      ALLOW_CONNECT='TRUE';
    'VCCIN'<20>:
      PIN_NUMBER='(0,0,0,0,0,0,0,0,0,0,0,0,0,0,0,0,0,0,CP55,0,0,0,0,0,0,0,0,0,0,~
0)';
      PINUSE='POWER';
      NO_LOAD_CHECK='Both';
      NO_IO_CHECK='Both';
      NO_ASSERT_CHECK='TRUE';
      NO_DIR_CHECK='TRUE';
      ALLOW_CONNECT='TRUE';
    'VCCIN'<19>:
      PIN_NUMBER='(0,0,0,0,0,0,0,0,0,0,0,0,0,0,0,0,0,0,CP57,0,0,0,0,0,0,0,0,0,0,~
0)';
      PINUSE='POWER';
      NO_LOAD_CHECK='Both';
      NO_IO_CHECK='Both';
      NO_ASSERT_CHECK='TRUE';
      NO_DIR_CHECK='TRUE';
      ALLOW_CONNECT='TRUE';
    'VCCIN'<18>:
      PIN_NUMBER='(0,0,0,0,0,0,0,0,0,0,0,0,0,0,0,0,0,0,CR34,0,0,0,0,0,0,0,0,0,0,~
0)';
      PINUSE='POWER';
      NO_LOAD_CHECK='Both';
      NO_IO_CHECK='Both';
      NO_ASSERT_CHECK='TRUE';
      NO_DIR_CHECK='TRUE';
      ALLOW_CONNECT='TRUE';
    'VCCIN'<17>:
      PIN_NUMBER='(0,0,0,0,0,0,0,0,0,0,0,0,0,0,0,0,0,0,CR54,0,0,0,0,0,0,0,0,0,0,~
0)';
      PINUSE='POWER';
      NO_LOAD_CHECK='Both';
      NO_IO_CHECK='Both';
      NO_ASSERT_CHECK='TRUE';
      NO_DIR_CHECK='TRUE';
      ALLOW_CONNECT='TRUE';
    'VCCIN'<16>:
      PIN_NUMBER='(0,0,0,0,0,0,0,0,0,0,0,0,0,0,0,0,0,0,CR56,0,0,0,0,0,0,0,0,0,0,~
0)';
      PINUSE='POWER';
      NO_LOAD_CHECK='Both';
      NO_IO_CHECK='Both';
      NO_ASSERT_CHECK='TRUE';
      NO_DIR_CHECK='TRUE';
      ALLOW_CONNECT='TRUE';
    'VCCIN'<15>:
      PIN_NUMBER='(0,0,0,0,0,0,0,0,0,0,0,0,0,0,0,0,0,0,CT37,0,0,0,0,0,0,0,0,0,0,~
0)';
      PINUSE='POWER';
      NO_LOAD_CHECK='Both';
      NO_IO_CHECK='Both';
      NO_ASSERT_CHECK='TRUE';
      NO_DIR_CHECK='TRUE';
      ALLOW_CONNECT='TRUE';
    'VCCIN'<14>:
      PIN_NUMBER='(0,0,0,0,0,0,0,0,0,0,0,0,0,0,0,0,0,0,CT39,0,0,0,0,0,0,0,0,0,0,~
0)';
      PINUSE='POWER';
      NO_LOAD_CHECK='Both';
      NO_IO_CHECK='Both';
      NO_ASSERT_CHECK='TRUE';
      NO_DIR_CHECK='TRUE';
      ALLOW_CONNECT='TRUE';
    'VCCIN'<13>:
      PIN_NUMBER='(0,0,0,0,0,0,0,0,0,0,0,0,0,0,0,0,0,0,CT41,0,0,0,0,0,0,0,0,0,0,~
0)';
      PINUSE='POWER';
      NO_LOAD_CHECK='Both';
      NO_IO_CHECK='Both';
      NO_ASSERT_CHECK='TRUE';
      NO_DIR_CHECK='TRUE';
      ALLOW_CONNECT='TRUE';
    'VCCIN'<12>:
      PIN_NUMBER='(0,0,0,0,0,0,0,0,0,0,0,0,0,0,0,0,0,0,CT53,0,0,0,0,0,0,0,0,0,0,~
0)';
      PINUSE='POWER';
      NO_LOAD_CHECK='Both';
      NO_IO_CHECK='Both';
      NO_ASSERT_CHECK='TRUE';
      NO_DIR_CHECK='TRUE';
      ALLOW_CONNECT='TRUE';
    'VCCIN'<11>:
      PIN_NUMBER='(0,0,0,0,0,0,0,0,0,0,0,0,0,0,0,0,0,0,CT55,0,0,0,0,0,0,0,0,0,0,~
0)';
      PINUSE='POWER';
      NO_LOAD_CHECK='Both';
      NO_IO_CHECK='Both';
      NO_ASSERT_CHECK='TRUE';
      NO_DIR_CHECK='TRUE';
      ALLOW_CONNECT='TRUE';
    'VCCIN'<10>:
      PIN_NUMBER='(0,0,0,0,0,0,0,0,0,0,0,0,0,0,0,0,0,0,CU38,0,0,0,0,0,0,0,0,0,0,~
0)';
      PINUSE='POWER';
      NO_LOAD_CHECK='Both';
      NO_IO_CHECK='Both';
      NO_ASSERT_CHECK='TRUE';
      NO_DIR_CHECK='TRUE';
      ALLOW_CONNECT='TRUE';
    'VCCIN'<9>:
      PIN_NUMBER='(0,0,0,0,0,0,0,0,0,0,0,0,0,0,0,0,0,0,CU40,0,0,0,0,0,0,0,0,0,0,~
0)';
      PINUSE='POWER';
      NO_LOAD_CHECK='Both';
      NO_IO_CHECK='Both';
      NO_ASSERT_CHECK='TRUE';
      NO_DIR_CHECK='TRUE';
      ALLOW_CONNECT='TRUE';
    'VCCIN'<8>:
      PIN_NUMBER='(0,0,0,0,0,0,0,0,0,0,0,0,0,0,0,0,0,0,CU42,0,0,0,0,0,0,0,0,0,0,~
0)';
      PINUSE='POWER';
      NO_LOAD_CHECK='Both';
      NO_IO_CHECK='Both';
      NO_ASSERT_CHECK='TRUE';
      NO_DIR_CHECK='TRUE';
      ALLOW_CONNECT='TRUE';
    'VCCIN'<7>:
      PIN_NUMBER='(0,0,0,0,0,0,0,0,0,0,0,0,0,0,0,0,0,0,CU52,0,0,0,0,0,0,0,0,0,0,~
0)';
      PINUSE='POWER';
      NO_LOAD_CHECK='Both';
      NO_IO_CHECK='Both';
      NO_ASSERT_CHECK='TRUE';
      NO_DIR_CHECK='TRUE';
      ALLOW_CONNECT='TRUE';
    'VCCIN'<6>:
      PIN_NUMBER='(0,0,0,0,0,0,0,0,0,0,0,0,0,0,0,0,0,0,CU54,0,0,0,0,0,0,0,0,0,0,~
0)';
      PINUSE='POWER';
      NO_LOAD_CHECK='Both';
      NO_IO_CHECK='Both';
      NO_ASSERT_CHECK='TRUE';
      NO_DIR_CHECK='TRUE';
      ALLOW_CONNECT='TRUE';
    'VCCIN'<5>:
      PIN_NUMBER='(0,0,0,0,0,0,0,0,0,0,0,0,0,0,0,0,0,0,CV51,0,0,0,0,0,0,0,0,0,0,~
0)';
      PINUSE='POWER';
      NO_LOAD_CHECK='Both';
      NO_IO_CHECK='Both';
      NO_ASSERT_CHECK='TRUE';
      NO_DIR_CHECK='TRUE';
      ALLOW_CONNECT='TRUE';
    'VCCIN'<4>:
      PIN_NUMBER='(0,0,0,0,0,0,0,0,0,0,0,0,0,0,0,0,0,0,CW46,0,0,0,0,0,0,0,0,0,0,~
0)';
      PINUSE='POWER';
      NO_LOAD_CHECK='Both';
      NO_IO_CHECK='Both';
      NO_ASSERT_CHECK='TRUE';
      NO_DIR_CHECK='TRUE';
      ALLOW_CONNECT='TRUE';
    'VCCIN'<3>:
      PIN_NUMBER='(0,0,0,0,0,0,0,0,0,0,0,0,0,0,0,0,0,0,CW48,0,0,0,0,0,0,0,0,0,0,~
0)';
      PINUSE='POWER';
      NO_LOAD_CHECK='Both';
      NO_IO_CHECK='Both';
      NO_ASSERT_CHECK='TRUE';
      NO_DIR_CHECK='TRUE';
      ALLOW_CONNECT='TRUE';
    'VCCIN'<2>:
      PIN_NUMBER='(0,0,0,0,0,0,0,0,0,0,0,0,0,0,0,0,0,0,CW50,0,0,0,0,0,0,0,0,0,0,~
0)';
      PINUSE='POWER';
      NO_LOAD_CHECK='Both';
      NO_IO_CHECK='Both';
      NO_ASSERT_CHECK='TRUE';
      NO_DIR_CHECK='TRUE';
      ALLOW_CONNECT='TRUE';
    'VCCIN'<1>:
      PIN_NUMBER='(0,0,0,0,0,0,0,0,0,0,0,0,0,0,0,0,0,0,CY47,0,0,0,0,0,0,0,0,0,0,~
0)';
      PINUSE='POWER';
      NO_LOAD_CHECK='Both';
      NO_IO_CHECK='Both';
      NO_ASSERT_CHECK='TRUE';
      NO_DIR_CHECK='TRUE';
      ALLOW_CONNECT='TRUE';
    'VCCIN'<0>:
      PIN_NUMBER='(0,0,0,0,0,0,0,0,0,0,0,0,0,0,0,0,0,0,CY49,0,0,0,0,0,0,0,0,0,0,~
0)';
      PINUSE='POWER';
      NO_LOAD_CHECK='Both';
      NO_IO_CHECK='Both';
      NO_ASSERT_CHECK='TRUE';
      NO_DIR_CHECK='TRUE';
      ALLOW_CONNECT='TRUE';
    'VCCINPMAX'<1>:
      PIN_NUMBER='(0,0,0,0,0,0,0,0,0,0,0,0,0,0,0,0,0,0,AV85,0,0,0,0,0,0,0,0,0,0,~
0)';
      PINUSE='POWER';
      NO_LOAD_CHECK='Both';
      NO_IO_CHECK='Both';
      NO_ASSERT_CHECK='TRUE';
      NO_DIR_CHECK='TRUE';
      ALLOW_CONNECT='TRUE';
    'VCCINPMAX'<0>:
      PIN_NUMBER='(0,0,0,0,0,0,0,0,0,0,0,0,0,0,0,0,0,0,AW86,0,0,0,0,0,0,0,0,0,0,~
0)';
      PINUSE='POWER';
      NO_LOAD_CHECK='Both';
      NO_IO_CHECK='Both';
      NO_ASSERT_CHECK='TRUE';
      NO_DIR_CHECK='TRUE';
      ALLOW_CONNECT='TRUE';
    'VCCIN_SENSE':
      PIN_NUMBER='(0,0,0,0,0,0,0,0,0,0,0,0,0,0,0,0,0,0,BA86,0,0,0,0,0,0,0,0,0,0,~
0)';
      BIDIRECTIONAL='TRUE';
      INPUT_LOAD='(-0.01,0.01)';
      OUTPUT_LOAD='(1.0,-1.0)';
      PINUSE='BI';
    'VCCIO'<104>:
      PIN_NUMBER='(0,0,0,0,0,0,0,0,0,0,0,0,0,0,0,0,0,0,0,0,AR28,0,0,0,0,0,0,0,0,~
0)';
      PINUSE='POWER';
      NO_LOAD_CHECK='Both';
      NO_IO_CHECK='Both';
      NO_ASSERT_CHECK='TRUE';
      NO_DIR_CHECK='TRUE';
      ALLOW_CONNECT='TRUE';
    'VCCIO'<103>:
      PIN_NUMBER='(0,0,0,0,0,0,0,0,0,0,0,0,0,0,0,0,0,0,0,0,AL28,0,0,0,0,0,0,0,0,~
0)';
      PINUSE='POWER';
      NO_LOAD_CHECK='Both';
      NO_IO_CHECK='Both';
      NO_ASSERT_CHECK='TRUE';
      NO_DIR_CHECK='TRUE';
      ALLOW_CONNECT='TRUE';
    'VCCIO'<102>:
      PIN_NUMBER='(0,0,0,0,0,0,0,0,0,0,0,0,0,0,0,0,0,0,0,0,AM29,0,0,0,0,0,0,0,0,~
0)';
      PINUSE='POWER';
      NO_LOAD_CHECK='Both';
      NO_IO_CHECK='Both';
      NO_ASSERT_CHECK='TRUE';
      NO_DIR_CHECK='TRUE';
      ALLOW_CONNECT='TRUE';
    'VCCIO'<101>:
      PIN_NUMBER='(0,0,0,0,0,0,0,0,0,0,0,0,0,0,0,0,0,0,0,0,AG34,0,0,0,0,0,0,0,0,~
0)';
      PINUSE='POWER';
      NO_LOAD_CHECK='Both';
      NO_IO_CHECK='Both';
      NO_ASSERT_CHECK='TRUE';
      NO_DIR_CHECK='TRUE';
      ALLOW_CONNECT='TRUE';
    'VCCIO'<100>:
      PIN_NUMBER='(0,0,0,0,0,0,0,0,0,0,0,0,0,0,0,0,0,0,0,0,AE34,0,0,0,0,0,0,0,0,~
0)';
      PINUSE='POWER';
      NO_LOAD_CHECK='Both';
      NO_IO_CHECK='Both';
      NO_ASSERT_CHECK='TRUE';
      NO_DIR_CHECK='TRUE';
      ALLOW_CONNECT='TRUE';
    'VCCIO'<99>:
      PIN_NUMBER='(0,0,0,0,0,0,0,0,0,0,0,0,0,0,0,0,0,0,0,0,AD35,0,0,0,0,0,0,0,0,~
0)';
      PINUSE='POWER';
      NO_LOAD_CHECK='Both';
      NO_IO_CHECK='Both';
      NO_ASSERT_CHECK='TRUE';
      NO_DIR_CHECK='TRUE';
      ALLOW_CONNECT='TRUE';
    'VCCIO'<98>:
      PIN_NUMBER='(0,0,0,0,0,0,0,0,0,0,0,0,0,0,0,0,0,0,0,0,AF35,0,0,0,0,0,0,0,0,~
0)';
      PINUSE='POWER';
      NO_LOAD_CHECK='Both';
      NO_IO_CHECK='Both';
      NO_ASSERT_CHECK='TRUE';
      NO_DIR_CHECK='TRUE';
      ALLOW_CONNECT='TRUE';
    'VCCIO'<97>:
      PIN_NUMBER='(0,0,0,0,0,0,0,0,0,0,0,0,0,0,0,0,0,0,0,0,AC36,0,0,0,0,0,0,0,0,~
0)';
      PINUSE='POWER';
      NO_LOAD_CHECK='Both';
      NO_IO_CHECK='Both';
      NO_ASSERT_CHECK='TRUE';
      NO_DIR_CHECK='TRUE';
      ALLOW_CONNECT='TRUE';
    'VCCIO'<96>:
      PIN_NUMBER='(0,0,0,0,0,0,0,0,0,0,0,0,0,0,0,0,0,0,0,0,AD37,0,0,0,0,0,0,0,0,~
0)';
      PINUSE='POWER';
      NO_LOAD_CHECK='Both';
      NO_IO_CHECK='Both';
      NO_ASSERT_CHECK='TRUE';
      NO_DIR_CHECK='TRUE';
      ALLOW_CONNECT='TRUE';
    'VCCIO'<95>:
      PIN_NUMBER='(0,0,0,0,0,0,0,0,0,0,0,0,0,0,0,0,0,0,0,0,AE36,0,0,0,0,0,0,0,0,~
0)';
      PINUSE='POWER';
      NO_LOAD_CHECK='Both';
      NO_IO_CHECK='Both';
      NO_ASSERT_CHECK='TRUE';
      NO_DIR_CHECK='TRUE';
      ALLOW_CONNECT='TRUE';
    'VCCIO'<94>:
      PIN_NUMBER='(0,0,0,0,0,0,0,0,0,0,0,0,0,0,0,0,0,0,0,0,BF27,0,0,0,0,0,0,0,0,~
0)';
      PINUSE='POWER';
      NO_LOAD_CHECK='Both';
      NO_IO_CHECK='Both';
      NO_ASSERT_CHECK='TRUE';
      NO_DIR_CHECK='TRUE';
      ALLOW_CONNECT='TRUE';
    'VCCIO'<93>:
      PIN_NUMBER='(0,0,0,0,0,0,0,0,0,0,0,0,0,0,0,0,0,0,0,0,BG26,0,0,0,0,0,0,0,0,~
0)';
      PINUSE='POWER';
      NO_LOAD_CHECK='Both';
      NO_IO_CHECK='Both';
      NO_ASSERT_CHECK='TRUE';
      NO_DIR_CHECK='TRUE';
      ALLOW_CONNECT='TRUE';
    'VCCIO'<92>:
      PIN_NUMBER='(0,0,0,0,0,0,0,0,0,0,0,0,0,0,0,0,0,0,0,0,BH25,0,0,0,0,0,0,0,0,~
0)';
      PINUSE='POWER';
      NO_LOAD_CHECK='Both';
      NO_IO_CHECK='Both';
      NO_ASSERT_CHECK='TRUE';
      NO_DIR_CHECK='TRUE';
      ALLOW_CONNECT='TRUE';
    'VCCIO'<91>:
      PIN_NUMBER='(0,0,0,0,0,0,0,0,0,0,0,0,0,0,0,0,0,0,0,0,BH27,0,0,0,0,0,0,0,0,~
0)';
      PINUSE='POWER';
      NO_LOAD_CHECK='Both';
      NO_IO_CHECK='Both';
      NO_ASSERT_CHECK='TRUE';
      NO_DIR_CHECK='TRUE';
      ALLOW_CONNECT='TRUE';
    'VCCIO'<90>:
      PIN_NUMBER='(0,0,0,0,0,0,0,0,0,0,0,0,0,0,0,0,0,0,0,0,BJ26,0,0,0,0,0,0,0,0,~
0)';
      PINUSE='POWER';
      NO_LOAD_CHECK='Both';
      NO_IO_CHECK='Both';
      NO_ASSERT_CHECK='TRUE';
      NO_DIR_CHECK='TRUE';
      ALLOW_CONNECT='TRUE';
    'VCCIO'<89>:
      PIN_NUMBER='(0,0,0,0,0,0,0,0,0,0,0,0,0,0,0,0,0,0,0,0,BK25,0,0,0,0,0,0,0,0,~
0)';
      PINUSE='POWER';
      NO_LOAD_CHECK='Both';
      NO_IO_CHECK='Both';
      NO_ASSERT_CHECK='TRUE';
      NO_DIR_CHECK='TRUE';
      ALLOW_CONNECT='TRUE';
    'VCCIO'<88>:
      PIN_NUMBER='(0,0,0,0,0,0,0,0,0,0,0,0,0,0,0,0,0,0,0,0,BK27,0,0,0,0,0,0,0,0,~
0)';
      PINUSE='POWER';
      NO_LOAD_CHECK='Both';
      NO_IO_CHECK='Both';
      NO_ASSERT_CHECK='TRUE';
      NO_DIR_CHECK='TRUE';
      ALLOW_CONNECT='TRUE';
    'VCCIO'<87>:
      PIN_NUMBER='(0,0,0,0,0,0,0,0,0,0,0,0,0,0,0,0,0,0,0,0,BL26,0,0,0,0,0,0,0,0,~
0)';
      PINUSE='POWER';
      NO_LOAD_CHECK='Both';
      NO_IO_CHECK='Both';
      NO_ASSERT_CHECK='TRUE';
      NO_DIR_CHECK='TRUE';
      ALLOW_CONNECT='TRUE';
    'VCCIO'<86>:
      PIN_NUMBER='(0,0,0,0,0,0,0,0,0,0,0,0,0,0,0,0,0,0,0,0,BM27,0,0,0,0,0,0,0,0,~
0)';
      PINUSE='POWER';
      NO_LOAD_CHECK='Both';
      NO_IO_CHECK='Both';
      NO_ASSERT_CHECK='TRUE';
      NO_DIR_CHECK='TRUE';
      ALLOW_CONNECT='TRUE';
    'VCCIO'<85>:
      PIN_NUMBER='(0,0,0,0,0,0,0,0,0,0,0,0,0,0,0,0,0,0,0,0,CH27,0,0,0,0,0,0,0,0,~
0)';
      PINUSE='POWER';
      NO_LOAD_CHECK='Both';
      NO_IO_CHECK='Both';
      NO_ASSERT_CHECK='TRUE';
      NO_DIR_CHECK='TRUE';
      ALLOW_CONNECT='TRUE';
    'VCCIO'<84>:
      PIN_NUMBER='(0,0,0,0,0,0,0,0,0,0,0,0,0,0,0,0,0,0,0,0,CJ28,0,0,0,0,0,0,0,0,~
0)';
      PINUSE='POWER';
      NO_LOAD_CHECK='Both';
      NO_IO_CHECK='Both';
      NO_ASSERT_CHECK='TRUE';
      NO_DIR_CHECK='TRUE';
      ALLOW_CONNECT='TRUE';
    'VCCIO'<83>:
      PIN_NUMBER='(0,0,0,0,0,0,0,0,0,0,0,0,0,0,0,0,0,0,0,0,CC26,0,0,0,0,0,0,0,0,~
0)';
      PINUSE='POWER';
      NO_LOAD_CHECK='Both';
      NO_IO_CHECK='Both';
      NO_ASSERT_CHECK='TRUE';
      NO_DIR_CHECK='TRUE';
      ALLOW_CONNECT='TRUE';
    'VCCIO'<82>:
      PIN_NUMBER='(0,0,0,0,0,0,0,0,0,0,0,0,0,0,0,0,0,0,0,0,CD27,0,0,0,0,0,0,0,0,~
0)';
      PINUSE='POWER';
      NO_LOAD_CHECK='Both';
      NO_IO_CHECK='Both';
      NO_ASSERT_CHECK='TRUE';
      NO_DIR_CHECK='TRUE';
      ALLOW_CONNECT='TRUE';
    'VCCIO'<81>:
      PIN_NUMBER='(0,0,0,0,0,0,0,0,0,0,0,0,0,0,0,0,0,0,0,0,CF27,0,0,0,0,0,0,0,0,~
0)';
      PINUSE='POWER';
      NO_LOAD_CHECK='Both';
      NO_IO_CHECK='Both';
      NO_ASSERT_CHECK='TRUE';
      NO_DIR_CHECK='TRUE';
      ALLOW_CONNECT='TRUE';
    'VCCIO'<80>:
      PIN_NUMBER='(0,0,0,0,0,0,0,0,0,0,0,0,0,0,0,0,0,0,0,0,AV27,0,0,0,0,0,0,0,0,~
0)';
      PINUSE='POWER';
      NO_LOAD_CHECK='Both';
      NO_IO_CHECK='Both';
      NO_ASSERT_CHECK='TRUE';
      NO_DIR_CHECK='TRUE';
      ALLOW_CONNECT='TRUE';
    'VCCIO'<79>:
      PIN_NUMBER='(0,0,0,0,0,0,0,0,0,0,0,0,0,0,0,0,0,0,0,0,AW26,0,0,0,0,0,0,0,0,~
0)';
      PINUSE='POWER';
      NO_LOAD_CHECK='Both';
      NO_IO_CHECK='Both';
      NO_ASSERT_CHECK='TRUE';
      NO_DIR_CHECK='TRUE';
      ALLOW_CONNECT='TRUE';
    'VCCIO'<78>:
      PIN_NUMBER='(0,0,0,0,0,0,0,0,0,0,0,0,0,0,0,0,0,0,0,0,AY27,0,0,0,0,0,0,0,0,~
0)';
      PINUSE='POWER';
      NO_LOAD_CHECK='Both';
      NO_IO_CHECK='Both';
      NO_ASSERT_CHECK='TRUE';
      NO_DIR_CHECK='TRUE';
      ALLOW_CONNECT='TRUE';
    'VCCIO'<77>:
      PIN_NUMBER='(0,0,0,0,0,0,0,0,0,0,0,0,0,0,0,0,0,0,0,0,BA26,0,0,0,0,0,0,0,0,~
0)';
      PINUSE='POWER';
      NO_LOAD_CHECK='Both';
      NO_IO_CHECK='Both';
      NO_ASSERT_CHECK='TRUE';
      NO_DIR_CHECK='TRUE';
      ALLOW_CONNECT='TRUE';
    'VCCIO'<76>:
      PIN_NUMBER='(0,0,0,0,0,0,0,0,0,0,0,0,0,0,0,0,0,0,0,0,BB27,0,0,0,0,0,0,0,0,~
0)';
      PINUSE='POWER';
      NO_LOAD_CHECK='Both';
      NO_IO_CHECK='Both';
      NO_ASSERT_CHECK='TRUE';
      NO_DIR_CHECK='TRUE';
      ALLOW_CONNECT='TRUE';
    'VCCIO'<75>:
      PIN_NUMBER='(0,0,0,0,0,0,0,0,0,0,0,0,0,0,0,0,0,0,0,0,BC26,0,0,0,0,0,0,0,0,~
0)';
      PINUSE='POWER';
      NO_LOAD_CHECK='Both';
      NO_IO_CHECK='Both';
      NO_ASSERT_CHECK='TRUE';
      NO_DIR_CHECK='TRUE';
      ALLOW_CONNECT='TRUE';
    'VCCIO'<74>:
      PIN_NUMBER='(0,0,0,0,0,0,0,0,0,0,0,0,0,0,0,0,0,0,0,0,W10,0,0,0,0,0,0,0,0,0~
)';
      PINUSE='POWER';
      NO_LOAD_CHECK='Both';
      NO_IO_CHECK='Both';
      NO_ASSERT_CHECK='TRUE';
      NO_DIR_CHECK='TRUE';
      ALLOW_CONNECT='TRUE';
    'VCCIO'<73>:
      PIN_NUMBER='(0,0,0,0,0,0,0,0,0,0,0,0,0,0,0,0,0,0,0,0,N18,0,0,0,0,0,0,0,0,0~
)';
      PINUSE='POWER';
      NO_LOAD_CHECK='Both';
      NO_IO_CHECK='Both';
      NO_ASSERT_CHECK='TRUE';
      NO_DIR_CHECK='TRUE';
      ALLOW_CONNECT='TRUE';
    'VCCIO'<72>:
      PIN_NUMBER='(0,0,0,0,0,0,0,0,0,0,0,0,0,0,0,0,0,0,0,0,M9,0,0,0,0,0,0,0,0,0)~
';
      PINUSE='POWER';
      NO_LOAD_CHECK='Both';
      NO_IO_CHECK='Both';
      NO_ASSERT_CHECK='TRUE';
      NO_DIR_CHECK='TRUE';
      ALLOW_CONNECT='TRUE';
    'VCCIO'<71>:
      PIN_NUMBER='(0,0,0,0,0,0,0,0,0,0,0,0,0,0,0,0,0,0,0,0,M7,0,0,0,0,0,0,0,0,0)~
';
      PINUSE='POWER';
      NO_LOAD_CHECK='Both';
      NO_IO_CHECK='Both';
      NO_ASSERT_CHECK='TRUE';
      NO_DIR_CHECK='TRUE';
      ALLOW_CONNECT='TRUE';
    'VCCIO'<70>:
      PIN_NUMBER='(0,0,0,0,0,0,0,0,0,0,0,0,0,0,0,0,0,0,0,0,K15,0,0,0,0,0,0,0,0,0~
)';
      PINUSE='POWER';
      NO_LOAD_CHECK='Both';
      NO_IO_CHECK='Both';
      NO_ASSERT_CHECK='TRUE';
      NO_DIR_CHECK='TRUE';
      ALLOW_CONNECT='TRUE';
    'VCCIO'<69>:
      PIN_NUMBER='(0,0,0,0,0,0,0,0,0,0,0,0,0,0,0,0,0,0,0,0,J2,0,0,0,0,0,0,0,0,0)~
';
      PINUSE='POWER';
      NO_LOAD_CHECK='Both';
      NO_IO_CHECK='Both';
      NO_ASSERT_CHECK='TRUE';
      NO_DIR_CHECK='TRUE';
      ALLOW_CONNECT='TRUE';
    'VCCIO'<68>:
      PIN_NUMBER='(0,0,0,0,0,0,0,0,0,0,0,0,0,0,0,0,0,0,0,0,EB15,0,0,0,0,0,0,0,0,~
0)';
      PINUSE='POWER';
      NO_LOAD_CHECK='Both';
      NO_IO_CHECK='Both';
      NO_ASSERT_CHECK='TRUE';
      NO_DIR_CHECK='TRUE';
      ALLOW_CONNECT='TRUE';
    'VCCIO'<67>:
      PIN_NUMBER='(0,0,0,0,0,0,0,0,0,0,0,0,0,0,0,0,0,0,0,0,EA12,0,0,0,0,0,0,0,0,~
0)';
      PINUSE='POWER';
      NO_LOAD_CHECK='Both';
      NO_IO_CHECK='Both';
      NO_ASSERT_CHECK='TRUE';
      NO_DIR_CHECK='TRUE';
      ALLOW_CONNECT='TRUE';
    'VCCIO'<66>:
      PIN_NUMBER='(0,0,0,0,0,0,0,0,0,0,0,0,0,0,0,0,0,0,0,0,DU20,0,0,0,0,0,0,0,0,~
0)';
      PINUSE='POWER';
      NO_LOAD_CHECK='Both';
      NO_IO_CHECK='Both';
      NO_ASSERT_CHECK='TRUE';
      NO_DIR_CHECK='TRUE';
      ALLOW_CONNECT='TRUE';
    'VCCIO'<65>:
      PIN_NUMBER='(0,0,0,0,0,0,0,0,0,0,0,0,0,0,0,0,0,0,0,0,DR2,0,0,0,0,0,0,0,0,0~
)';
      PINUSE='POWER';
      NO_LOAD_CHECK='Both';
      NO_IO_CHECK='Both';
      NO_ASSERT_CHECK='TRUE';
      NO_DIR_CHECK='TRUE';
      ALLOW_CONNECT='TRUE';
    'VCCIO'<64>:
      PIN_NUMBER='(0,0,0,0,0,0,0,0,0,0,0,0,0,0,0,0,0,0,0,0,DR10,0,0,0,0,0,0,0,0,~
0)';
      PINUSE='POWER';
      NO_LOAD_CHECK='Both';
      NO_IO_CHECK='Both';
      NO_ASSERT_CHECK='TRUE';
      NO_DIR_CHECK='TRUE';
      ALLOW_CONNECT='TRUE';
    'VCCIO'<63>:
      PIN_NUMBER='(0,0,0,0,0,0,0,0,0,0,0,0,0,0,0,0,0,0,0,0,DP19,0,0,0,0,0,0,0,0,~
0)';
      PINUSE='POWER';
      NO_LOAD_CHECK='Both';
      NO_IO_CHECK='Both';
      NO_ASSERT_CHECK='TRUE';
      NO_DIR_CHECK='TRUE';
      ALLOW_CONNECT='TRUE';
    'VCCIO'<62>:
      PIN_NUMBER='(0,0,0,0,0,0,0,0,0,0,0,0,0,0,0,0,0,0,0,0,DN8,0,0,0,0,0,0,0,0,0~
)';
      PINUSE='POWER';
      NO_LOAD_CHECK='Both';
      NO_IO_CHECK='Both';
      NO_ASSERT_CHECK='TRUE';
      NO_DIR_CHECK='TRUE';
      ALLOW_CONNECT='TRUE';
    'VCCIO'<61>:
      PIN_NUMBER='(0,0,0,0,0,0,0,0,0,0,0,0,0,0,0,0,0,0,0,0,DM17,0,0,0,0,0,0,0,0,~
0)';
      PINUSE='POWER';
      NO_LOAD_CHECK='Both';
      NO_IO_CHECK='Both';
      NO_ASSERT_CHECK='TRUE';
      NO_DIR_CHECK='TRUE';
      ALLOW_CONNECT='TRUE';
    'VCCIO'<60>:
      PIN_NUMBER='(0,0,0,0,0,0,0,0,0,0,0,0,0,0,0,0,0,0,0,0,DJ16,0,0,0,0,0,0,0,0,~
0)';
      PINUSE='POWER';
      NO_LOAD_CHECK='Both';
      NO_IO_CHECK='Both';
      NO_ASSERT_CHECK='TRUE';
      NO_DIR_CHECK='TRUE';
      ALLOW_CONNECT='TRUE';
    'VCCIO'<59>:
      PIN_NUMBER='(0,0,0,0,0,0,0,0,0,0,0,0,0,0,0,0,0,0,0,0,H13,0,0,0,0,0,0,0,0,0~
)';
      PINUSE='POWER';
      NO_LOAD_CHECK='Both';
      NO_IO_CHECK='Both';
      NO_ASSERT_CHECK='TRUE';
      NO_DIR_CHECK='TRUE';
      ALLOW_CONNECT='TRUE';
    'VCCIO'<58>:
      PIN_NUMBER='(0,0,0,0,0,0,0,0,0,0,0,0,0,0,0,0,0,0,0,0,J10,0,0,0,0,0,0,0,0,0~
)';
      PINUSE='POWER';
      NO_LOAD_CHECK='Both';
      NO_IO_CHECK='Both';
      NO_ASSERT_CHECK='TRUE';
      NO_DIR_CHECK='TRUE';
      ALLOW_CONNECT='TRUE';
    'VCCIO'<57>:
      PIN_NUMBER='(0,0,0,0,0,0,0,0,0,0,0,0,0,0,0,0,0,0,0,0,L14,0,0,0,0,0,0,0,0,0~
)';
      PINUSE='POWER';
      NO_LOAD_CHECK='Both';
      NO_IO_CHECK='Both';
      NO_ASSERT_CHECK='TRUE';
      NO_DIR_CHECK='TRUE';
      ALLOW_CONNECT='TRUE';
    'VCCIO'<56>:
      PIN_NUMBER='(0,0,0,0,0,0,0,0,0,0,0,0,0,0,0,0,0,0,0,0,L16,0,0,0,0,0,0,0,0,0~
)';
      PINUSE='POWER';
      NO_LOAD_CHECK='Both';
      NO_IO_CHECK='Both';
      NO_ASSERT_CHECK='TRUE';
      NO_DIR_CHECK='TRUE';
      ALLOW_CONNECT='TRUE';
    'VCCIO'<55>:
      PIN_NUMBER='(0,0,0,0,0,0,0,0,0,0,0,0,0,0,0,0,0,0,0,0,DH7,0,0,0,0,0,0,0,0,0~
)';
      PINUSE='POWER';
      NO_LOAD_CHECK='Both';
      NO_IO_CHECK='Both';
      NO_ASSERT_CHECK='TRUE';
      NO_DIR_CHECK='TRUE';
      ALLOW_CONNECT='TRUE';
    'VCCIO'<54>:
      PIN_NUMBER='(0,0,0,0,0,0,0,0,0,0,0,0,0,0,0,0,0,0,0,0,DG8,0,0,0,0,0,0,0,0,0~
)';
      PINUSE='POWER';
      NO_LOAD_CHECK='Both';
      NO_IO_CHECK='Both';
      NO_ASSERT_CHECK='TRUE';
      NO_DIR_CHECK='TRUE';
      ALLOW_CONNECT='TRUE';
    'VCCIO'<53>:
      PIN_NUMBER='(0,0,0,0,0,0,0,0,0,0,0,0,0,0,0,0,0,0,0,0,M11,0,0,0,0,0,0,0,0,0~
)';
      PINUSE='POWER';
      NO_LOAD_CHECK='Both';
      NO_IO_CHECK='Both';
      NO_ASSERT_CHECK='TRUE';
      NO_DIR_CHECK='TRUE';
      ALLOW_CONNECT='TRUE';
    'VCCIO'<52>:
      PIN_NUMBER='(0,0,0,0,0,0,0,0,0,0,0,0,0,0,0,0,0,0,0,0,M21,0,0,0,0,0,0,0,0,0~
)';
      PINUSE='POWER';
      NO_LOAD_CHECK='Both';
      NO_IO_CHECK='Both';
      NO_ASSERT_CHECK='TRUE';
      NO_DIR_CHECK='TRUE';
      ALLOW_CONNECT='TRUE';
    'VCCIO'<51>:
      PIN_NUMBER='(0,0,0,0,0,0,0,0,0,0,0,0,0,0,0,0,0,0,0,0,P5,0,0,0,0,0,0,0,0,0)~
';
      PINUSE='POWER';
      NO_LOAD_CHECK='Both';
      NO_IO_CHECK='Both';
      NO_ASSERT_CHECK='TRUE';
      NO_DIR_CHECK='TRUE';
      ALLOW_CONNECT='TRUE';
    'VCCIO'<50>:
      PIN_NUMBER='(0,0,0,0,0,0,0,0,0,0,0,0,0,0,0,0,0,0,0,0,T3,0,0,0,0,0,0,0,0,0)~
';
      PINUSE='POWER';
      NO_LOAD_CHECK='Both';
      NO_IO_CHECK='Both';
      NO_ASSERT_CHECK='TRUE';
      NO_DIR_CHECK='TRUE';
      ALLOW_CONNECT='TRUE';
    'VCCIO'<49>:
      PIN_NUMBER='(0,0,0,0,0,0,0,0,0,0,0,0,0,0,0,0,0,0,0,0,U14,0,0,0,0,0,0,0,0,0~
)';
      PINUSE='POWER';
      NO_LOAD_CHECK='Both';
      NO_IO_CHECK='Both';
      NO_ASSERT_CHECK='TRUE';
      NO_DIR_CHECK='TRUE';
      ALLOW_CONNECT='TRUE';
    'VCCIO'<48>:
      PIN_NUMBER='(0,0,0,0,0,0,0,0,0,0,0,0,0,0,0,0,0,0,0,0,DF21,0,0,0,0,0,0,0,0,~
0)';
      PINUSE='POWER';
      NO_LOAD_CHECK='Both';
      NO_IO_CHECK='Both';
      NO_ASSERT_CHECK='TRUE';
      NO_DIR_CHECK='TRUE';
      ALLOW_CONNECT='TRUE';
    'VCCIO'<47>:
      PIN_NUMBER='(0,0,0,0,0,0,0,0,0,0,0,0,0,0,0,0,0,0,0,0,W4,0,0,0,0,0,0,0,0,0)~
';
      PINUSE='POWER';
      NO_LOAD_CHECK='Both';
      NO_IO_CHECK='Both';
      NO_ASSERT_CHECK='TRUE';
      NO_DIR_CHECK='TRUE';
      ALLOW_CONNECT='TRUE';
    'VCCIO'<46>:
      PIN_NUMBER='(0,0,0,0,0,0,0,0,0,0,0,0,0,0,0,0,0,0,0,0,W6,0,0,0,0,0,0,0,0,0)~
';
      PINUSE='POWER';
      NO_LOAD_CHECK='Both';
      NO_IO_CHECK='Both';
      NO_ASSERT_CHECK='TRUE';
      NO_DIR_CHECK='TRUE';
      ALLOW_CONNECT='TRUE';
    'VCCIO'<45>:
      PIN_NUMBER='(0,0,0,0,0,0,0,0,0,0,0,0,0,0,0,0,0,0,0,0,AA10,0,0,0,0,0,0,0,0,~
0)';
      PINUSE='POWER';
      NO_LOAD_CHECK='Both';
      NO_IO_CHECK='Both';
      NO_ASSERT_CHECK='TRUE';
      NO_DIR_CHECK='TRUE';
      ALLOW_CONNECT='TRUE';
    'VCCIO'<44>:
      PIN_NUMBER='(0,0,0,0,0,0,0,0,0,0,0,0,0,0,0,0,0,0,0,0,AC20,0,0,0,0,0,0,0,0,~
0)';
      PINUSE='POWER';
      NO_LOAD_CHECK='Both';
      NO_IO_CHECK='Both';
      NO_ASSERT_CHECK='TRUE';
      NO_DIR_CHECK='TRUE';
      ALLOW_CONNECT='TRUE';
    'VCCIO'<43>:
      PIN_NUMBER='(0,0,0,0,0,0,0,0,0,0,0,0,0,0,0,0,0,0,0,0,AC4,0,0,0,0,0,0,0,0,0~
)';
      PINUSE='POWER';
      NO_LOAD_CHECK='Both';
      NO_IO_CHECK='Both';
      NO_ASSERT_CHECK='TRUE';
      NO_DIR_CHECK='TRUE';
      ALLOW_CONNECT='TRUE';
    'VCCIO'<42>:
      PIN_NUMBER='(0,0,0,0,0,0,0,0,0,0,0,0,0,0,0,0,0,0,0,0,AH9,0,0,0,0,0,0,0,0,0~
)';
      PINUSE='POWER';
      NO_LOAD_CHECK='Both';
      NO_IO_CHECK='Both';
      NO_ASSERT_CHECK='TRUE';
      NO_DIR_CHECK='TRUE';
      ALLOW_CONNECT='TRUE';
    'VCCIO'<41>:
      PIN_NUMBER='(0,0,0,0,0,0,0,0,0,0,0,0,0,0,0,0,0,0,0,0,DF13,0,0,0,0,0,0,0,0,~
0)';
      PINUSE='POWER';
      NO_LOAD_CHECK='Both';
      NO_IO_CHECK='Both';
      NO_ASSERT_CHECK='TRUE';
      NO_DIR_CHECK='TRUE';
      ALLOW_CONNECT='TRUE';
    'VCCIO'<40>:
      PIN_NUMBER='(0,0,0,0,0,0,0,0,0,0,0,0,0,0,0,0,0,0,0,0,AN10,0,0,0,0,0,0,0,0,~
0)';
      PINUSE='POWER';
      NO_LOAD_CHECK='Both';
      NO_IO_CHECK='Both';
      NO_ASSERT_CHECK='TRUE';
      NO_DIR_CHECK='TRUE';
      ALLOW_CONNECT='TRUE';
    'VCCIO'<39>:
      PIN_NUMBER='(0,0,0,0,0,0,0,0,0,0,0,0,0,0,0,0,0,0,0,0,DD7,0,0,0,0,0,0,0,0,0~
)';
      PINUSE='POWER';
      NO_LOAD_CHECK='Both';
      NO_IO_CHECK='Both';
      NO_ASSERT_CHECK='TRUE';
      NO_DIR_CHECK='TRUE';
      ALLOW_CONNECT='TRUE';
    'VCCIO'<38>:
      PIN_NUMBER='(0,0,0,0,0,0,0,0,0,0,0,0,0,0,0,0,0,0,0,0,AT11,0,0,0,0,0,0,0,0,~
0)';
      PINUSE='POWER';
      NO_LOAD_CHECK='Both';
      NO_IO_CHECK='Both';
      NO_ASSERT_CHECK='TRUE';
      NO_DIR_CHECK='TRUE';
      ALLOW_CONNECT='TRUE';
    'VCCIO'<37>:
      PIN_NUMBER='(0,0,0,0,0,0,0,0,0,0,0,0,0,0,0,0,0,0,0,0,AW6,0,0,0,0,0,0,0,0,0~
)';
      PINUSE='POWER';
      NO_LOAD_CHECK='Both';
      NO_IO_CHECK='Both';
      NO_ASSERT_CHECK='TRUE';
      NO_DIR_CHECK='TRUE';
      ALLOW_CONNECT='TRUE';
    'VCCIO'<36>:
      PIN_NUMBER='(0,0,0,0,0,0,0,0,0,0,0,0,0,0,0,0,0,0,0,0,AY11,0,0,0,0,0,0,0,0,~
0)';
      PINUSE='POWER';
      NO_LOAD_CHECK='Both';
      NO_IO_CHECK='Both';
      NO_ASSERT_CHECK='TRUE';
      NO_DIR_CHECK='TRUE';
      ALLOW_CONNECT='TRUE';
    'VCCIO'<35>:
      PIN_NUMBER='(0,0,0,0,0,0,0,0,0,0,0,0,0,0,0,0,0,0,0,0,BA24,0,0,0,0,0,0,0,0,~
0)';
      PINUSE='POWER';
      NO_LOAD_CHECK='Both';
      NO_IO_CHECK='Both';
      NO_ASSERT_CHECK='TRUE';
      NO_DIR_CHECK='TRUE';
      ALLOW_CONNECT='TRUE';
    'VCCIO'<34>:
      PIN_NUMBER='(0,0,0,0,0,0,0,0,0,0,0,0,0,0,0,0,0,0,0,0,BB5,0,0,0,0,0,0,0,0,0~
)';
      PINUSE='POWER';
      NO_LOAD_CHECK='Both';
      NO_IO_CHECK='Both';
      NO_ASSERT_CHECK='TRUE';
      NO_DIR_CHECK='TRUE';
      ALLOW_CONNECT='TRUE';
    'VCCIO'<33>:
      PIN_NUMBER='(0,0,0,0,0,0,0,0,0,0,0,0,0,0,0,0,0,0,0,0,DA14,0,0,0,0,0,0,0,0,~
0)';
      PINUSE='POWER';
      NO_LOAD_CHECK='Both';
      NO_IO_CHECK='Both';
      NO_ASSERT_CHECK='TRUE';
      NO_DIR_CHECK='TRUE';
      ALLOW_CONNECT='TRUE';
    'VCCIO'<32>:
      PIN_NUMBER='(0,0,0,0,0,0,0,0,0,0,0,0,0,0,0,0,0,0,0,0,BF23,0,0,0,0,0,0,0,0,~
0)';
      PINUSE='POWER';
      NO_LOAD_CHECK='Both';
      NO_IO_CHECK='Both';
      NO_ASSERT_CHECK='TRUE';
      NO_DIR_CHECK='TRUE';
      ALLOW_CONNECT='TRUE';
    'VCCIO'<31>:
      PIN_NUMBER='(0,0,0,0,0,0,0,0,0,0,0,0,0,0,0,0,0,0,0,0,BJ24,0,0,0,0,0,0,0,0,~
0)';
      PINUSE='POWER';
      NO_LOAD_CHECK='Both';
      NO_IO_CHECK='Both';
      NO_ASSERT_CHECK='TRUE';
      NO_DIR_CHECK='TRUE';
      ALLOW_CONNECT='TRUE';
    'VCCIO'<30>:
      PIN_NUMBER='(0,0,0,0,0,0,0,0,0,0,0,0,0,0,0,0,0,0,0,0,BP25,0,0,0,0,0,0,0,0,~
0)';
      PINUSE='POWER';
      NO_LOAD_CHECK='Both';
      NO_IO_CHECK='Both';
      NO_ASSERT_CHECK='TRUE';
      NO_DIR_CHECK='TRUE';
      ALLOW_CONNECT='TRUE';
    'VCCIO'<29>:
      PIN_NUMBER='(0,0,0,0,0,0,0,0,0,0,0,0,0,0,0,0,0,0,0,0,CB13,0,0,0,0,0,0,0,0,~
0)';
      PINUSE='POWER';
      NO_LOAD_CHECK='Both';
      NO_IO_CHECK='Both';
      NO_ASSERT_CHECK='TRUE';
      NO_DIR_CHECK='TRUE';
      ALLOW_CONNECT='TRUE';
    'VCCIO'<28>:
      PIN_NUMBER='(0,0,0,0,0,0,0,0,0,0,0,0,0,0,0,0,0,0,0,0,CB17,0,0,0,0,0,0,0,0,~
0)';
      PINUSE='POWER';
      NO_LOAD_CHECK='Both';
      NO_IO_CHECK='Both';
      NO_ASSERT_CHECK='TRUE';
      NO_DIR_CHECK='TRUE';
      ALLOW_CONNECT='TRUE';
    'VCCIO'<27>:
      PIN_NUMBER='(0,0,0,0,0,0,0,0,0,0,0,0,0,0,0,0,0,0,0,0,CD9,0,0,0,0,0,0,0,0,0~
)';
      PINUSE='POWER';
      NO_LOAD_CHECK='Both';
      NO_IO_CHECK='Both';
      NO_ASSERT_CHECK='TRUE';
      NO_DIR_CHECK='TRUE';
      ALLOW_CONNECT='TRUE';
    'VCCIO'<26>:
      PIN_NUMBER='(0,0,0,0,0,0,0,0,0,0,0,0,0,0,0,0,0,0,0,0,CE18,0,0,0,0,0,0,0,0,~
0)';
      PINUSE='POWER';
      NO_LOAD_CHECK='Both';
      NO_IO_CHECK='Both';
      NO_ASSERT_CHECK='TRUE';
      NO_DIR_CHECK='TRUE';
      ALLOW_CONNECT='TRUE';
    'VCCIO'<25>:
      PIN_NUMBER='(0,0,0,0,0,0,0,0,0,0,0,0,0,0,0,0,0,0,0,0,D7,0,0,0,0,0,0,0,0,0)~
';
      PINUSE='POWER';
      NO_LOAD_CHECK='Both';
      NO_IO_CHECK='Both';
      NO_ASSERT_CHECK='TRUE';
      NO_DIR_CHECK='TRUE';
      ALLOW_CONNECT='TRUE';
    'VCCIO'<24>:
      PIN_NUMBER='(0,0,0,0,0,0,0,0,0,0,0,0,0,0,0,0,0,0,0,0,CH9,0,0,0,0,0,0,0,0,0~
)';
      PINUSE='POWER';
      NO_LOAD_CHECK='Both';
      NO_IO_CHECK='Both';
      NO_ASSERT_CHECK='TRUE';
      NO_DIR_CHECK='TRUE';
      ALLOW_CONNECT='TRUE';
    'VCCIO'<23>:
      PIN_NUMBER='(0,0,0,0,0,0,0,0,0,0,0,0,0,0,0,0,0,0,0,0,CV7,0,0,0,0,0,0,0,0,0~
)';
      PINUSE='POWER';
      NO_LOAD_CHECK='Both';
      NO_IO_CHECK='Both';
      NO_ASSERT_CHECK='TRUE';
      NO_DIR_CHECK='TRUE';
      ALLOW_CONNECT='TRUE';
    'VCCIO'<22>:
      PIN_NUMBER='(0,0,0,0,0,0,0,0,0,0,0,0,0,0,0,0,0,0,0,0,CK5,0,0,0,0,0,0,0,0,0~
)';
      PINUSE='POWER';
      NO_LOAD_CHECK='Both';
      NO_IO_CHECK='Both';
      NO_ASSERT_CHECK='TRUE';
      NO_DIR_CHECK='TRUE';
      ALLOW_CONNECT='TRUE';
    'VCCIO'<21>:
      PIN_NUMBER='(0,0,0,0,0,0,0,0,0,0,0,0,0,0,0,0,0,0,0,0,CL12,0,0,0,0,0,0,0,0,~
0)';
      PINUSE='POWER';
      NO_LOAD_CHECK='Both';
      NO_IO_CHECK='Both';
      NO_ASSERT_CHECK='TRUE';
      NO_DIR_CHECK='TRUE';
      ALLOW_CONNECT='TRUE';
    'VCCIO'<20>:
      PIN_NUMBER='(0,0,0,0,0,0,0,0,0,0,0,0,0,0,0,0,0,0,0,0,CM15,0,0,0,0,0,0,0,0,~
0)';
      PINUSE='POWER';
      NO_LOAD_CHECK='Both';
      NO_IO_CHECK='Both';
      NO_ASSERT_CHECK='TRUE';
      NO_DIR_CHECK='TRUE';
      ALLOW_CONNECT='TRUE';
    'VCCIO'<19>:
      PIN_NUMBER='(0,0,0,0,0,0,0,0,0,0,0,0,0,0,0,0,0,0,0,0,0,CN6,0,0,0,0,0,0,0,0~
)';
      PINUSE='POWER';
      NO_LOAD_CHECK='Both';
      NO_IO_CHECK='Both';
      NO_ASSERT_CHECK='TRUE';
      NO_DIR_CHECK='TRUE';
      ALLOW_CONNECT='TRUE';
    'VCCIO'<18>:
      PIN_NUMBER='(0,0,0,0,0,0,0,0,0,0,0,0,0,0,0,0,0,0,0,0,0,CU12,0,0,0,0,0,0,0,~
0)';
      PINUSE='POWER';
      NO_LOAD_CHECK='Both';
      NO_IO_CHECK='Both';
      NO_ASSERT_CHECK='TRUE';
      NO_DIR_CHECK='TRUE';
      ALLOW_CONNECT='TRUE';
    'VCCIO'<17>:
      PIN_NUMBER='(0,0,0,0,0,0,0,0,0,0,0,0,0,0,0,0,0,0,0,0,0,CV21,0,0,0,0,0,0,0,~
0)';
      PINUSE='POWER';
      NO_LOAD_CHECK='Both';
      NO_IO_CHECK='Both';
      NO_ASSERT_CHECK='TRUE';
      NO_DIR_CHECK='TRUE';
      ALLOW_CONNECT='TRUE';
    'VCCIO'<16>:
      PIN_NUMBER='(0,0,0,0,0,0,0,0,0,0,0,0,0,0,0,0,0,0,0,0,0,CU18,0,0,0,0,0,0,0,~
0)';
      PINUSE='POWER';
      NO_LOAD_CHECK='Both';
      NO_IO_CHECK='Both';
      NO_ASSERT_CHECK='TRUE';
      NO_DIR_CHECK='TRUE';
      ALLOW_CONNECT='TRUE';
    'VCCIO'<15>:
      PIN_NUMBER='(0,0,0,0,0,0,0,0,0,0,0,0,0,0,0,0,0,0,0,0,0,CY17,0,0,0,0,0,0,0,~
0)';
      PINUSE='POWER';
      NO_LOAD_CHECK='Both';
      NO_IO_CHECK='Both';
      NO_ASSERT_CHECK='TRUE';
      NO_DIR_CHECK='TRUE';
      ALLOW_CONNECT='TRUE';
    'VCCIO'<14>:
      PIN_NUMBER='(0,0,0,0,0,0,0,0,0,0,0,0,0,0,0,0,0,0,0,0,0,DC18,0,0,0,0,0,0,0,~
0)';
      PINUSE='POWER';
      NO_LOAD_CHECK='Both';
      NO_IO_CHECK='Both';
      NO_ASSERT_CHECK='TRUE';
      NO_DIR_CHECK='TRUE';
      ALLOW_CONNECT='TRUE';
    'VCCIO'<13>:
      PIN_NUMBER='(0,0,0,0,0,0,0,0,0,0,0,0,0,0,0,0,0,0,0,0,0,DE14,0,0,0,0,0,0,0,~
0)';
      PINUSE='POWER';
      NO_LOAD_CHECK='Both';
      NO_IO_CHECK='Both';
      NO_ASSERT_CHECK='TRUE';
      NO_DIR_CHECK='TRUE';
      ALLOW_CONNECT='TRUE';
    'VCCIO'<12>:
      PIN_NUMBER='(0,0,0,0,0,0,0,0,0,0,0,0,0,0,0,0,0,0,0,0,0,CP13,0,0,0,0,0,0,0,~
0)';
      PINUSE='POWER';
      NO_LOAD_CHECK='Both';
      NO_IO_CHECK='Both';
      NO_ASSERT_CHECK='TRUE';
      NO_DIR_CHECK='TRUE';
      ALLOW_CONNECT='TRUE';
    'VCCIO'<11>:
      PIN_NUMBER='(0,0,0,0,0,0,0,0,0,0,0,0,0,0,0,0,0,0,0,0,0,CL20,0,0,0,0,0,0,0,~
0)';
      PINUSE='POWER';
      NO_LOAD_CHECK='Both';
      NO_IO_CHECK='Both';
      NO_ASSERT_CHECK='TRUE';
      NO_DIR_CHECK='TRUE';
      ALLOW_CONNECT='TRUE';
    'VCCIO'<10>:
      PIN_NUMBER='(0,0,0,0,0,0,0,0,0,0,0,0,0,0,0,0,0,0,0,0,0,CG14,0,0,0,0,0,0,0,~
0)';
      PINUSE='POWER';
      NO_LOAD_CHECK='Both';
      NO_IO_CHECK='Both';
      NO_ASSERT_CHECK='TRUE';
      NO_DIR_CHECK='TRUE';
      ALLOW_CONNECT='TRUE';
    'VCCIO'<9>:
      PIN_NUMBER='(0,0,0,0,0,0,0,0,0,0,0,0,0,0,0,0,0,0,0,0,0,CF5,0,0,0,0,0,0,0,0~
)';
      PINUSE='POWER';
      NO_LOAD_CHECK='Both';
      NO_IO_CHECK='Both';
      NO_ASSERT_CHECK='TRUE';
      NO_DIR_CHECK='TRUE';
      ALLOW_CONNECT='TRUE';
    'VCCIO'<8>:
      PIN_NUMBER='(0,0,0,0,0,0,0,0,0,0,0,0,0,0,0,0,0,0,0,0,0,DK21,0,0,0,0,0,0,0,~
0)';
      PINUSE='POWER';
      NO_LOAD_CHECK='Both';
      NO_IO_CHECK='Both';
      NO_ASSERT_CHECK='TRUE';
      NO_DIR_CHECK='TRUE';
      ALLOW_CONNECT='TRUE';
    'VCCIO'<7>:
      PIN_NUMBER='(0,0,0,0,0,0,0,0,0,0,0,0,0,0,0,0,0,0,0,0,0,BE24,0,0,0,0,0,0,0,~
0)';
      PINUSE='POWER';
      NO_LOAD_CHECK='Both';
      NO_IO_CHECK='Both';
      NO_ASSERT_CHECK='TRUE';
      NO_DIR_CHECK='TRUE';
      ALLOW_CONNECT='TRUE';
    'VCCIO'<6>:
      PIN_NUMBER='(0,0,0,0,0,0,0,0,0,0,0,0,0,0,0,0,0,0,0,0,0,AT7,0,0,0,0,0,0,0,0~
)';
      PINUSE='POWER';
      NO_LOAD_CHECK='Both';
      NO_IO_CHECK='Both';
      NO_ASSERT_CHECK='TRUE';
      NO_DIR_CHECK='TRUE';
      ALLOW_CONNECT='TRUE';
    'VCCIO'<5>:
      PIN_NUMBER='(0,0,0,0,0,0,0,0,0,0,0,0,0,0,0,0,0,0,0,0,0,AT5,0,0,0,0,0,0,0,0~
)';
      PINUSE='POWER';
      NO_LOAD_CHECK='Both';
      NO_IO_CHECK='Both';
      NO_ASSERT_CHECK='TRUE';
      NO_DIR_CHECK='TRUE';
      ALLOW_CONNECT='TRUE';
    'VCCIO'<4>:
      PIN_NUMBER='(0,0,0,0,0,0,0,0,0,0,0,0,0,0,0,0,0,0,0,0,0,AM5,0,0,0,0,0,0,0,0~
)';
      PINUSE='POWER';
      NO_LOAD_CHECK='Both';
      NO_IO_CHECK='Both';
      NO_ASSERT_CHECK='TRUE';
      NO_DIR_CHECK='TRUE';
      ALLOW_CONNECT='TRUE';
    'VCCIO'<3>:
      PIN_NUMBER='(0,0,0,0,0,0,0,0,0,0,0,0,0,0,0,0,0,0,0,0,0,DV11,0,0,0,0,0,0,0,~
0)';
      PINUSE='POWER';
      NO_LOAD_CHECK='Both';
      NO_IO_CHECK='Both';
      NO_ASSERT_CHECK='TRUE';
      NO_DIR_CHECK='TRUE';
      ALLOW_CONNECT='TRUE';
    'VCCIO'<2>:
      PIN_NUMBER='(0,0,0,0,0,0,0,0,0,0,0,0,0,0,0,0,0,0,0,0,0,AF5,0,0,0,0,0,0,0,0~
)';
      PINUSE='POWER';
      NO_LOAD_CHECK='Both';
      NO_IO_CHECK='Both';
      NO_ASSERT_CHECK='TRUE';
      NO_DIR_CHECK='TRUE';
      ALLOW_CONNECT='TRUE';
    'VCCIO'<1>:
      PIN_NUMBER='(0,0,0,0,0,0,0,0,0,0,0,0,0,0,0,0,0,0,0,0,0,AE10,0,0,0,0,0,0,0,~
0)';
      PINUSE='POWER';
      NO_LOAD_CHECK='Both';
      NO_IO_CHECK='Both';
      NO_ASSERT_CHECK='TRUE';
      NO_DIR_CHECK='TRUE';
      ALLOW_CONNECT='TRUE';
    'VCCIO'<0>:
      PIN_NUMBER='(0,0,0,0,0,0,0,0,0,0,0,0,0,0,0,0,0,0,0,0,0,EE10,0,0,0,0,0,0,0,~
0)';
      PINUSE='POWER';
      NO_LOAD_CHECK='Both';
      NO_IO_CHECK='Both';
      NO_ASSERT_CHECK='TRUE';
      NO_DIR_CHECK='TRUE';
      ALLOW_CONNECT='TRUE';
    'VCCIO_SENSE':
      PIN_NUMBER='(0,0,0,0,0,0,0,0,0,0,0,0,0,0,0,0,0,0,0,0,0,BH5,0,0,0,0,0,0,0,0~
)';
      PINUSE='POWER';
      NO_LOAD_CHECK='Both';
      NO_IO_CHECK='Both';
      NO_ASSERT_CHECK='TRUE';
      NO_DIR_CHECK='TRUE';
      ALLOW_CONNECT='TRUE';
    'VCCSA'<25>:
      PIN_NUMBER='(0,0,0,0,0,0,0,0,0,0,0,0,0,0,0,0,0,0,0,0,CB65,0,0,0,0,0,0,0,0,~
0)';
      PINUSE='POWER';
      NO_LOAD_CHECK='Both';
      NO_IO_CHECK='Both';
      NO_ASSERT_CHECK='TRUE';
      NO_DIR_CHECK='TRUE';
      ALLOW_CONNECT='TRUE';
    'VCCSA'<24>:
      PIN_NUMBER='(0,0,0,0,0,0,0,0,0,0,0,0,0,0,0,0,0,0,0,0,CB67,0,0,0,0,0,0,0,0,~
0)';
      PINUSE='POWER';
      NO_LOAD_CHECK='Both';
      NO_IO_CHECK='Both';
      NO_ASSERT_CHECK='TRUE';
      NO_DIR_CHECK='TRUE';
      ALLOW_CONNECT='TRUE';
    'VCCSA'<23>:
      PIN_NUMBER='(0,0,0,0,0,0,0,0,0,0,0,0,0,0,0,0,0,0,0,0,CB69,0,0,0,0,0,0,0,0,~
0)';
      PINUSE='POWER';
      NO_LOAD_CHECK='Both';
      NO_IO_CHECK='Both';
      NO_ASSERT_CHECK='TRUE';
      NO_DIR_CHECK='TRUE';
      ALLOW_CONNECT='TRUE';
    'VCCSA'<22>:
      PIN_NUMBER='(0,0,0,0,0,0,0,0,0,0,0,0,0,0,0,0,0,0,0,0,CC66,0,0,0,0,0,0,0,0,~
0)';
      PINUSE='POWER';
      NO_LOAD_CHECK='Both';
      NO_IO_CHECK='Both';
      NO_ASSERT_CHECK='TRUE';
      NO_DIR_CHECK='TRUE';
      ALLOW_CONNECT='TRUE';
    'VCCSA'<21>:
      PIN_NUMBER='(0,0,0,0,0,0,0,0,0,0,0,0,0,0,0,0,0,0,0,0,CC68,0,0,0,0,0,0,0,0,~
0)';
      PINUSE='POWER';
      NO_LOAD_CHECK='Both';
      NO_IO_CHECK='Both';
      NO_ASSERT_CHECK='TRUE';
      NO_DIR_CHECK='TRUE';
      ALLOW_CONNECT='TRUE';
    'VCCSA'<20>:
      PIN_NUMBER='(0,0,0,0,0,0,0,0,0,0,0,0,0,0,0,0,0,0,0,0,CC70,0,0,0,0,0,0,0,0,~
0)';
      PINUSE='POWER';
      NO_LOAD_CHECK='Both';
      NO_IO_CHECK='Both';
      NO_ASSERT_CHECK='TRUE';
      NO_DIR_CHECK='TRUE';
      ALLOW_CONNECT='TRUE';
    'VCCSA'<19>:
      PIN_NUMBER='(0,0,0,0,0,0,0,0,0,0,0,0,0,0,0,0,0,0,0,0,CD65,0,0,0,0,0,0,0,0,~
0)';
      PINUSE='POWER';
      NO_LOAD_CHECK='Both';
      NO_IO_CHECK='Both';
      NO_ASSERT_CHECK='TRUE';
      NO_DIR_CHECK='TRUE';
      ALLOW_CONNECT='TRUE';
    'VCCSA'<18>:
      PIN_NUMBER='(0,0,0,0,0,0,0,0,0,0,0,0,0,0,0,0,0,0,0,0,CD67,0,0,0,0,0,0,0,0,~
0)';
      PINUSE='POWER';
      NO_LOAD_CHECK='Both';
      NO_IO_CHECK='Both';
      NO_ASSERT_CHECK='TRUE';
      NO_DIR_CHECK='TRUE';
      ALLOW_CONNECT='TRUE';
    'VCCSA'<17>:
      PIN_NUMBER='(0,0,0,0,0,0,0,0,0,0,0,0,0,0,0,0,0,0,0,0,CD69,0,0,0,0,0,0,0,0,~
0)';
      PINUSE='POWER';
      NO_LOAD_CHECK='Both';
      NO_IO_CHECK='Both';
      NO_ASSERT_CHECK='TRUE';
      NO_DIR_CHECK='TRUE';
      ALLOW_CONNECT='TRUE';
    'VCCSA'<16>:
      PIN_NUMBER='(0,0,0,0,0,0,0,0,0,0,0,0,0,0,0,0,0,0,0,0,CD71,0,0,0,0,0,0,0,0,~
0)';
      PINUSE='POWER';
      NO_LOAD_CHECK='Both';
      NO_IO_CHECK='Both';
      NO_ASSERT_CHECK='TRUE';
      NO_DIR_CHECK='TRUE';
      ALLOW_CONNECT='TRUE';
    'VCCSA'<15>:
      PIN_NUMBER='(0,0,0,0,0,0,0,0,0,0,0,0,0,0,0,0,0,0,0,0,CE64,0,0,0,0,0,0,0,0,~
0)';
      PINUSE='POWER';
      NO_LOAD_CHECK='Both';
      NO_IO_CHECK='Both';
      NO_ASSERT_CHECK='TRUE';
      NO_DIR_CHECK='TRUE';
      ALLOW_CONNECT='TRUE';
    'VCCSA'<14>:
      PIN_NUMBER='(0,0,0,0,0,0,0,0,0,0,0,0,0,0,0,0,0,0,0,0,CE66,0,0,0,0,0,0,0,0,~
0)';
      PINUSE='POWER';
      NO_LOAD_CHECK='Both';
      NO_IO_CHECK='Both';
      NO_ASSERT_CHECK='TRUE';
      NO_DIR_CHECK='TRUE';
      ALLOW_CONNECT='TRUE';
    'VCCSA'<13>:
      PIN_NUMBER='(0,0,0,0,0,0,0,0,0,0,0,0,0,0,0,0,0,0,0,0,CE68,0,0,0,0,0,0,0,0,~
0)';
      PINUSE='POWER';
      NO_LOAD_CHECK='Both';
      NO_IO_CHECK='Both';
      NO_ASSERT_CHECK='TRUE';
      NO_DIR_CHECK='TRUE';
      ALLOW_CONNECT='TRUE';
    'VCCSA'<12>:
      PIN_NUMBER='(0,0,0,0,0,0,0,0,0,0,0,0,0,0,0,0,0,0,0,0,CE72,0,0,0,0,0,0,0,0,~
0)';
      PINUSE='POWER';
      NO_LOAD_CHECK='Both';
      NO_IO_CHECK='Both';
      NO_ASSERT_CHECK='TRUE';
      NO_DIR_CHECK='TRUE';
      ALLOW_CONNECT='TRUE';
    'VCCSA'<11>:
      PIN_NUMBER='(0,0,0,0,0,0,0,0,0,0,0,0,0,0,0,0,0,0,0,0,CE74,0,0,0,0,0,0,0,0,~
0)';
      PINUSE='POWER';
      NO_LOAD_CHECK='Both';
      NO_IO_CHECK='Both';
      NO_ASSERT_CHECK='TRUE';
      NO_DIR_CHECK='TRUE';
      ALLOW_CONNECT='TRUE';
    'VCCSA'<10>:
      PIN_NUMBER='(0,0,0,0,0,0,0,0,0,0,0,0,0,0,0,0,0,0,0,0,CF65,0,0,0,0,0,0,0,0,~
0)';
      PINUSE='POWER';
      NO_LOAD_CHECK='Both';
      NO_IO_CHECK='Both';
      NO_ASSERT_CHECK='TRUE';
      NO_DIR_CHECK='TRUE';
      ALLOW_CONNECT='TRUE';
    'VCCSA'<9>:
      PIN_NUMBER='(0,0,0,0,0,0,0,0,0,0,0,0,0,0,0,0,0,0,0,0,CF67,0,0,0,0,0,0,0,0,~
0)';
      PINUSE='POWER';
      NO_LOAD_CHECK='Both';
      NO_IO_CHECK='Both';
      NO_ASSERT_CHECK='TRUE';
      NO_DIR_CHECK='TRUE';
      ALLOW_CONNECT='TRUE';
    'VCCSA'<8>:
      PIN_NUMBER='(0,0,0,0,0,0,0,0,0,0,0,0,0,0,0,0,0,0,0,0,CF73,0,0,0,0,0,0,0,0,~
0)';
      PINUSE='POWER';
      NO_LOAD_CHECK='Both';
      NO_IO_CHECK='Both';
      NO_ASSERT_CHECK='TRUE';
      NO_DIR_CHECK='TRUE';
      ALLOW_CONNECT='TRUE';
    'VCCSA'<7>:
      PIN_NUMBER='(0,0,0,0,0,0,0,0,0,0,0,0,0,0,0,0,0,0,0,0,CF75,0,0,0,0,0,0,0,0,~
0)';
      PINUSE='POWER';
      NO_LOAD_CHECK='Both';
      NO_IO_CHECK='Both';
      NO_ASSERT_CHECK='TRUE';
      NO_DIR_CHECK='TRUE';
      ALLOW_CONNECT='TRUE';
    'VCCSA'<6>:
      PIN_NUMBER='(0,0,0,0,0,0,0,0,0,0,0,0,0,0,0,0,0,0,0,0,CG64,0,0,0,0,0,0,0,0,~
0)';
      PINUSE='POWER';
      NO_LOAD_CHECK='Both';
      NO_IO_CHECK='Both';
      NO_ASSERT_CHECK='TRUE';
      NO_DIR_CHECK='TRUE';
      ALLOW_CONNECT='TRUE';
    'VCCSA'<5>:
      PIN_NUMBER='(0,0,0,0,0,0,0,0,0,0,0,0,0,0,0,0,0,0,0,0,CG66,0,0,0,0,0,0,0,0,~
0)';
      PINUSE='POWER';
      NO_LOAD_CHECK='Both';
      NO_IO_CHECK='Both';
      NO_ASSERT_CHECK='TRUE';
      NO_DIR_CHECK='TRUE';
      ALLOW_CONNECT='TRUE';
    'VCCSA'<4>:
      PIN_NUMBER='(0,0,0,0,0,0,0,0,0,0,0,0,0,0,0,0,0,0,0,0,CG74,0,0,0,0,0,0,0,0,~
0)';
      PINUSE='POWER';
      NO_LOAD_CHECK='Both';
      NO_IO_CHECK='Both';
      NO_ASSERT_CHECK='TRUE';
      NO_DIR_CHECK='TRUE';
      ALLOW_CONNECT='TRUE';
    'VCCSA'<3>:
      PIN_NUMBER='(0,0,0,0,0,0,0,0,0,0,0,0,0,0,0,0,0,0,0,0,CH65,0,0,0,0,0,0,0,0,~
0)';
      PINUSE='POWER';
      NO_LOAD_CHECK='Both';
      NO_IO_CHECK='Both';
      NO_ASSERT_CHECK='TRUE';
      NO_DIR_CHECK='TRUE';
      ALLOW_CONNECT='TRUE';
    'VCCSA'<2>:
      PIN_NUMBER='(0,0,0,0,0,0,0,0,0,0,0,0,0,0,0,0,0,0,0,0,CH75,0,0,0,0,0,0,0,0,~
0)';
      PINUSE='POWER';
      NO_LOAD_CHECK='Both';
      NO_IO_CHECK='Both';
      NO_ASSERT_CHECK='TRUE';
      NO_DIR_CHECK='TRUE';
      ALLOW_CONNECT='TRUE';
    'VCCSA'<1>:
      PIN_NUMBER='(0,0,0,0,0,0,0,0,0,0,0,0,0,0,0,0,0,0,0,0,CJ64,0,0,0,0,0,0,0,0,~
0)';
      PINUSE='POWER';
      NO_LOAD_CHECK='Both';
      NO_IO_CHECK='Both';
      NO_ASSERT_CHECK='TRUE';
      NO_DIR_CHECK='TRUE';
      ALLOW_CONNECT='TRUE';
    'VCCSA'<0>:
      PIN_NUMBER='(0,0,0,0,0,0,0,0,0,0,0,0,0,0,0,0,0,0,0,0,CJ66,0,0,0,0,0,0,0,0,~
0)';
      PINUSE='POWER';
      NO_LOAD_CHECK='Both';
      NO_IO_CHECK='Both';
      NO_ASSERT_CHECK='TRUE';
      NO_DIR_CHECK='TRUE';
      ALLOW_CONNECT='TRUE';
    'VCCSA_SENSE':
      PIN_NUMBER='(0,0,0,0,0,0,0,0,0,0,0,0,0,0,0,0,0,0,0,0,0,CE76,0,0,0,0,0,0,0,~
0)';
      PINUSE='POWER';
      NO_LOAD_CHECK='Both';
      NO_IO_CHECK='Both';
      NO_ASSERT_CHECK='TRUE';
      NO_DIR_CHECK='TRUE';
      ALLOW_CONNECT='TRUE';
    'VSENSEPMAX':
      PIN_NUMBER='(0,0,0,0,0,0,0,0,0,0,0,0,0,0,0,0,0,0,AD41,0,0,0,0,0,0,0,0,0,0,~
0)';
      PINUSE='POWER';
      NO_LOAD_CHECK='Both';
      NO_IO_CHECK='Both';
      NO_ASSERT_CHECK='TRUE';
      NO_DIR_CHECK='TRUE';
      ALLOW_CONNECT='TRUE';
    'VSS'<1253>:
      PIN_NUMBER='(0,0,0,0,0,0,0,0,0,0,0,0,0,0,0,0,0,0,0,0,0,0,B9,0,0,0,0,0,0,0)~
';
      PINUSE='GROUND';
      NO_LOAD_CHECK='Both';
      NO_IO_CHECK='Both';
      NO_ASSERT_CHECK='TRUE';
      NO_DIR_CHECK='TRUE';
      ALLOW_CONNECT='TRUE';
    'VSS'<1252>:
      PIN_NUMBER='(0,0,0,0,0,0,0,0,0,0,0,0,0,0,0,0,0,0,0,0,0,0,A42,0,0,0,0,0,0,0~
)';
      PINUSE='GROUND';
      NO_LOAD_CHECK='Both';
      NO_IO_CHECK='Both';
      NO_ASSERT_CHECK='TRUE';
      NO_DIR_CHECK='TRUE';
      ALLOW_CONNECT='TRUE';
    'VSS'<1251>:
      PIN_NUMBER='(0,0,0,0,0,0,0,0,0,0,0,0,0,0,0,0,0,0,0,0,0,0,B43,0,0,0,0,0,0,0~
)';
      PINUSE='GROUND';
      NO_LOAD_CHECK='Both';
      NO_IO_CHECK='Both';
      NO_ASSERT_CHECK='TRUE';
      NO_DIR_CHECK='TRUE';
      ALLOW_CONNECT='TRUE';
    'VSS'<1250>:
      PIN_NUMBER='(0,0,0,0,0,0,0,0,0,0,0,0,0,0,0,0,0,0,0,0,0,0,B5,0,0,0,0,0,0,0)~
';
      PINUSE='GROUND';
      NO_LOAD_CHECK='Both';
      NO_IO_CHECK='Both';
      NO_ASSERT_CHECK='TRUE';
      NO_DIR_CHECK='TRUE';
      ALLOW_CONNECT='TRUE';
    'VSS'<1249>:
      PIN_NUMBER='(0,0,0,0,0,0,0,0,0,0,0,0,0,0,0,0,0,0,0,0,0,0,B79,0,0,0,0,0,0,0~
)';
      PINUSE='GROUND';
      NO_LOAD_CHECK='Both';
      NO_IO_CHECK='Both';
      NO_ASSERT_CHECK='TRUE';
      NO_DIR_CHECK='TRUE';
      ALLOW_CONNECT='TRUE';
    'VSS'<1248>:
      PIN_NUMBER='(0,0,0,0,0,0,0,0,0,0,0,0,0,0,0,0,0,0,0,0,0,0,C4,0,0,0,0,0,0,0)~
';
      PINUSE='GROUND';
      NO_LOAD_CHECK='Both';
      NO_IO_CHECK='Both';
      NO_ASSERT_CHECK='TRUE';
      NO_DIR_CHECK='TRUE';
      ALLOW_CONNECT='TRUE';
    'VSS'<1247>:
      PIN_NUMBER='(0,0,0,0,0,0,0,0,0,0,0,0,0,0,0,0,0,0,0,0,0,0,C80,0,0,0,0,0,0,0~
)';
      PINUSE='GROUND';
      NO_LOAD_CHECK='Both';
      NO_IO_CHECK='Both';
      NO_ASSERT_CHECK='TRUE';
      NO_DIR_CHECK='TRUE';
      ALLOW_CONNECT='TRUE';
    'VSS'<1246>:
      PIN_NUMBER='(0,0,0,0,0,0,0,0,0,0,0,0,0,0,0,0,0,0,0,0,0,0,D3,0,0,0,0,0,0,0)~
';
      PINUSE='GROUND';
      NO_LOAD_CHECK='Both';
      NO_IO_CHECK='Both';
      NO_ASSERT_CHECK='TRUE';
      NO_DIR_CHECK='TRUE';
      ALLOW_CONNECT='TRUE';
    'VSS'<1245>:
      PIN_NUMBER='(0,0,0,0,0,0,0,0,0,0,0,0,0,0,0,0,0,0,0,0,0,0,D81,0,0,0,0,0,0,0~
)';
      PINUSE='GROUND';
      NO_LOAD_CHECK='Both';
      NO_IO_CHECK='Both';
      NO_ASSERT_CHECK='TRUE';
      NO_DIR_CHECK='TRUE';
      ALLOW_CONNECT='TRUE';
    'VSS'<1244>:
      PIN_NUMBER='(0,0,0,0,0,0,0,0,0,0,0,0,0,0,0,0,0,0,0,0,0,0,E82,0,0,0,0,0,0,0~
)';
      PINUSE='GROUND';
      NO_LOAD_CHECK='Both';
      NO_IO_CHECK='Both';
      NO_ASSERT_CHECK='TRUE';
      NO_DIR_CHECK='TRUE';
      ALLOW_CONNECT='TRUE';
    'VSS'<1243>:
      PIN_NUMBER='(0,0,0,0,0,0,0,0,0,0,0,0,0,0,0,0,0,0,0,0,0,0,J86,0,0,0,0,0,0,0~
)';
      PINUSE='GROUND';
      NO_LOAD_CHECK='Both';
      NO_IO_CHECK='Both';
      NO_ASSERT_CHECK='TRUE';
      NO_DIR_CHECK='TRUE';
      ALLOW_CONNECT='TRUE';
    'VSS'<1242>:
      PIN_NUMBER='(0,0,0,0,0,0,0,0,0,0,0,0,0,0,0,0,0,0,0,0,0,0,DY85,0,0,0,0,0,0,~
0)';
      PINUSE='GROUND';
      NO_LOAD_CHECK='Both';
      NO_IO_CHECK='Both';
      NO_ASSERT_CHECK='TRUE';
      NO_DIR_CHECK='TRUE';
      ALLOW_CONNECT='TRUE';
    'VSS'<1241>:
      PIN_NUMBER='(0,0,0,0,0,0,0,0,0,0,0,0,0,0,0,0,0,0,0,0,0,0,EA84,0,0,0,0,0,0,~
0)';
      PINUSE='GROUND';
      NO_LOAD_CHECK='Both';
      NO_IO_CHECK='Both';
      NO_ASSERT_CHECK='TRUE';
      NO_DIR_CHECK='TRUE';
      ALLOW_CONNECT='TRUE';
    'VSS'<1240>:
      PIN_NUMBER='(0,0,0,0,0,0,0,0,0,0,0,0,0,0,0,0,0,0,0,0,0,0,EB83,0,0,0,0,0,0,~
0)';
      PINUSE='GROUND';
      NO_LOAD_CHECK='Both';
      NO_IO_CHECK='Both';
      NO_ASSERT_CHECK='TRUE';
      NO_DIR_CHECK='TRUE';
      ALLOW_CONNECT='TRUE';
    'VSS'<1239>:
      PIN_NUMBER='(0,0,0,0,0,0,0,0,0,0,0,0,0,0,0,0,0,0,0,0,0,0,DW2,0,0,0,0,0,0,0~
)';
      PINUSE='GROUND';
      NO_LOAD_CHECK='Both';
      NO_IO_CHECK='Both';
      NO_ASSERT_CHECK='TRUE';
      NO_DIR_CHECK='TRUE';
      ALLOW_CONNECT='TRUE';
    'VSS'<1238>:
      PIN_NUMBER='(0,0,0,0,0,0,0,0,0,0,0,0,0,0,0,0,0,0,0,0,0,0,EC42,0,0,0,0,0,0,~
0)';
      PINUSE='GROUND';
      NO_LOAD_CHECK='Both';
      NO_IO_CHECK='Both';
      NO_ASSERT_CHECK='TRUE';
      NO_DIR_CHECK='TRUE';
      ALLOW_CONNECT='TRUE';
    'VSS'<1237>:
      PIN_NUMBER='(0,0,0,0,0,0,0,0,0,0,0,0,0,0,0,0,0,0,0,0,0,0,EC6,0,0,0,0,0,0,0~
)';
      PINUSE='GROUND';
      NO_LOAD_CHECK='Both';
      NO_IO_CHECK='Both';
      NO_ASSERT_CHECK='TRUE';
      NO_DIR_CHECK='TRUE';
      ALLOW_CONNECT='TRUE';
    'VSS'<1236>:
      PIN_NUMBER='(0,0,0,0,0,0,0,0,0,0,0,0,0,0,0,0,0,0,0,0,0,0,EC82,0,0,0,0,0,0,~
0)';
      PINUSE='GROUND';
      NO_LOAD_CHECK='Both';
      NO_IO_CHECK='Both';
      NO_ASSERT_CHECK='TRUE';
      NO_DIR_CHECK='TRUE';
      ALLOW_CONNECT='TRUE';
    'VSS'<1235>:
      PIN_NUMBER='(0,0,0,0,0,0,0,0,0,0,0,0,0,0,0,0,0,0,0,0,0,0,ED41,0,0,0,0,0,0,~
0)';
      PINUSE='GROUND';
      NO_LOAD_CHECK='Both';
      NO_IO_CHECK='Both';
      NO_ASSERT_CHECK='TRUE';
      NO_DIR_CHECK='TRUE';
      ALLOW_CONNECT='TRUE';
    'VSS'<1234>:
      PIN_NUMBER='(0,0,0,0,0,0,0,0,0,0,0,0,0,0,0,0,0,0,0,0,0,0,ED7,0,0,0,0,0,0,0~
)';
      PINUSE='GROUND';
      NO_LOAD_CHECK='Both';
      NO_IO_CHECK='Both';
      NO_ASSERT_CHECK='TRUE';
      NO_DIR_CHECK='TRUE';
      ALLOW_CONNECT='TRUE';
    'VSS'<1233>:
      PIN_NUMBER='(0,0,0,0,0,0,0,0,0,0,0,0,0,0,0,0,0,0,0,0,0,0,ED81,0,0,0,0,0,0,~
0)';
      PINUSE='GROUND';
      NO_LOAD_CHECK='Both';
      NO_IO_CHECK='Both';
      NO_ASSERT_CHECK='TRUE';
      NO_DIR_CHECK='TRUE';
      ALLOW_CONNECT='TRUE';
    'VSS'<1232>:
      PIN_NUMBER='(0,0,0,0,0,0,0,0,0,0,0,0,0,0,0,0,0,0,0,0,0,0,EE40,0,0,0,0,0,0,~
0)';
      PINUSE='GROUND';
      NO_LOAD_CHECK='Both';
      NO_IO_CHECK='Both';
      NO_ASSERT_CHECK='TRUE';
      NO_DIR_CHECK='TRUE';
      ALLOW_CONNECT='TRUE';
    'VSS'<1231>:
      PIN_NUMBER='(0,0,0,0,0,0,0,0,0,0,0,0,0,0,0,0,0,0,0,0,0,0,EE8,0,0,0,0,0,0,0~
)';
      PINUSE='GROUND';
      NO_LOAD_CHECK='Both';
      NO_IO_CHECK='Both';
      NO_ASSERT_CHECK='TRUE';
      NO_DIR_CHECK='TRUE';
      ALLOW_CONNECT='TRUE';
    'VSS'<1230>:
      PIN_NUMBER='(0,0,0,0,0,0,0,0,0,0,0,0,0,0,0,0,0,0,0,0,0,0,EE80,0,0,0,0,0,0,~
0)';
      PINUSE='GROUND';
      NO_LOAD_CHECK='Both';
      NO_IO_CHECK='Both';
      NO_ASSERT_CHECK='TRUE';
      NO_DIR_CHECK='TRUE';
      ALLOW_CONNECT='TRUE';
    'VSS'<1229>:
      PIN_NUMBER='(0,0,0,0,0,0,0,0,0,0,0,0,0,0,0,0,0,0,0,0,0,0,ED69,0,0,0,0,0,0,~
0)';
      PINUSE='GROUND';
      NO_LOAD_CHECK='Both';
      NO_IO_CHECK='Both';
      NO_ASSERT_CHECK='TRUE';
      NO_DIR_CHECK='TRUE';
      ALLOW_CONNECT='TRUE';
    'VSS'<1228>:
      PIN_NUMBER='(0,0,0,0,0,0,0,0,0,0,0,0,0,0,0,0,0,0,0,0,0,0,E66,0,0,0,0,0,0,0~
)';
      PINUSE='GROUND';
      NO_LOAD_CHECK='Both';
      NO_IO_CHECK='Both';
      NO_ASSERT_CHECK='TRUE';
      NO_DIR_CHECK='TRUE';
      ALLOW_CONNECT='TRUE';
    'VSS'<1227>:
      PIN_NUMBER='(0,0,0,0,0,0,0,0,0,0,0,0,0,0,0,0,0,0,0,0,0,0,V11,0,0,0,0,0,0,0~
)';
      PINUSE='GROUND';
      NO_LOAD_CHECK='Both';
      NO_IO_CHECK='Both';
      NO_ASSERT_CHECK='TRUE';
      NO_DIR_CHECK='TRUE';
      ALLOW_CONNECT='TRUE';
    'VSS'<1226>:
      PIN_NUMBER='(0,0,0,0,0,0,0,0,0,0,0,0,0,0,0,0,0,0,0,0,0,0,L8,0,0,0,0,0,0,0)~
';
      PINUSE='GROUND';
      NO_LOAD_CHECK='Both';
      NO_IO_CHECK='Both';
      NO_ASSERT_CHECK='TRUE';
      NO_DIR_CHECK='TRUE';
      ALLOW_CONNECT='TRUE';
    'VSS'<1225>:
      PIN_NUMBER='(0,0,0,0,0,0,0,0,0,0,0,0,0,0,0,0,0,0,0,0,0,0,EA14,0,0,0,0,0,0,~
0)';
      PINUSE='GROUND';
      NO_LOAD_CHECK='Both';
      NO_IO_CHECK='Both';
      NO_ASSERT_CHECK='TRUE';
      NO_DIR_CHECK='TRUE';
      ALLOW_CONNECT='TRUE';
    'VSS'<1224>:
      PIN_NUMBER='(0,0,0,0,0,0,0,0,0,0,0,0,0,0,0,0,0,0,0,0,0,0,DY63,0,0,0,0,0,0,~
0)';
      PINUSE='GROUND';
      NO_LOAD_CHECK='Both';
      NO_IO_CHECK='Both';
      NO_ASSERT_CHECK='TRUE';
      NO_DIR_CHECK='TRUE';
      ALLOW_CONNECT='TRUE';
    'VSS'<1223>:
      PIN_NUMBER='(0,0,0,0,0,0,0,0,0,0,0,0,0,0,0,0,0,0,0,0,0,0,DY61,0,0,0,0,0,0,~
0)';
      PINUSE='GROUND';
      NO_LOAD_CHECK='Both';
      NO_IO_CHECK='Both';
      NO_ASSERT_CHECK='TRUE';
      NO_DIR_CHECK='TRUE';
      ALLOW_CONNECT='TRUE';
    'VSS'<1222>:
      PIN_NUMBER='(0,0,0,0,0,0,0,0,0,0,0,0,0,0,0,0,0,0,0,0,0,0,DY59,0,0,0,0,0,0,~
0)';
      PINUSE='GROUND';
      NO_LOAD_CHECK='Both';
      NO_IO_CHECK='Both';
      NO_ASSERT_CHECK='TRUE';
      NO_DIR_CHECK='TRUE';
      ALLOW_CONNECT='TRUE';
    'VSS'<1221>:
      PIN_NUMBER='(0,0,0,0,0,0,0,0,0,0,0,0,0,0,0,0,0,0,0,0,0,0,DY57,0,0,0,0,0,0,~
0)';
      PINUSE='GROUND';
      NO_LOAD_CHECK='Both';
      NO_IO_CHECK='Both';
      NO_ASSERT_CHECK='TRUE';
      NO_DIR_CHECK='TRUE';
      ALLOW_CONNECT='TRUE';
    'VSS'<1220>:
      PIN_NUMBER='(0,0,0,0,0,0,0,0,0,0,0,0,0,0,0,0,0,0,0,0,0,0,DY55,0,0,0,0,0,0,~
0)';
      PINUSE='GROUND';
      NO_LOAD_CHECK='Both';
      NO_IO_CHECK='Both';
      NO_ASSERT_CHECK='TRUE';
      NO_DIR_CHECK='TRUE';
      ALLOW_CONNECT='TRUE';
    'VSS'<1219>:
      PIN_NUMBER='(0,0,0,0,0,0,0,0,0,0,0,0,0,0,0,0,0,0,0,0,0,0,DY53,0,0,0,0,0,0,~
0)';
      PINUSE='GROUND';
      NO_LOAD_CHECK='Both';
      NO_IO_CHECK='Both';
      NO_ASSERT_CHECK='TRUE';
      NO_DIR_CHECK='TRUE';
      ALLOW_CONNECT='TRUE';
    'VSS'<1218>:
      PIN_NUMBER='(0,0,0,0,0,0,0,0,0,0,0,0,0,0,0,0,0,0,0,0,0,0,DY51,0,0,0,0,0,0,~
0)';
      PINUSE='GROUND';
      NO_LOAD_CHECK='Both';
      NO_IO_CHECK='Both';
      NO_ASSERT_CHECK='TRUE';
      NO_DIR_CHECK='TRUE';
      ALLOW_CONNECT='TRUE';
    'VSS'<1217>:
      PIN_NUMBER='(0,0,0,0,0,0,0,0,0,0,0,0,0,0,0,0,0,0,0,0,0,0,DY49,0,0,0,0,0,0,~
0)';
      PINUSE='GROUND';
      NO_LOAD_CHECK='Both';
      NO_IO_CHECK='Both';
      NO_ASSERT_CHECK='TRUE';
      NO_DIR_CHECK='TRUE';
      ALLOW_CONNECT='TRUE';
    'VSS'<1216>:
      PIN_NUMBER='(0,0,0,0,0,0,0,0,0,0,0,0,0,0,0,0,0,0,0,0,0,0,DY47,0,0,0,0,0,0,~
0)';
      PINUSE='GROUND';
      NO_LOAD_CHECK='Both';
      NO_IO_CHECK='Both';
      NO_ASSERT_CHECK='TRUE';
      NO_DIR_CHECK='TRUE';
      ALLOW_CONNECT='TRUE';
    'VSS'<1215>:
      PIN_NUMBER='(0,0,0,0,0,0,0,0,0,0,0,0,0,0,0,0,0,0,0,0,0,0,DY45,0,0,0,0,0,0,~
0)';
      PINUSE='GROUND';
      NO_LOAD_CHECK='Both';
      NO_IO_CHECK='Both';
      NO_ASSERT_CHECK='TRUE';
      NO_DIR_CHECK='TRUE';
      ALLOW_CONNECT='TRUE';
    'VSS'<1214>:
      PIN_NUMBER='(0,0,0,0,0,0,0,0,0,0,0,0,0,0,0,0,0,0,0,0,0,0,DV19,0,0,0,0,0,0,~
0)';
      PINUSE='GROUND';
      NO_LOAD_CHECK='Both';
      NO_IO_CHECK='Both';
      NO_ASSERT_CHECK='TRUE';
      NO_DIR_CHECK='TRUE';
      ALLOW_CONNECT='TRUE';
    'VSS'<1213>:
      PIN_NUMBER='(0,0,0,0,0,0,0,0,0,0,0,0,0,0,0,0,0,0,0,0,0,0,DP9,0,0,0,0,0,0,0~
)';
      PINUSE='GROUND';
      NO_LOAD_CHECK='Both';
      NO_IO_CHECK='Both';
      NO_ASSERT_CHECK='TRUE';
      NO_DIR_CHECK='TRUE';
      ALLOW_CONNECT='TRUE';
    'VSS'<1212>:
      PIN_NUMBER='(0,0,0,0,0,0,0,0,0,0,0,0,0,0,0,0,0,0,0,0,0,0,DP63,0,0,0,0,0,0,~
0)';
      PINUSE='GROUND';
      NO_LOAD_CHECK='Both';
      NO_IO_CHECK='Both';
      NO_ASSERT_CHECK='TRUE';
      NO_DIR_CHECK='TRUE';
      ALLOW_CONNECT='TRUE';
    'VSS'<1211>:
      PIN_NUMBER='(0,0,0,0,0,0,0,0,0,0,0,0,0,0,0,0,0,0,0,0,0,0,DP61,0,0,0,0,0,0,~
0)';
      PINUSE='GROUND';
      NO_LOAD_CHECK='Both';
      NO_IO_CHECK='Both';
      NO_ASSERT_CHECK='TRUE';
      NO_DIR_CHECK='TRUE';
      ALLOW_CONNECT='TRUE';
    'VSS'<1210>:
      PIN_NUMBER='(0,0,0,0,0,0,0,0,0,0,0,0,0,0,0,0,0,0,0,0,0,0,DP59,0,0,0,0,0,0,~
0)';
      PINUSE='GROUND';
      NO_LOAD_CHECK='Both';
      NO_IO_CHECK='Both';
      NO_ASSERT_CHECK='TRUE';
      NO_DIR_CHECK='TRUE';
      ALLOW_CONNECT='TRUE';
    'VSS'<1209>:
      PIN_NUMBER='(0,0,0,0,0,0,0,0,0,0,0,0,0,0,0,0,0,0,0,0,0,0,DP57,0,0,0,0,0,0,~
0)';
      PINUSE='GROUND';
      NO_LOAD_CHECK='Both';
      NO_IO_CHECK='Both';
      NO_ASSERT_CHECK='TRUE';
      NO_DIR_CHECK='TRUE';
      ALLOW_CONNECT='TRUE';
    'VSS'<1208>:
      PIN_NUMBER='(0,0,0,0,0,0,0,0,0,0,0,0,0,0,0,0,0,0,0,0,0,0,DP55,0,0,0,0,0,0,~
0)';
      PINUSE='GROUND';
      NO_LOAD_CHECK='Both';
      NO_IO_CHECK='Both';
      NO_ASSERT_CHECK='TRUE';
      NO_DIR_CHECK='TRUE';
      ALLOW_CONNECT='TRUE';
    'VSS'<1207>:
      PIN_NUMBER='(0,0,0,0,0,0,0,0,0,0,0,0,0,0,0,0,0,0,0,0,0,0,DP53,0,0,0,0,0,0,~
0)';
      PINUSE='GROUND';
      NO_LOAD_CHECK='Both';
      NO_IO_CHECK='Both';
      NO_ASSERT_CHECK='TRUE';
      NO_DIR_CHECK='TRUE';
      ALLOW_CONNECT='TRUE';
    'VSS'<1206>:
      PIN_NUMBER='(0,0,0,0,0,0,0,0,0,0,0,0,0,0,0,0,0,0,0,0,0,0,DP51,0,0,0,0,0,0,~
0)';
      PINUSE='GROUND';
      NO_LOAD_CHECK='Both';
      NO_IO_CHECK='Both';
      NO_ASSERT_CHECK='TRUE';
      NO_DIR_CHECK='TRUE';
      ALLOW_CONNECT='TRUE';
    'VSS'<1205>:
      PIN_NUMBER='(0,0,0,0,0,0,0,0,0,0,0,0,0,0,0,0,0,0,0,0,0,0,DP49,0,0,0,0,0,0,~
0)';
      PINUSE='GROUND';
      NO_LOAD_CHECK='Both';
      NO_IO_CHECK='Both';
      NO_ASSERT_CHECK='TRUE';
      NO_DIR_CHECK='TRUE';
      ALLOW_CONNECT='TRUE';
    'VSS'<1204>:
      PIN_NUMBER='(0,0,0,0,0,0,0,0,0,0,0,0,0,0,0,0,0,0,0,0,0,0,DP47,0,0,0,0,0,0,~
0)';
      PINUSE='GROUND';
      NO_LOAD_CHECK='Both';
      NO_IO_CHECK='Both';
      NO_ASSERT_CHECK='TRUE';
      NO_DIR_CHECK='TRUE';
      ALLOW_CONNECT='TRUE';
    'VSS'<1203>:
      PIN_NUMBER='(0,0,0,0,0,0,0,0,0,0,0,0,0,0,0,0,0,0,0,0,0,0,DP45,0,0,0,0,0,0,~
0)';
      PINUSE='GROUND';
      NO_LOAD_CHECK='Both';
      NO_IO_CHECK='Both';
      NO_ASSERT_CHECK='TRUE';
      NO_DIR_CHECK='TRUE';
      ALLOW_CONNECT='TRUE';
    'VSS'<1202>:
      PIN_NUMBER='(0,0,0,0,0,0,0,0,0,0,0,0,0,0,0,0,0,0,0,0,0,0,DN18,0,0,0,0,0,0,~
0)';
      PINUSE='GROUND';
      NO_LOAD_CHECK='Both';
      NO_IO_CHECK='Both';
      NO_ASSERT_CHECK='TRUE';
      NO_DIR_CHECK='TRUE';
      ALLOW_CONNECT='TRUE';
    'VSS'<1201>:
      PIN_NUMBER='(0,0,0,0,0,0,0,0,0,0,0,0,0,0,0,0,0,0,0,0,0,0,DL8,0,0,0,0,0,0,0~
)';
      PINUSE='GROUND';
      NO_LOAD_CHECK='Both';
      NO_IO_CHECK='Both';
      NO_ASSERT_CHECK='TRUE';
      NO_DIR_CHECK='TRUE';
      ALLOW_CONNECT='TRUE';
    'VSS'<1200>:
      PIN_NUMBER='(0,0,0,0,0,0,0,0,0,0,0,0,0,0,0,0,0,0,0,0,0,0,DE62,0,0,0,0,0,0,~
0)';
      PINUSE='GROUND';
      NO_LOAD_CHECK='Both';
      NO_IO_CHECK='Both';
      NO_ASSERT_CHECK='TRUE';
      NO_DIR_CHECK='TRUE';
      ALLOW_CONNECT='TRUE';
    'VSS'<1199>:
      PIN_NUMBER='(0,0,0,0,0,0,0,0,0,0,0,0,0,0,0,0,0,0,0,0,0,0,DE60,0,0,0,0,0,0,~
0)';
      PINUSE='GROUND';
      NO_LOAD_CHECK='Both';
      NO_IO_CHECK='Both';
      NO_ASSERT_CHECK='TRUE';
      NO_DIR_CHECK='TRUE';
      ALLOW_CONNECT='TRUE';
    'VSS'<1198>:
      PIN_NUMBER='(0,0,0,0,0,0,0,0,0,0,0,0,0,0,0,0,0,0,0,0,0,0,DE58,0,0,0,0,0,0,~
0)';
      PINUSE='GROUND';
      NO_LOAD_CHECK='Both';
      NO_IO_CHECK='Both';
      NO_ASSERT_CHECK='TRUE';
      NO_DIR_CHECK='TRUE';
      ALLOW_CONNECT='TRUE';
    'VSS'<1197>:
      PIN_NUMBER='(0,0,0,0,0,0,0,0,0,0,0,0,0,0,0,0,0,0,0,0,0,0,DE56,0,0,0,0,0,0,~
0)';
      PINUSE='GROUND';
      NO_LOAD_CHECK='Both';
      NO_IO_CHECK='Both';
      NO_ASSERT_CHECK='TRUE';
      NO_DIR_CHECK='TRUE';
      ALLOW_CONNECT='TRUE';
    'VSS'<1196>:
      PIN_NUMBER='(0,0,0,0,0,0,0,0,0,0,0,0,0,0,0,0,0,0,0,0,0,0,DE54,0,0,0,0,0,0,~
0)';
      PINUSE='GROUND';
      NO_LOAD_CHECK='Both';
      NO_IO_CHECK='Both';
      NO_ASSERT_CHECK='TRUE';
      NO_DIR_CHECK='TRUE';
      ALLOW_CONNECT='TRUE';
    'VSS'<1195>:
      PIN_NUMBER='(0,0,0,0,0,0,0,0,0,0,0,0,0,0,0,0,0,0,0,0,0,0,DE52,0,0,0,0,0,0,~
0)';
      PINUSE='GROUND';
      NO_LOAD_CHECK='Both';
      NO_IO_CHECK='Both';
      NO_ASSERT_CHECK='TRUE';
      NO_DIR_CHECK='TRUE';
      ALLOW_CONNECT='TRUE';
    'VSS'<1194>:
      PIN_NUMBER='(0,0,0,0,0,0,0,0,0,0,0,0,0,0,0,0,0,0,0,0,0,0,DE50,0,0,0,0,0,0,~
0)';
      PINUSE='GROUND';
      NO_LOAD_CHECK='Both';
      NO_IO_CHECK='Both';
      NO_ASSERT_CHECK='TRUE';
      NO_DIR_CHECK='TRUE';
      ALLOW_CONNECT='TRUE';
    'VSS'<1193>:
      PIN_NUMBER='(0,0,0,0,0,0,0,0,0,0,0,0,0,0,0,0,0,0,0,0,0,0,DE48,0,0,0,0,0,0,~
0)';
      PINUSE='GROUND';
      NO_LOAD_CHECK='Both';
      NO_IO_CHECK='Both';
      NO_ASSERT_CHECK='TRUE';
      NO_DIR_CHECK='TRUE';
      ALLOW_CONNECT='TRUE';
    'VSS'<1192>:
      PIN_NUMBER='(0,0,0,0,0,0,0,0,0,0,0,0,0,0,0,0,0,0,0,0,0,0,CW6,0,0,0,0,0,0,0~
)';
      PINUSE='GROUND';
      NO_LOAD_CHECK='Both';
      NO_IO_CHECK='Both';
      NO_ASSERT_CHECK='TRUE';
      NO_DIR_CHECK='TRUE';
      ALLOW_CONNECT='TRUE';
    'VSS'<1191>:
      PIN_NUMBER='(0,0,0,0,0,0,0,0,0,0,0,0,0,0,0,0,0,0,0,0,0,0,CG6,0,0,0,0,0,0,0~
)';
      PINUSE='GROUND';
      NO_LOAD_CHECK='Both';
      NO_IO_CHECK='Both';
      NO_ASSERT_CHECK='TRUE';
      NO_DIR_CHECK='TRUE';
      ALLOW_CONNECT='TRUE';
    'VSS'<1190>:
      PIN_NUMBER='(0,0,0,0,0,0,0,0,0,0,0,0,0,0,0,0,0,0,0,0,0,0,AR6,0,0,0,0,0,0,0~
)';
      PINUSE='GROUND';
      NO_LOAD_CHECK='Both';
      NO_IO_CHECK='Both';
      NO_ASSERT_CHECK='TRUE';
      NO_DIR_CHECK='TRUE';
      ALLOW_CONNECT='TRUE';
    'VSS'<1189>:
      PIN_NUMBER='(0,0,0,0,0,0,0,0,0,0,0,0,0,0,0,0,0,0,0,0,0,0,AJ4,0,0,0,0,0,0,0~
)';
      PINUSE='GROUND';
      NO_LOAD_CHECK='Both';
      NO_IO_CHECK='Both';
      NO_ASSERT_CHECK='TRUE';
      NO_DIR_CHECK='TRUE';
      ALLOW_CONNECT='TRUE';
    'VSS'<1188>:
      PIN_NUMBER='(0,0,0,0,0,0,0,0,0,0,0,0,0,0,0,0,0,0,0,0,0,0,AC62,0,0,0,0,0,0,~
0)';
      PINUSE='GROUND';
      NO_LOAD_CHECK='Both';
      NO_IO_CHECK='Both';
      NO_ASSERT_CHECK='TRUE';
      NO_DIR_CHECK='TRUE';
      ALLOW_CONNECT='TRUE';
    'VSS'<1187>:
      PIN_NUMBER='(0,0,0,0,0,0,0,0,0,0,0,0,0,0,0,0,0,0,0,0,0,0,AC60,0,0,0,0,0,0,~
0)';
      PINUSE='GROUND';
      NO_LOAD_CHECK='Both';
      NO_IO_CHECK='Both';
      NO_ASSERT_CHECK='TRUE';
      NO_DIR_CHECK='TRUE';
      ALLOW_CONNECT='TRUE';
    'VSS'<1186>:
      PIN_NUMBER='(0,0,0,0,0,0,0,0,0,0,0,0,0,0,0,0,0,0,0,0,0,0,AC58,0,0,0,0,0,0,~
0)';
      PINUSE='GROUND';
      NO_LOAD_CHECK='Both';
      NO_IO_CHECK='Both';
      NO_ASSERT_CHECK='TRUE';
      NO_DIR_CHECK='TRUE';
      ALLOW_CONNECT='TRUE';
    'VSS'<1185>:
      PIN_NUMBER='(0,0,0,0,0,0,0,0,0,0,0,0,0,0,0,0,0,0,0,0,0,0,A26,0,0,0,0,0,0,0~
)';
      PINUSE='GROUND';
      NO_LOAD_CHECK='Both';
      NO_IO_CHECK='Both';
      NO_ASSERT_CHECK='TRUE';
      NO_DIR_CHECK='TRUE';
      ALLOW_CONNECT='TRUE';
    'VSS'<1184>:
      PIN_NUMBER='(0,0,0,0,0,0,0,0,0,0,0,0,0,0,0,0,0,0,0,0,0,0,A30,0,0,0,0,0,0,0~
)';
      PINUSE='GROUND';
      NO_LOAD_CHECK='Both';
      NO_IO_CHECK='Both';
      NO_ASSERT_CHECK='TRUE';
      NO_DIR_CHECK='TRUE';
      ALLOW_CONNECT='TRUE';
    'VSS'<1183>:
      PIN_NUMBER='(0,0,0,0,0,0,0,0,0,0,0,0,0,0,0,0,0,0,0,0,0,0,A32,0,0,0,0,0,0,0~
)';
      PINUSE='GROUND';
      NO_LOAD_CHECK='Both';
      NO_IO_CHECK='Both';
      NO_ASSERT_CHECK='TRUE';
      NO_DIR_CHECK='TRUE';
      ALLOW_CONNECT='TRUE';
    'VSS'<1182>:
      PIN_NUMBER='(0,0,0,0,0,0,0,0,0,0,0,0,0,0,0,0,0,0,0,0,0,0,A36,0,0,0,0,0,0,0~
)';
      PINUSE='GROUND';
      NO_LOAD_CHECK='Both';
      NO_IO_CHECK='Both';
      NO_ASSERT_CHECK='TRUE';
      NO_DIR_CHECK='TRUE';
      ALLOW_CONNECT='TRUE';
    'VSS'<1181>:
      PIN_NUMBER='(0,0,0,0,0,0,0,0,0,0,0,0,0,0,0,0,0,0,0,0,0,0,A38,0,0,0,0,0,0,0~
)';
      PINUSE='GROUND';
      NO_LOAD_CHECK='Both';
      NO_IO_CHECK='Both';
      NO_ASSERT_CHECK='TRUE';
      NO_DIR_CHECK='TRUE';
      ALLOW_CONNECT='TRUE';
    'VSS'<1180>:
      PIN_NUMBER='(0,0,0,0,0,0,0,0,0,0,0,0,0,0,0,0,0,0,0,0,0,0,B25,0,0,0,0,0,0,0~
)';
      PINUSE='GROUND';
      NO_LOAD_CHECK='Both';
      NO_IO_CHECK='Both';
      NO_ASSERT_CHECK='TRUE';
      NO_DIR_CHECK='TRUE';
      ALLOW_CONNECT='TRUE';
    'VSS'<1179>:
      PIN_NUMBER='(0,0,0,0,0,0,0,0,0,0,0,0,0,0,0,0,0,0,0,0,0,0,B31,0,0,0,0,0,0,0~
)';
      PINUSE='GROUND';
      NO_LOAD_CHECK='Both';
      NO_IO_CHECK='Both';
      NO_ASSERT_CHECK='TRUE';
      NO_DIR_CHECK='TRUE';
      ALLOW_CONNECT='TRUE';
    'VSS'<1178>:
      PIN_NUMBER='(0,0,0,0,0,0,0,0,0,0,0,0,0,0,0,0,0,0,0,0,0,0,B37,0,0,0,0,0,0,0~
)';
      PINUSE='GROUND';
      NO_LOAD_CHECK='Both';
      NO_IO_CHECK='Both';
      NO_ASSERT_CHECK='TRUE';
      NO_DIR_CHECK='TRUE';
      ALLOW_CONNECT='TRUE';
    'VSS'<1177>:
      PIN_NUMBER='(0,0,0,0,0,0,0,0,0,0,0,0,0,0,0,0,0,0,0,0,0,0,B71,0,0,0,0,0,0,0~
)';
      PINUSE='GROUND';
      NO_LOAD_CHECK='Both';
      NO_IO_CHECK='Both';
      NO_ASSERT_CHECK='TRUE';
      NO_DIR_CHECK='TRUE';
      ALLOW_CONNECT='TRUE';
    'VSS'<1176>:
      PIN_NUMBER='(0,0,0,0,0,0,0,0,0,0,0,0,0,0,0,0,0,0,0,0,0,0,B75,0,0,0,0,0,0,0~
)';
      PINUSE='GROUND';
      NO_LOAD_CHECK='Both';
      NO_IO_CHECK='Both';
      NO_ASSERT_CHECK='TRUE';
      NO_DIR_CHECK='TRUE';
      ALLOW_CONNECT='TRUE';
    'VSS'<1175>:
      PIN_NUMBER='(0,0,0,0,0,0,0,0,0,0,0,0,0,0,0,0,0,0,0,0,0,0,C8,0,0,0,0,0,0,0)~
';
      PINUSE='GROUND';
      NO_LOAD_CHECK='Both';
      NO_IO_CHECK='Both';
      NO_ASSERT_CHECK='TRUE';
      NO_DIR_CHECK='TRUE';
      ALLOW_CONNECT='TRUE';
    'VSS'<1174>:
      PIN_NUMBER='(0,0,0,0,0,0,0,0,0,0,0,0,0,0,0,0,0,0,0,0,0,0,C10,0,0,0,0,0,0,0~
)';
      PINUSE='GROUND';
      NO_LOAD_CHECK='Both';
      NO_IO_CHECK='Both';
      NO_ASSERT_CHECK='TRUE';
      NO_DIR_CHECK='TRUE';
      ALLOW_CONNECT='TRUE';
    'VSS'<1173>:
      PIN_NUMBER='(0,0,0,0,0,0,0,0,0,0,0,0,0,0,0,0,0,0,0,0,0,0,C12,0,0,0,0,0,0,0~
)';
      PINUSE='GROUND';
      NO_LOAD_CHECK='Both';
      NO_IO_CHECK='Both';
      NO_ASSERT_CHECK='TRUE';
      NO_DIR_CHECK='TRUE';
      ALLOW_CONNECT='TRUE';
    'VSS'<1172>:
      PIN_NUMBER='(0,0,0,0,0,0,0,0,0,0,0,0,0,0,0,0,0,0,0,0,0,0,C14,0,0,0,0,0,0,0~
)';
      PINUSE='GROUND';
      NO_LOAD_CHECK='Both';
      NO_IO_CHECK='Both';
      NO_ASSERT_CHECK='TRUE';
      NO_DIR_CHECK='TRUE';
      ALLOW_CONNECT='TRUE';
    'VSS'<1171>:
      PIN_NUMBER='(0,0,0,0,0,0,0,0,0,0,0,0,0,0,0,0,0,0,0,0,0,0,C16,0,0,0,0,0,0,0~
)';
      PINUSE='GROUND';
      NO_LOAD_CHECK='Both';
      NO_IO_CHECK='Both';
      NO_ASSERT_CHECK='TRUE';
      NO_DIR_CHECK='TRUE';
      ALLOW_CONNECT='TRUE';
    'VSS'<1170>:
      PIN_NUMBER='(0,0,0,0,0,0,0,0,0,0,0,0,0,0,0,0,0,0,0,0,0,0,C76,0,0,0,0,0,0,0~
)';
      PINUSE='GROUND';
      NO_LOAD_CHECK='Both';
      NO_IO_CHECK='Both';
      NO_ASSERT_CHECK='TRUE';
      NO_DIR_CHECK='TRUE';
      ALLOW_CONNECT='TRUE';
    'VSS'<1169>:
      PIN_NUMBER='(0,0,0,0,0,0,0,0,0,0,0,0,0,0,0,0,0,0,0,0,0,0,C78,0,0,0,0,0,0,0~
)';
      PINUSE='GROUND';
      NO_LOAD_CHECK='Both';
      NO_IO_CHECK='Both';
      NO_ASSERT_CHECK='TRUE';
      NO_DIR_CHECK='TRUE';
      ALLOW_CONNECT='TRUE';
    'VSS'<1168>:
      PIN_NUMBER='(0,0,0,0,0,0,0,0,0,0,0,0,0,0,0,0,0,0,0,0,0,0,CM27,0,0,0,0,0,0,~
0)';
      PINUSE='GROUND';
      NO_LOAD_CHECK='Both';
      NO_IO_CHECK='Both';
      NO_ASSERT_CHECK='TRUE';
      NO_DIR_CHECK='TRUE';
      ALLOW_CONNECT='TRUE';
    'VSS'<1167>:
      PIN_NUMBER='(0,0,0,0,0,0,0,0,0,0,0,0,0,0,0,0,0,0,0,0,0,0,D11,0,0,0,0,0,0,0~
)';
      PINUSE='GROUND';
      NO_LOAD_CHECK='Both';
      NO_IO_CHECK='Both';
      NO_ASSERT_CHECK='TRUE';
      NO_DIR_CHECK='TRUE';
      ALLOW_CONNECT='TRUE';
    'VSS'<1166>:
      PIN_NUMBER='(0,0,0,0,0,0,0,0,0,0,0,0,0,0,0,0,0,0,0,0,0,0,D13,0,0,0,0,0,0,0~
)';
      PINUSE='GROUND';
      NO_LOAD_CHECK='Both';
      NO_IO_CHECK='Both';
      NO_ASSERT_CHECK='TRUE';
      NO_DIR_CHECK='TRUE';
      ALLOW_CONNECT='TRUE';
    'VSS'<1165>:
      PIN_NUMBER='(0,0,0,0,0,0,0,0,0,0,0,0,0,0,0,0,0,0,0,0,0,0,D25,0,0,0,0,0,0,0~
)';
      PINUSE='GROUND';
      NO_LOAD_CHECK='Both';
      NO_IO_CHECK='Both';
      NO_ASSERT_CHECK='TRUE';
      NO_DIR_CHECK='TRUE';
      ALLOW_CONNECT='TRUE';
    'VSS'<1164>:
      PIN_NUMBER='(0,0,0,0,0,0,0,0,0,0,0,0,0,0,0,0,0,0,0,0,0,0,D27,0,0,0,0,0,0,0~
)';
      PINUSE='GROUND';
      NO_LOAD_CHECK='Both';
      NO_IO_CHECK='Both';
      NO_ASSERT_CHECK='TRUE';
      NO_DIR_CHECK='TRUE';
      ALLOW_CONNECT='TRUE';
    'VSS'<1163>:
      PIN_NUMBER='(0,0,0,0,0,0,0,0,0,0,0,0,0,0,0,0,0,0,0,0,0,0,D29,0,0,0,0,0,0,0~
)';
      PINUSE='GROUND';
      NO_LOAD_CHECK='Both';
      NO_IO_CHECK='Both';
      NO_ASSERT_CHECK='TRUE';
      NO_DIR_CHECK='TRUE';
      ALLOW_CONNECT='TRUE';
    'VSS'<1162>:
      PIN_NUMBER='(0,0,0,0,0,0,0,0,0,0,0,0,0,0,0,0,0,0,0,0,0,0,D31,0,0,0,0,0,0,0~
)';
      PINUSE='GROUND';
      NO_LOAD_CHECK='Both';
      NO_IO_CHECK='Both';
      NO_ASSERT_CHECK='TRUE';
      NO_DIR_CHECK='TRUE';
      ALLOW_CONNECT='TRUE';
    'VSS'<1161>:
      PIN_NUMBER='(0,0,0,0,0,0,0,0,0,0,0,0,0,0,0,0,0,0,0,0,0,0,D33,0,0,0,0,0,0,0~
)';
      PINUSE='GROUND';
      NO_LOAD_CHECK='Both';
      NO_IO_CHECK='Both';
      NO_ASSERT_CHECK='TRUE';
      NO_DIR_CHECK='TRUE';
      ALLOW_CONNECT='TRUE';
    'VSS'<1160>:
      PIN_NUMBER='(0,0,0,0,0,0,0,0,0,0,0,0,0,0,0,0,0,0,0,0,0,0,D35,0,0,0,0,0,0,0~
)';
      PINUSE='GROUND';
      NO_LOAD_CHECK='Both';
      NO_IO_CHECK='Both';
      NO_ASSERT_CHECK='TRUE';
      NO_DIR_CHECK='TRUE';
      ALLOW_CONNECT='TRUE';
    'VSS'<1159>:
      PIN_NUMBER='(0,0,0,0,0,0,0,0,0,0,0,0,0,0,0,0,0,0,0,0,0,0,D37,0,0,0,0,0,0,0~
)';
      PINUSE='GROUND';
      NO_LOAD_CHECK='Both';
      NO_IO_CHECK='Both';
      NO_ASSERT_CHECK='TRUE';
      NO_DIR_CHECK='TRUE';
      ALLOW_CONNECT='TRUE';
    'VSS'<1158>:
      PIN_NUMBER='(0,0,0,0,0,0,0,0,0,0,0,0,0,0,0,0,0,0,0,0,0,0,D39,0,0,0,0,0,0,0~
)';
      PINUSE='GROUND';
      NO_LOAD_CHECK='Both';
      NO_IO_CHECK='Both';
      NO_ASSERT_CHECK='TRUE';
      NO_DIR_CHECK='TRUE';
      ALLOW_CONNECT='TRUE';
    'VSS'<1157>:
      PIN_NUMBER='(0,0,0,0,0,0,0,0,0,0,0,0,0,0,0,0,0,0,0,0,0,0,D41,0,0,0,0,0,0,0~
)';
      PINUSE='GROUND';
      NO_LOAD_CHECK='Both';
      NO_IO_CHECK='Both';
      NO_ASSERT_CHECK='TRUE';
      NO_DIR_CHECK='TRUE';
      ALLOW_CONNECT='TRUE';
    'VSS'<1156>:
      PIN_NUMBER='(0,0,0,0,0,0,0,0,0,0,0,0,0,0,0,0,0,0,0,0,0,0,D43,0,0,0,0,0,0,0~
)';
      PINUSE='GROUND';
      NO_LOAD_CHECK='Both';
      NO_IO_CHECK='Both';
      NO_ASSERT_CHECK='TRUE';
      NO_DIR_CHECK='TRUE';
      ALLOW_CONNECT='TRUE';
    'VSS'<1155>:
      PIN_NUMBER='(0,0,0,0,0,0,0,0,0,0,0,0,0,0,0,0,0,0,0,0,0,0,D77,0,0,0,0,0,0,0~
)';
      PINUSE='GROUND';
      NO_LOAD_CHECK='Both';
      NO_IO_CHECK='Both';
      NO_ASSERT_CHECK='TRUE';
      NO_DIR_CHECK='TRUE';
      ALLOW_CONNECT='TRUE';
    'VSS'<1154>:
      PIN_NUMBER='(0,0,0,0,0,0,0,0,0,0,0,0,0,0,0,0,0,0,0,0,0,0,E6,0,0,0,0,0,0,0)~
';
      PINUSE='GROUND';
      NO_LOAD_CHECK='Both';
      NO_IO_CHECK='Both';
      NO_ASSERT_CHECK='TRUE';
      NO_DIR_CHECK='TRUE';
      ALLOW_CONNECT='TRUE';
    'VSS'<1153>:
      PIN_NUMBER='(0,0,0,0,0,0,0,0,0,0,0,0,0,0,0,0,0,0,0,0,0,0,E8,0,0,0,0,0,0,0)~
';
      PINUSE='GROUND';
      NO_LOAD_CHECK='Both';
      NO_IO_CHECK='Both';
      NO_ASSERT_CHECK='TRUE';
      NO_DIR_CHECK='TRUE';
      ALLOW_CONNECT='TRUE';
    'VSS'<1152>:
      PIN_NUMBER='(0,0,0,0,0,0,0,0,0,0,0,0,0,0,0,0,0,0,0,0,0,0,E16,0,0,0,0,0,0,0~
)';
      PINUSE='GROUND';
      NO_LOAD_CHECK='Both';
      NO_IO_CHECK='Both';
      NO_ASSERT_CHECK='TRUE';
      NO_DIR_CHECK='TRUE';
      ALLOW_CONNECT='TRUE';
    'VSS'<1151>:
      PIN_NUMBER='(0,0,0,0,0,0,0,0,0,0,0,0,0,0,0,0,0,0,0,0,0,0,E18,0,0,0,0,0,0,0~
)';
      PINUSE='GROUND';
      NO_LOAD_CHECK='Both';
      NO_IO_CHECK='Both';
      NO_ASSERT_CHECK='TRUE';
      NO_DIR_CHECK='TRUE';
      ALLOW_CONNECT='TRUE';
    'VSS'<1150>:
      PIN_NUMBER='(0,0,0,0,0,0,0,0,0,0,0,0,0,0,0,0,0,0,0,0,0,0,E20,0,0,0,0,0,0,0~
)';
      PINUSE='GROUND';
      NO_LOAD_CHECK='Both';
      NO_IO_CHECK='Both';
      NO_ASSERT_CHECK='TRUE';
      NO_DIR_CHECK='TRUE';
      ALLOW_CONNECT='TRUE';
    'VSS'<1149>:
      PIN_NUMBER='(0,0,0,0,0,0,0,0,0,0,0,0,0,0,0,0,0,0,0,0,0,0,E22,0,0,0,0,0,0,0~
)';
      PINUSE='GROUND';
      NO_LOAD_CHECK='Both';
      NO_IO_CHECK='Both';
      NO_ASSERT_CHECK='TRUE';
      NO_DIR_CHECK='TRUE';
      ALLOW_CONNECT='TRUE';
    'VSS'<1148>:
      PIN_NUMBER='(0,0,0,0,0,0,0,0,0,0,0,0,0,0,0,0,0,0,0,0,0,0,E72,0,0,0,0,0,0,0~
)';
      PINUSE='GROUND';
      NO_LOAD_CHECK='Both';
      NO_IO_CHECK='Both';
      NO_ASSERT_CHECK='TRUE';
      NO_DIR_CHECK='TRUE';
      ALLOW_CONNECT='TRUE';
    'VSS'<1147>:
      PIN_NUMBER='(0,0,0,0,0,0,0,0,0,0,0,0,0,0,0,0,0,0,0,0,0,0,E74,0,0,0,0,0,0,0~
)';
      PINUSE='GROUND';
      NO_LOAD_CHECK='Both';
      NO_IO_CHECK='Both';
      NO_ASSERT_CHECK='TRUE';
      NO_DIR_CHECK='TRUE';
      ALLOW_CONNECT='TRUE';
    'VSS'<1146>:
      PIN_NUMBER='(0,0,0,0,0,0,0,0,0,0,0,0,0,0,0,0,0,0,0,0,0,0,E76,0,0,0,0,0,0,0~
)';
      PINUSE='GROUND';
      NO_LOAD_CHECK='Both';
      NO_IO_CHECK='Both';
      NO_ASSERT_CHECK='TRUE';
      NO_DIR_CHECK='TRUE';
      ALLOW_CONNECT='TRUE';
    'VSS'<1145>:
      PIN_NUMBER='(0,0,0,0,0,0,0,0,0,0,0,0,0,0,0,0,0,0,0,0,0,0,F5,0,0,0,0,0,0,0)~
';
      PINUSE='GROUND';
      NO_LOAD_CHECK='Both';
      NO_IO_CHECK='Both';
      NO_ASSERT_CHECK='TRUE';
      NO_DIR_CHECK='TRUE';
      ALLOW_CONNECT='TRUE';
    'VSS'<1144>:
      PIN_NUMBER='(0,0,0,0,0,0,0,0,0,0,0,0,0,0,0,0,0,0,0,0,0,0,F17,0,0,0,0,0,0,0~
)';
      PINUSE='GROUND';
      NO_LOAD_CHECK='Both';
      NO_IO_CHECK='Both';
      NO_ASSERT_CHECK='TRUE';
      NO_DIR_CHECK='TRUE';
      ALLOW_CONNECT='TRUE';
    'VSS'<1143>:
      PIN_NUMBER='(0,0,0,0,0,0,0,0,0,0,0,0,0,0,0,0,0,0,0,0,0,0,F19,0,0,0,0,0,0,0~
)';
      PINUSE='GROUND';
      NO_LOAD_CHECK='Both';
      NO_IO_CHECK='Both';
      NO_ASSERT_CHECK='TRUE';
      NO_DIR_CHECK='TRUE';
      ALLOW_CONNECT='TRUE';
    'VSS'<1142>:
      PIN_NUMBER='(0,0,0,0,0,0,0,0,0,0,0,0,0,0,0,0,0,0,0,0,0,0,F25,0,0,0,0,0,0,0~
)';
      PINUSE='GROUND';
      NO_LOAD_CHECK='Both';
      NO_IO_CHECK='Both';
      NO_ASSERT_CHECK='TRUE';
      NO_DIR_CHECK='TRUE';
      ALLOW_CONNECT='TRUE';
    'VSS'<1141>:
      PIN_NUMBER='(0,0,0,0,0,0,0,0,0,0,0,0,0,0,0,0,0,0,0,0,0,0,F31,0,0,0,0,0,0,0~
)';
      PINUSE='GROUND';
      NO_LOAD_CHECK='Both';
      NO_IO_CHECK='Both';
      NO_ASSERT_CHECK='TRUE';
      NO_DIR_CHECK='TRUE';
      ALLOW_CONNECT='TRUE';
    'VSS'<1140>:
      PIN_NUMBER='(0,0,0,0,0,0,0,0,0,0,0,0,0,0,0,0,0,0,0,0,0,0,F37,0,0,0,0,0,0,0~
)';
      PINUSE='GROUND';
      NO_LOAD_CHECK='Both';
      NO_IO_CHECK='Both';
      NO_ASSERT_CHECK='TRUE';
      NO_DIR_CHECK='TRUE';
      ALLOW_CONNECT='TRUE';
    'VSS'<1139>:
      PIN_NUMBER='(0,0,0,0,0,0,0,0,0,0,0,0,0,0,0,0,0,0,0,0,0,0,F43,0,0,0,0,0,0,0~
)';
      PINUSE='GROUND';
      NO_LOAD_CHECK='Both';
      NO_IO_CHECK='Both';
      NO_ASSERT_CHECK='TRUE';
      NO_DIR_CHECK='TRUE';
      ALLOW_CONNECT='TRUE';
    'VSS'<1138>:
      PIN_NUMBER='(0,0,0,0,0,0,0,0,0,0,0,0,0,0,0,0,0,0,0,0,0,0,F67,0,0,0,0,0,0,0~
)';
      PINUSE='GROUND';
      NO_LOAD_CHECK='Both';
      NO_IO_CHECK='Both';
      NO_ASSERT_CHECK='TRUE';
      NO_DIR_CHECK='TRUE';
      ALLOW_CONNECT='TRUE';
    'VSS'<1137>:
      PIN_NUMBER='(0,0,0,0,0,0,0,0,0,0,0,0,0,0,0,0,0,0,0,0,0,0,F69,0,0,0,0,0,0,0~
)';
      PINUSE='GROUND';
      NO_LOAD_CHECK='Both';
      NO_IO_CHECK='Both';
      NO_ASSERT_CHECK='TRUE';
      NO_DIR_CHECK='TRUE';
      ALLOW_CONNECT='TRUE';
    'VSS'<1136>:
      PIN_NUMBER='(0,0,0,0,0,0,0,0,0,0,0,0,0,0,0,0,0,0,0,0,0,0,G4,0,0,0,0,0,0,0)~
';
      PINUSE='GROUND';
      NO_LOAD_CHECK='Both';
      NO_IO_CHECK='Both';
      NO_ASSERT_CHECK='TRUE';
      NO_DIR_CHECK='TRUE';
      ALLOW_CONNECT='TRUE';
    'VSS'<1135>:
      PIN_NUMBER='(0,0,0,0,0,0,0,0,0,0,0,0,0,0,0,0,0,0,0,0,0,0,G8,0,0,0,0,0,0,0)~
';
      PINUSE='GROUND';
      NO_LOAD_CHECK='Both';
      NO_IO_CHECK='Both';
      NO_ASSERT_CHECK='TRUE';
      NO_DIR_CHECK='TRUE';
      ALLOW_CONNECT='TRUE';
    'VSS'<1134>:
      PIN_NUMBER='(0,0,0,0,0,0,0,0,0,0,0,0,0,0,0,0,0,0,0,0,0,0,G22,0,0,0,0,0,0,0~
)';
      PINUSE='GROUND';
      NO_LOAD_CHECK='Both';
      NO_IO_CHECK='Both';
      NO_ASSERT_CHECK='TRUE';
      NO_DIR_CHECK='TRUE';
      ALLOW_CONNECT='TRUE';
    'VSS'<1133>:
      PIN_NUMBER='(0,0,0,0,0,0,0,0,0,0,0,0,0,0,0,0,0,0,0,0,0,0,G24,0,0,0,0,0,0,0~
)';
      PINUSE='GROUND';
      NO_LOAD_CHECK='Both';
      NO_IO_CHECK='Both';
      NO_ASSERT_CHECK='TRUE';
      NO_DIR_CHECK='TRUE';
      ALLOW_CONNECT='TRUE';
    'VSS'<1132>:
      PIN_NUMBER='(0,0,0,0,0,0,0,0,0,0,0,0,0,0,0,0,0,0,0,0,0,0,G26,0,0,0,0,0,0,0~
)';
      PINUSE='GROUND';
      NO_LOAD_CHECK='Both';
      NO_IO_CHECK='Both';
      NO_ASSERT_CHECK='TRUE';
      NO_DIR_CHECK='TRUE';
      ALLOW_CONNECT='TRUE';
    'VSS'<1131>:
      PIN_NUMBER='(0,0,0,0,0,0,0,0,0,0,0,0,0,0,0,0,0,0,0,0,0,0,G30,0,0,0,0,0,0,0~
)';
      PINUSE='GROUND';
      NO_LOAD_CHECK='Both';
      NO_IO_CHECK='Both';
      NO_ASSERT_CHECK='TRUE';
      NO_DIR_CHECK='TRUE';
      ALLOW_CONNECT='TRUE';
    'VSS'<1130>:
      PIN_NUMBER='(0,0,0,0,0,0,0,0,0,0,0,0,0,0,0,0,0,0,0,0,0,0,G32,0,0,0,0,0,0,0~
)';
      PINUSE='GROUND';
      NO_LOAD_CHECK='Both';
      NO_IO_CHECK='Both';
      NO_ASSERT_CHECK='TRUE';
      NO_DIR_CHECK='TRUE';
      ALLOW_CONNECT='TRUE';
    'VSS'<1129>:
      PIN_NUMBER='(0,0,0,0,0,0,0,0,0,0,0,0,0,0,0,0,0,0,0,0,0,0,G36,0,0,0,0,0,0,0~
)';
      PINUSE='GROUND';
      NO_LOAD_CHECK='Both';
      NO_IO_CHECK='Both';
      NO_ASSERT_CHECK='TRUE';
      NO_DIR_CHECK='TRUE';
      ALLOW_CONNECT='TRUE';
    'VSS'<1128>:
      PIN_NUMBER='(0,0,0,0,0,0,0,0,0,0,0,0,0,0,0,0,0,0,0,0,0,0,G38,0,0,0,0,0,0,0~
)';
      PINUSE='GROUND';
      NO_LOAD_CHECK='Both';
      NO_IO_CHECK='Both';
      NO_ASSERT_CHECK='TRUE';
      NO_DIR_CHECK='TRUE';
      ALLOW_CONNECT='TRUE';
    'VSS'<1127>:
      PIN_NUMBER='(0,0,0,0,0,0,0,0,0,0,0,0,0,0,0,0,0,0,0,0,0,0,G42,0,0,0,0,0,0,0~
)';
      PINUSE='GROUND';
      NO_LOAD_CHECK='Both';
      NO_IO_CHECK='Both';
      NO_ASSERT_CHECK='TRUE';
      NO_DIR_CHECK='TRUE';
      ALLOW_CONNECT='TRUE';
    'VSS'<1126>:
      PIN_NUMBER='(0,0,0,0,0,0,0,0,0,0,0,0,0,0,0,0,0,0,0,0,0,0,G66,0,0,0,0,0,0,0~
)';
      PINUSE='GROUND';
      NO_LOAD_CHECK='Both';
      NO_IO_CHECK='Both';
      NO_ASSERT_CHECK='TRUE';
      NO_DIR_CHECK='TRUE';
      ALLOW_CONNECT='TRUE';
    'VSS'<1125>:
      PIN_NUMBER='(0,0,0,0,0,0,0,0,0,0,0,0,0,0,0,0,0,0,0,0,0,0,G70,0,0,0,0,0,0,0~
)';
      PINUSE='GROUND';
      NO_LOAD_CHECK='Both';
      NO_IO_CHECK='Both';
      NO_ASSERT_CHECK='TRUE';
      NO_DIR_CHECK='TRUE';
      ALLOW_CONNECT='TRUE';
    'VSS'<1124>:
      PIN_NUMBER='(0,0,0,0,0,0,0,0,0,0,0,0,0,0,0,0,0,0,0,0,0,0,G76,0,0,0,0,0,0,0~
)';
      PINUSE='GROUND';
      NO_LOAD_CHECK='Both';
      NO_IO_CHECK='Both';
      NO_ASSERT_CHECK='TRUE';
      NO_DIR_CHECK='TRUE';
      ALLOW_CONNECT='TRUE';
    'VSS'<1123>:
      PIN_NUMBER='(0,0,0,0,0,0,0,0,0,0,0,0,0,0,0,0,0,0,0,0,0,0,G78,0,0,0,0,0,0,0~
)';
      PINUSE='GROUND';
      NO_LOAD_CHECK='Both';
      NO_IO_CHECK='Both';
      NO_ASSERT_CHECK='TRUE';
      NO_DIR_CHECK='TRUE';
      ALLOW_CONNECT='TRUE';
    'VSS'<1122>:
      PIN_NUMBER='(0,0,0,0,0,0,0,0,0,0,0,0,0,0,0,0,0,0,0,0,0,0,G80,0,0,0,0,0,0,0~
)';
      PINUSE='GROUND';
      NO_LOAD_CHECK='Both';
      NO_IO_CHECK='Both';
      NO_ASSERT_CHECK='TRUE';
      NO_DIR_CHECK='TRUE';
      ALLOW_CONNECT='TRUE';
    'VSS'<1121>:
      PIN_NUMBER='(0,0,0,0,0,0,0,0,0,0,0,0,0,0,0,0,0,0,0,0,0,0,G82,0,0,0,0,0,0,0~
)';
      PINUSE='GROUND';
      NO_LOAD_CHECK='Both';
      NO_IO_CHECK='Both';
      NO_ASSERT_CHECK='TRUE';
      NO_DIR_CHECK='TRUE';
      ALLOW_CONNECT='TRUE';
    'VSS'<1120>:
      PIN_NUMBER='(0,0,0,0,0,0,0,0,0,0,0,0,0,0,0,0,0,0,0,0,0,0,H3,0,0,0,0,0,0,0)~
';
      PINUSE='GROUND';
      NO_LOAD_CHECK='Both';
      NO_IO_CHECK='Both';
      NO_ASSERT_CHECK='TRUE';
      NO_DIR_CHECK='TRUE';
      ALLOW_CONNECT='TRUE';
    'VSS'<1119>:
      PIN_NUMBER='(0,0,0,0,0,0,0,0,0,0,0,0,0,0,0,0,0,0,0,0,0,0,H11,0,0,0,0,0,0,0~
)';
      PINUSE='GROUND';
      NO_LOAD_CHECK='Both';
      NO_IO_CHECK='Both';
      NO_ASSERT_CHECK='TRUE';
      NO_DIR_CHECK='TRUE';
      ALLOW_CONNECT='TRUE';
    'VSS'<1118>:
      PIN_NUMBER='(0,0,0,0,0,0,0,0,0,0,0,0,0,0,0,0,0,0,0,0,0,0,H25,0,0,0,0,0,0,0~
)';
      PINUSE='GROUND';
      NO_LOAD_CHECK='Both';
      NO_IO_CHECK='Both';
      NO_ASSERT_CHECK='TRUE';
      NO_DIR_CHECK='TRUE';
      ALLOW_CONNECT='TRUE';
    'VSS'<1117>:
      PIN_NUMBER='(0,0,0,0,0,0,0,0,0,0,0,0,0,0,0,0,0,0,0,0,0,0,H27,0,0,0,0,0,0,0~
)';
      PINUSE='GROUND';
      NO_LOAD_CHECK='Both';
      NO_IO_CHECK='Both';
      NO_ASSERT_CHECK='TRUE';
      NO_DIR_CHECK='TRUE';
      ALLOW_CONNECT='TRUE';
    'VSS'<1116>:
      PIN_NUMBER='(0,0,0,0,0,0,0,0,0,0,0,0,0,0,0,0,0,0,0,0,0,0,H29,0,0,0,0,0,0,0~
)';
      PINUSE='GROUND';
      NO_LOAD_CHECK='Both';
      NO_IO_CHECK='Both';
      NO_ASSERT_CHECK='TRUE';
      NO_DIR_CHECK='TRUE';
      ALLOW_CONNECT='TRUE';
    'VSS'<1115>:
      PIN_NUMBER='(0,0,0,0,0,0,0,0,0,0,0,0,0,0,0,0,0,0,0,0,0,0,H31,0,0,0,0,0,0,0~
)';
      PINUSE='GROUND';
      NO_LOAD_CHECK='Both';
      NO_IO_CHECK='Both';
      NO_ASSERT_CHECK='TRUE';
      NO_DIR_CHECK='TRUE';
      ALLOW_CONNECT='TRUE';
    'VSS'<1114>:
      PIN_NUMBER='(0,0,0,0,0,0,0,0,0,0,0,0,0,0,0,0,0,0,0,0,0,0,H33,0,0,0,0,0,0,0~
)';
      PINUSE='GROUND';
      NO_LOAD_CHECK='Both';
      NO_IO_CHECK='Both';
      NO_ASSERT_CHECK='TRUE';
      NO_DIR_CHECK='TRUE';
      ALLOW_CONNECT='TRUE';
    'VSS'<1113>:
      PIN_NUMBER='(0,0,0,0,0,0,0,0,0,0,0,0,0,0,0,0,0,0,0,0,0,0,H35,0,0,0,0,0,0,0~
)';
      PINUSE='GROUND';
      NO_LOAD_CHECK='Both';
      NO_IO_CHECK='Both';
      NO_ASSERT_CHECK='TRUE';
      NO_DIR_CHECK='TRUE';
      ALLOW_CONNECT='TRUE';
    'VSS'<1112>:
      PIN_NUMBER='(0,0,0,0,0,0,0,0,0,0,0,0,0,0,0,0,0,0,0,0,0,0,H37,0,0,0,0,0,0,0~
)';
      PINUSE='GROUND';
      NO_LOAD_CHECK='Both';
      NO_IO_CHECK='Both';
      NO_ASSERT_CHECK='TRUE';
      NO_DIR_CHECK='TRUE';
      ALLOW_CONNECT='TRUE';
    'VSS'<1111>:
      PIN_NUMBER='(0,0,0,0,0,0,0,0,0,0,0,0,0,0,0,0,0,0,0,0,0,0,H39,0,0,0,0,0,0,0~
)';
      PINUSE='GROUND';
      NO_LOAD_CHECK='Both';
      NO_IO_CHECK='Both';
      NO_ASSERT_CHECK='TRUE';
      NO_DIR_CHECK='TRUE';
      ALLOW_CONNECT='TRUE';
    'VSS'<1110>:
      PIN_NUMBER='(0,0,0,0,0,0,0,0,0,0,0,0,0,0,0,0,0,0,0,0,0,0,H41,0,0,0,0,0,0,0~
)';
      PINUSE='GROUND';
      NO_LOAD_CHECK='Both';
      NO_IO_CHECK='Both';
      NO_ASSERT_CHECK='TRUE';
      NO_DIR_CHECK='TRUE';
      ALLOW_CONNECT='TRUE';
    'VSS'<1109>:
      PIN_NUMBER='(0,0,0,0,0,0,0,0,0,0,0,0,0,0,0,0,0,0,0,0,0,0,H65,0,0,0,0,0,0,0~
)';
      PINUSE='GROUND';
      NO_LOAD_CHECK='Both';
      NO_IO_CHECK='Both';
      NO_ASSERT_CHECK='TRUE';
      NO_DIR_CHECK='TRUE';
      ALLOW_CONNECT='TRUE';
    'VSS'<1108>:
      PIN_NUMBER='(0,0,0,0,0,0,0,0,0,0,0,0,0,0,0,0,0,0,0,0,0,0,H71,0,0,0,0,0,0,0~
)';
      PINUSE='GROUND';
      NO_LOAD_CHECK='Both';
      NO_IO_CHECK='Both';
      NO_ASSERT_CHECK='TRUE';
      NO_DIR_CHECK='TRUE';
      ALLOW_CONNECT='TRUE';
    'VSS'<1107>:
      PIN_NUMBER='(0,0,0,0,0,0,0,0,0,0,0,0,0,0,0,0,0,0,0,0,0,0,H75,0,0,0,0,0,0,0~
)';
      PINUSE='GROUND';
      NO_LOAD_CHECK='Both';
      NO_IO_CHECK='Both';
      NO_ASSERT_CHECK='TRUE';
      NO_DIR_CHECK='TRUE';
      ALLOW_CONNECT='TRUE';
    'VSS'<1106>:
      PIN_NUMBER='(0,0,0,0,0,0,0,0,0,0,0,0,0,0,0,0,0,0,0,0,0,0,DN44,0,0,0,0,0,0,~
0)';
      PINUSE='GROUND';
      NO_LOAD_CHECK='Both';
      NO_IO_CHECK='Both';
      NO_ASSERT_CHECK='TRUE';
      NO_DIR_CHECK='TRUE';
      ALLOW_CONNECT='TRUE';
    'VSS'<1105>:
      PIN_NUMBER='(0,0,0,0,0,0,0,0,0,0,0,0,0,0,0,0,0,0,0,0,0,0,J4,0,0,0,0,0,0,0)~
';
      PINUSE='GROUND';
      NO_LOAD_CHECK='Both';
      NO_IO_CHECK='Both';
      NO_ASSERT_CHECK='TRUE';
      NO_DIR_CHECK='TRUE';
      ALLOW_CONNECT='TRUE';
    'VSS'<1104>:
      PIN_NUMBER='(0,0,0,0,0,0,0,0,0,0,0,0,0,0,0,0,0,0,0,0,0,0,J12,0,0,0,0,0,0,0~
)';
      PINUSE='GROUND';
      NO_LOAD_CHECK='Both';
      NO_IO_CHECK='Both';
      NO_ASSERT_CHECK='TRUE';
      NO_DIR_CHECK='TRUE';
      ALLOW_CONNECT='TRUE';
    'VSS'<1103>:
      PIN_NUMBER='(0,0,0,0,0,0,0,0,0,0,0,0,0,0,0,0,0,0,0,0,0,0,J14,0,0,0,0,0,0,0~
)';
      PINUSE='GROUND';
      NO_LOAD_CHECK='Both';
      NO_IO_CHECK='Both';
      NO_ASSERT_CHECK='TRUE';
      NO_DIR_CHECK='TRUE';
      ALLOW_CONNECT='TRUE';
    'VSS'<1102>:
      PIN_NUMBER='(0,0,0,0,0,0,0,0,0,0,0,0,0,0,0,0,0,0,0,0,0,0,J22,0,0,0,0,0,0,0~
)';
      PINUSE='GROUND';
      NO_LOAD_CHECK='Both';
      NO_IO_CHECK='Both';
      NO_ASSERT_CHECK='TRUE';
      NO_DIR_CHECK='TRUE';
      ALLOW_CONNECT='TRUE';
    'VSS'<1101>:
      PIN_NUMBER='(0,0,0,0,0,0,0,0,0,0,0,0,0,0,0,0,0,0,0,0,0,0,J26,0,0,0,0,0,0,0~
)';
      PINUSE='GROUND';
      NO_LOAD_CHECK='Both';
      NO_IO_CHECK='Both';
      NO_ASSERT_CHECK='TRUE';
      NO_DIR_CHECK='TRUE';
      ALLOW_CONNECT='TRUE';
    'VSS'<1100>:
      PIN_NUMBER='(0,0,0,0,0,0,0,0,0,0,0,0,0,0,0,0,0,0,0,0,0,0,J28,0,0,0,0,0,0,0~
)';
      PINUSE='GROUND';
      NO_LOAD_CHECK='Both';
      NO_IO_CHECK='Both';
      NO_ASSERT_CHECK='TRUE';
      NO_DIR_CHECK='TRUE';
      ALLOW_CONNECT='TRUE';
    'VSS'<1099>:
      PIN_NUMBER='(0,0,0,0,0,0,0,0,0,0,0,0,0,0,0,0,0,0,0,0,0,0,J32,0,0,0,0,0,0,0~
)';
      PINUSE='GROUND';
      NO_LOAD_CHECK='Both';
      NO_IO_CHECK='Both';
      NO_ASSERT_CHECK='TRUE';
      NO_DIR_CHECK='TRUE';
      ALLOW_CONNECT='TRUE';
    'VSS'<1098>:
      PIN_NUMBER='(0,0,0,0,0,0,0,0,0,0,0,0,0,0,0,0,0,0,0,0,0,0,J34,0,0,0,0,0,0,0~
)';
      PINUSE='GROUND';
      NO_LOAD_CHECK='Both';
      NO_IO_CHECK='Both';
      NO_ASSERT_CHECK='TRUE';
      NO_DIR_CHECK='TRUE';
      ALLOW_CONNECT='TRUE';
    'VSS'<1097>:
      PIN_NUMBER='(0,0,0,0,0,0,0,0,0,0,0,0,0,0,0,0,0,0,0,0,0,0,J38,0,0,0,0,0,0,0~
)';
      PINUSE='GROUND';
      NO_LOAD_CHECK='Both';
      NO_IO_CHECK='Both';
      NO_ASSERT_CHECK='TRUE';
      NO_DIR_CHECK='TRUE';
      ALLOW_CONNECT='TRUE';
    'VSS'<1096>:
      PIN_NUMBER='(0,0,0,0,0,0,0,0,0,0,0,0,0,0,0,0,0,0,0,0,0,0,J40,0,0,0,0,0,0,0~
)';
      PINUSE='GROUND';
      NO_LOAD_CHECK='Both';
      NO_IO_CHECK='Both';
      NO_ASSERT_CHECK='TRUE';
      NO_DIR_CHECK='TRUE';
      ALLOW_CONNECT='TRUE';
    'VSS'<1095>:
      PIN_NUMBER='(0,0,0,0,0,0,0,0,0,0,0,0,0,0,0,0,0,0,0,0,0,0,J72,0,0,0,0,0,0,0~
)';
      PINUSE='GROUND';
      NO_LOAD_CHECK='Both';
      NO_IO_CHECK='Both';
      NO_ASSERT_CHECK='TRUE';
      NO_DIR_CHECK='TRUE';
      ALLOW_CONNECT='TRUE';
    'VSS'<1094>:
      PIN_NUMBER='(0,0,0,0,0,0,0,0,0,0,0,0,0,0,0,0,0,0,0,0,0,0,J74,0,0,0,0,0,0,0~
)';
      PINUSE='GROUND';
      NO_LOAD_CHECK='Both';
      NO_IO_CHECK='Both';
      NO_ASSERT_CHECK='TRUE';
      NO_DIR_CHECK='TRUE';
      ALLOW_CONNECT='TRUE';
    'VSS'<1093>:
      PIN_NUMBER='(0,0,0,0,0,0,0,0,0,0,0,0,0,0,0,0,0,0,0,0,0,0,0,J76,0,0,0,0,0,0~
)';
      PINUSE='GROUND';
      NO_LOAD_CHECK='Both';
      NO_IO_CHECK='Both';
      NO_ASSERT_CHECK='TRUE';
      NO_DIR_CHECK='TRUE';
      ALLOW_CONNECT='TRUE';
    'VSS'<1092>:
      PIN_NUMBER='(0,0,0,0,0,0,0,0,0,0,0,0,0,0,0,0,0,0,0,0,0,0,0,J82,0,0,0,0,0,0~
)';
      PINUSE='GROUND';
      NO_LOAD_CHECK='Both';
      NO_IO_CHECK='Both';
      NO_ASSERT_CHECK='TRUE';
      NO_DIR_CHECK='TRUE';
      ALLOW_CONNECT='TRUE';
    'VSS'<1091>:
      PIN_NUMBER='(0,0,0,0,0,0,0,0,0,0,0,0,0,0,0,0,0,0,0,0,0,0,0,J84,0,0,0,0,0,0~
)';
      PINUSE='GROUND';
      NO_LOAD_CHECK='Both';
      NO_IO_CHECK='Both';
      NO_ASSERT_CHECK='TRUE';
      NO_DIR_CHECK='TRUE';
      ALLOW_CONNECT='TRUE';
    'VSS'<1090>:
      PIN_NUMBER='(0,0,0,0,0,0,0,0,0,0,0,0,0,0,0,0,0,0,0,0,0,0,0,K1,0,0,0,0,0,0)~
';
      PINUSE='GROUND';
      NO_LOAD_CHECK='Both';
      NO_IO_CHECK='Both';
      NO_ASSERT_CHECK='TRUE';
      NO_DIR_CHECK='TRUE';
      ALLOW_CONNECT='TRUE';
    'VSS'<1089>:
      PIN_NUMBER='(0,0,0,0,0,0,0,0,0,0,0,0,0,0,0,0,0,0,0,0,0,0,0,K11,0,0,0,0,0,0~
)';
      PINUSE='GROUND';
      NO_LOAD_CHECK='Both';
      NO_IO_CHECK='Both';
      NO_ASSERT_CHECK='TRUE';
      NO_DIR_CHECK='TRUE';
      ALLOW_CONNECT='TRUE';
    'VSS'<1088>:
      PIN_NUMBER='(0,0,0,0,0,0,0,0,0,0,0,0,0,0,0,0,0,0,0,0,0,0,0,K13,0,0,0,0,0,0~
)';
      PINUSE='GROUND';
      NO_LOAD_CHECK='Both';
      NO_IO_CHECK='Both';
      NO_ASSERT_CHECK='TRUE';
      NO_DIR_CHECK='TRUE';
      ALLOW_CONNECT='TRUE';
    'VSS'<1087>:
      PIN_NUMBER='(0,0,0,0,0,0,0,0,0,0,0,0,0,0,0,0,0,0,0,0,0,0,0,K17,0,0,0,0,0,0~
)';
      PINUSE='GROUND';
      NO_LOAD_CHECK='Both';
      NO_IO_CHECK='Both';
      NO_ASSERT_CHECK='TRUE';
      NO_DIR_CHECK='TRUE';
      ALLOW_CONNECT='TRUE';
    'VSS'<1086>:
      PIN_NUMBER='(0,0,0,0,0,0,0,0,0,0,0,0,0,0,0,0,0,0,0,0,0,0,0,DB7,0,0,0,0,0,0~
)';
      PINUSE='GROUND';
      NO_LOAD_CHECK='Both';
      NO_IO_CHECK='Both';
      NO_ASSERT_CHECK='TRUE';
      NO_DIR_CHECK='TRUE';
      ALLOW_CONNECT='TRUE';
    'VSS'<1085>:
      PIN_NUMBER='(0,0,0,0,0,0,0,0,0,0,0,0,0,0,0,0,0,0,0,0,0,0,0,K27,0,0,0,0,0,0~
)';
      PINUSE='GROUND';
      NO_LOAD_CHECK='Both';
      NO_IO_CHECK='Both';
      NO_ASSERT_CHECK='TRUE';
      NO_DIR_CHECK='TRUE';
      ALLOW_CONNECT='TRUE';
    'VSS'<1084>:
      PIN_NUMBER='(0,0,0,0,0,0,0,0,0,0,0,0,0,0,0,0,0,0,0,0,0,0,0,K33,0,0,0,0,0,0~
)';
      PINUSE='GROUND';
      NO_LOAD_CHECK='Both';
      NO_IO_CHECK='Both';
      NO_ASSERT_CHECK='TRUE';
      NO_DIR_CHECK='TRUE';
      ALLOW_CONNECT='TRUE';
    'VSS'<1083>:
      PIN_NUMBER='(0,0,0,0,0,0,0,0,0,0,0,0,0,0,0,0,0,0,0,0,0,0,0,K39,0,0,0,0,0,0~
)';
      PINUSE='GROUND';
      NO_LOAD_CHECK='Both';
      NO_IO_CHECK='Both';
      NO_ASSERT_CHECK='TRUE';
      NO_DIR_CHECK='TRUE';
      ALLOW_CONNECT='TRUE';
    'VSS'<1082>:
      PIN_NUMBER='(0,0,0,0,0,0,0,0,0,0,0,0,0,0,0,0,0,0,0,0,0,0,0,K65,0,0,0,0,0,0~
)';
      PINUSE='GROUND';
      NO_LOAD_CHECK='Both';
      NO_IO_CHECK='Both';
      NO_ASSERT_CHECK='TRUE';
      NO_DIR_CHECK='TRUE';
      ALLOW_CONNECT='TRUE';
    'VSS'<1081>:
      PIN_NUMBER='(0,0,0,0,0,0,0,0,0,0,0,0,0,0,0,0,0,0,0,0,0,0,0,K67,0,0,0,0,0,0~
)';
      PINUSE='GROUND';
      NO_LOAD_CHECK='Both';
      NO_IO_CHECK='Both';
      NO_ASSERT_CHECK='TRUE';
      NO_DIR_CHECK='TRUE';
      ALLOW_CONNECT='TRUE';
    'VSS'<1080>:
      PIN_NUMBER='(0,0,0,0,0,0,0,0,0,0,0,0,0,0,0,0,0,0,0,0,0,0,0,K69,0,0,0,0,0,0~
)';
      PINUSE='GROUND';
      NO_LOAD_CHECK='Both';
      NO_IO_CHECK='Both';
      NO_ASSERT_CHECK='TRUE';
      NO_DIR_CHECK='TRUE';
      ALLOW_CONNECT='TRUE';
    'VSS'<1079>:
      PIN_NUMBER='(0,0,0,0,0,0,0,0,0,0,0,0,0,0,0,0,0,0,0,0,0,0,0,K71,0,0,0,0,0,0~
)';
      PINUSE='GROUND';
      NO_LOAD_CHECK='Both';
      NO_IO_CHECK='Both';
      NO_ASSERT_CHECK='TRUE';
      NO_DIR_CHECK='TRUE';
      ALLOW_CONNECT='TRUE';
    'VSS'<1078>:
      PIN_NUMBER='(0,0,0,0,0,0,0,0,0,0,0,0,0,0,0,0,0,0,0,0,0,0,0,K73,0,0,0,0,0,0~
)';
      PINUSE='GROUND';
      NO_LOAD_CHECK='Both';
      NO_IO_CHECK='Both';
      NO_ASSERT_CHECK='TRUE';
      NO_DIR_CHECK='TRUE';
      ALLOW_CONNECT='TRUE';
    'VSS'<1077>:
      PIN_NUMBER='(0,0,0,0,0,0,0,0,0,0,0,0,0,0,0,0,0,0,0,0,0,0,0,K77,0,0,0,0,0,0~
)';
      PINUSE='GROUND';
      NO_LOAD_CHECK='Both';
      NO_IO_CHECK='Both';
      NO_ASSERT_CHECK='TRUE';
      NO_DIR_CHECK='TRUE';
      ALLOW_CONNECT='TRUE';
    'VSS'<1076>:
      PIN_NUMBER='(0,0,0,0,0,0,0,0,0,0,0,0,0,0,0,0,0,0,0,0,0,0,0,K81,0,0,0,0,0,0~
)';
      PINUSE='GROUND';
      NO_LOAD_CHECK='Both';
      NO_IO_CHECK='Both';
      NO_ASSERT_CHECK='TRUE';
      NO_DIR_CHECK='TRUE';
      ALLOW_CONNECT='TRUE';
    'VSS'<1075>:
      PIN_NUMBER='(0,0,0,0,0,0,0,0,0,0,0,0,0,0,0,0,0,0,0,0,0,0,0,K83,0,0,0,0,0,0~
)';
      PINUSE='GROUND';
      NO_LOAD_CHECK='Both';
      NO_IO_CHECK='Both';
      NO_ASSERT_CHECK='TRUE';
      NO_DIR_CHECK='TRUE';
      ALLOW_CONNECT='TRUE';
    'VSS'<1074>:
      PIN_NUMBER='(0,0,0,0,0,0,0,0,0,0,0,0,0,0,0,0,0,0,0,0,0,0,0,K85,0,0,0,0,0,0~
)';
      PINUSE='GROUND';
      NO_LOAD_CHECK='Both';
      NO_IO_CHECK='Both';
      NO_ASSERT_CHECK='TRUE';
      NO_DIR_CHECK='TRUE';
      ALLOW_CONNECT='TRUE';
    'VSS'<1073>:
      PIN_NUMBER='(0,0,0,0,0,0,0,0,0,0,0,0,0,0,0,0,0,0,0,0,0,0,0,L10,0,0,0,0,0,0~
)';
      PINUSE='GROUND';
      NO_LOAD_CHECK='Both';
      NO_IO_CHECK='Both';
      NO_ASSERT_CHECK='TRUE';
      NO_DIR_CHECK='TRUE';
      ALLOW_CONNECT='TRUE';
    'VSS'<1072>:
      PIN_NUMBER='(0,0,0,0,0,0,0,0,0,0,0,0,0,0,0,0,0,0,0,0,0,0,0,L2,0,0,0,0,0,0)~
';
      PINUSE='GROUND';
      NO_LOAD_CHECK='Both';
      NO_IO_CHECK='Both';
      NO_ASSERT_CHECK='TRUE';
      NO_DIR_CHECK='TRUE';
      ALLOW_CONNECT='TRUE';
    'VSS'<1071>:
      PIN_NUMBER='(0,0,0,0,0,0,0,0,0,0,0,0,0,0,0,0,0,0,0,0,0,0,0,L6,0,0,0,0,0,0)~
';
      PINUSE='GROUND';
      NO_LOAD_CHECK='Both';
      NO_IO_CHECK='Both';
      NO_ASSERT_CHECK='TRUE';
      NO_DIR_CHECK='TRUE';
      ALLOW_CONNECT='TRUE';
    'VSS'<1070>:
      PIN_NUMBER='(0,0,0,0,0,0,0,0,0,0,0,0,0,0,0,0,0,0,0,0,0,0,0,L20,0,0,0,0,0,0~
)';
      PINUSE='GROUND';
      NO_LOAD_CHECK='Both';
      NO_IO_CHECK='Both';
      NO_ASSERT_CHECK='TRUE';
      NO_DIR_CHECK='TRUE';
      ALLOW_CONNECT='TRUE';
    'VSS'<1069>:
      PIN_NUMBER='(0,0,0,0,0,0,0,0,0,0,0,0,0,0,0,0,0,0,0,0,0,0,0,L22,0,0,0,0,0,0~
)';
      PINUSE='GROUND';
      NO_LOAD_CHECK='Both';
      NO_IO_CHECK='Both';
      NO_ASSERT_CHECK='TRUE';
      NO_DIR_CHECK='TRUE';
      ALLOW_CONNECT='TRUE';
    'VSS'<1068>:
      PIN_NUMBER='(0,0,0,0,0,0,0,0,0,0,0,0,0,0,0,0,0,0,0,0,0,0,0,L72,0,0,0,0,0,0~
)';
      PINUSE='GROUND';
      NO_LOAD_CHECK='Both';
      NO_IO_CHECK='Both';
      NO_ASSERT_CHECK='TRUE';
      NO_DIR_CHECK='TRUE';
      ALLOW_CONNECT='TRUE';
    'VSS'<1067>:
      PIN_NUMBER='(0,0,0,0,0,0,0,0,0,0,0,0,0,0,0,0,0,0,0,0,0,0,0,L78,0,0,0,0,0,0~
)';
      PINUSE='GROUND';
      NO_LOAD_CHECK='Both';
      NO_IO_CHECK='Both';
      NO_ASSERT_CHECK='TRUE';
      NO_DIR_CHECK='TRUE';
      ALLOW_CONNECT='TRUE';
    'VSS'<1066>:
      PIN_NUMBER='(0,0,0,0,0,0,0,0,0,0,0,0,0,0,0,0,0,0,0,0,0,0,0,L80,0,0,0,0,0,0~
)';
      PINUSE='GROUND';
      NO_LOAD_CHECK='Both';
      NO_IO_CHECK='Both';
      NO_ASSERT_CHECK='TRUE';
      NO_DIR_CHECK='TRUE';
      ALLOW_CONNECT='TRUE';
    'VSS'<1065>:
      PIN_NUMBER='(0,0,0,0,0,0,0,0,0,0,0,0,0,0,0,0,0,0,0,0,0,0,0,L82,0,0,0,0,0,0~
)';
      PINUSE='GROUND';
      NO_LOAD_CHECK='Both';
      NO_IO_CHECK='Both';
      NO_ASSERT_CHECK='TRUE';
      NO_DIR_CHECK='TRUE';
      ALLOW_CONNECT='TRUE';
    'VSS'<1064>:
      PIN_NUMBER='(0,0,0,0,0,0,0,0,0,0,0,0,0,0,0,0,0,0,0,0,0,0,0,BT9,0,0,0,0,0,0~
)';
      PINUSE='GROUND';
      NO_LOAD_CHECK='Both';
      NO_IO_CHECK='Both';
      NO_ASSERT_CHECK='TRUE';
      NO_DIR_CHECK='TRUE';
      ALLOW_CONNECT='TRUE';
    'VSS'<1063>:
      PIN_NUMBER='(0,0,0,0,0,0,0,0,0,0,0,0,0,0,0,0,0,0,0,0,0,0,0,CT7,0,0,0,0,0,0~
)';
      PINUSE='GROUND';
      NO_LOAD_CHECK='Both';
      NO_IO_CHECK='Both';
      NO_ASSERT_CHECK='TRUE';
      NO_DIR_CHECK='TRUE';
      ALLOW_CONNECT='TRUE';
    'VSS'<1062>:
      PIN_NUMBER='(0,0,0,0,0,0,0,0,0,0,0,0,0,0,0,0,0,0,0,0,0,0,0,M15,0,0,0,0,0,0~
)';
      PINUSE='GROUND';
      NO_LOAD_CHECK='Both';
      NO_IO_CHECK='Both';
      NO_ASSERT_CHECK='TRUE';
      NO_DIR_CHECK='TRUE';
      ALLOW_CONNECT='TRUE';
    'VSS'<1061>:
      PIN_NUMBER='(0,0,0,0,0,0,0,0,0,0,0,0,0,0,0,0,0,0,0,0,0,0,0,M17,0,0,0,0,0,0~
)';
      PINUSE='GROUND';
      NO_LOAD_CHECK='Both';
      NO_IO_CHECK='Both';
      NO_ASSERT_CHECK='TRUE';
      NO_DIR_CHECK='TRUE';
      ALLOW_CONNECT='TRUE';
    'VSS'<1060>:
      PIN_NUMBER='(0,0,0,0,0,0,0,0,0,0,0,0,0,0,0,0,0,0,0,0,0,0,0,M19,0,0,0,0,0,0~
)';
      PINUSE='GROUND';
      NO_LOAD_CHECK='Both';
      NO_IO_CHECK='Both';
      NO_ASSERT_CHECK='TRUE';
      NO_DIR_CHECK='TRUE';
      ALLOW_CONNECT='TRUE';
    'VSS'<1059>:
      PIN_NUMBER='(0,0,0,0,0,0,0,0,0,0,0,0,0,0,0,0,0,0,0,0,0,0,0,M23,0,0,0,0,0,0~
)';
      PINUSE='GROUND';
      NO_LOAD_CHECK='Both';
      NO_IO_CHECK='Both';
      NO_ASSERT_CHECK='TRUE';
      NO_DIR_CHECK='TRUE';
      ALLOW_CONNECT='TRUE';
    'VSS'<1058>:
      PIN_NUMBER='(0,0,0,0,0,0,0,0,0,0,0,0,0,0,0,0,0,0,0,0,0,0,0,M25,0,0,0,0,0,0~
)';
      PINUSE='GROUND';
      NO_LOAD_CHECK='Both';
      NO_IO_CHECK='Both';
      NO_ASSERT_CHECK='TRUE';
      NO_DIR_CHECK='TRUE';
      ALLOW_CONNECT='TRUE';
    'VSS'<1057>:
      PIN_NUMBER='(0,0,0,0,0,0,0,0,0,0,0,0,0,0,0,0,0,0,0,0,0,0,0,M27,0,0,0,0,0,0~
)';
      PINUSE='GROUND';
      NO_LOAD_CHECK='Both';
      NO_IO_CHECK='Both';
      NO_ASSERT_CHECK='TRUE';
      NO_DIR_CHECK='TRUE';
      ALLOW_CONNECT='TRUE';
    'VSS'<1056>:
      PIN_NUMBER='(0,0,0,0,0,0,0,0,0,0,0,0,0,0,0,0,0,0,0,0,0,0,0,M29,0,0,0,0,0,0~
)';
      PINUSE='GROUND';
      NO_LOAD_CHECK='Both';
      NO_IO_CHECK='Both';
      NO_ASSERT_CHECK='TRUE';
      NO_DIR_CHECK='TRUE';
      ALLOW_CONNECT='TRUE';
    'VSS'<1055>:
      PIN_NUMBER='(0,0,0,0,0,0,0,0,0,0,0,0,0,0,0,0,0,0,0,0,0,0,0,M31,0,0,0,0,0,0~
)';
      PINUSE='GROUND';
      NO_LOAD_CHECK='Both';
      NO_IO_CHECK='Both';
      NO_ASSERT_CHECK='TRUE';
      NO_DIR_CHECK='TRUE';
      ALLOW_CONNECT='TRUE';
    'VSS'<1054>:
      PIN_NUMBER='(0,0,0,0,0,0,0,0,0,0,0,0,0,0,0,0,0,0,0,0,0,0,0,M33,0,0,0,0,0,0~
)';
      PINUSE='GROUND';
      NO_LOAD_CHECK='Both';
      NO_IO_CHECK='Both';
      NO_ASSERT_CHECK='TRUE';
      NO_DIR_CHECK='TRUE';
      ALLOW_CONNECT='TRUE';
    'VSS'<1053>:
      PIN_NUMBER='(0,0,0,0,0,0,0,0,0,0,0,0,0,0,0,0,0,0,0,0,0,0,0,M35,0,0,0,0,0,0~
)';
      PINUSE='GROUND';
      NO_LOAD_CHECK='Both';
      NO_IO_CHECK='Both';
      NO_ASSERT_CHECK='TRUE';
      NO_DIR_CHECK='TRUE';
      ALLOW_CONNECT='TRUE';
    'VSS'<1052>:
      PIN_NUMBER='(0,0,0,0,0,0,0,0,0,0,0,0,0,0,0,0,0,0,0,0,0,0,0,M37,0,0,0,0,0,0~
)';
      PINUSE='GROUND';
      NO_LOAD_CHECK='Both';
      NO_IO_CHECK='Both';
      NO_ASSERT_CHECK='TRUE';
      NO_DIR_CHECK='TRUE';
      ALLOW_CONNECT='TRUE';
    'VSS'<1051>:
      PIN_NUMBER='(0,0,0,0,0,0,0,0,0,0,0,0,0,0,0,0,0,0,0,0,0,0,0,M39,0,0,0,0,0,0~
)';
      PINUSE='GROUND';
      NO_LOAD_CHECK='Both';
      NO_IO_CHECK='Both';
      NO_ASSERT_CHECK='TRUE';
      NO_DIR_CHECK='TRUE';
      ALLOW_CONNECT='TRUE';
    'VSS'<1050>:
      PIN_NUMBER='(0,0,0,0,0,0,0,0,0,0,0,0,0,0,0,0,0,0,0,0,0,0,0,M41,0,0,0,0,0,0~
)';
      PINUSE='GROUND';
      NO_LOAD_CHECK='Both';
      NO_IO_CHECK='Both';
      NO_ASSERT_CHECK='TRUE';
      NO_DIR_CHECK='TRUE';
      ALLOW_CONNECT='TRUE';
    'VSS'<1049>:
      PIN_NUMBER='(0,0,0,0,0,0,0,0,0,0,0,0,0,0,0,0,0,0,0,0,0,0,0,M43,0,0,0,0,0,0~
)';
      PINUSE='GROUND';
      NO_LOAD_CHECK='Both';
      NO_IO_CHECK='Both';
      NO_ASSERT_CHECK='TRUE';
      NO_DIR_CHECK='TRUE';
      ALLOW_CONNECT='TRUE';
    'VSS'<1048>:
      PIN_NUMBER='(0,0,0,0,0,0,0,0,0,0,0,0,0,0,0,0,0,0,0,0,0,0,0,M65,0,0,0,0,0,0~
)';
      PINUSE='GROUND';
      NO_LOAD_CHECK='Both';
      NO_IO_CHECK='Both';
      NO_ASSERT_CHECK='TRUE';
      NO_DIR_CHECK='TRUE';
      ALLOW_CONNECT='TRUE';
    'VSS'<1047>:
      PIN_NUMBER='(0,0,0,0,0,0,0,0,0,0,0,0,0,0,0,0,0,0,0,0,0,0,0,M71,0,0,0,0,0,0~
)';
      PINUSE='GROUND';
      NO_LOAD_CHECK='Both';
      NO_IO_CHECK='Both';
      NO_ASSERT_CHECK='TRUE';
      NO_DIR_CHECK='TRUE';
      ALLOW_CONNECT='TRUE';
    'VSS'<1046>:
      PIN_NUMBER='(0,0,0,0,0,0,0,0,0,0,0,0,0,0,0,0,0,0,0,0,0,0,0,M79,0,0,0,0,0,0~
)';
      PINUSE='GROUND';
      NO_LOAD_CHECK='Both';
      NO_IO_CHECK='Both';
      NO_ASSERT_CHECK='TRUE';
      NO_DIR_CHECK='TRUE';
      ALLOW_CONNECT='TRUE';
    'VSS'<1045>:
      PIN_NUMBER='(0,0,0,0,0,0,0,0,0,0,0,0,0,0,0,0,0,0,0,0,0,0,0,M83,0,0,0,0,0,0~
)';
      PINUSE='GROUND';
      NO_LOAD_CHECK='Both';
      NO_IO_CHECK='Both';
      NO_ASSERT_CHECK='TRUE';
      NO_DIR_CHECK='TRUE';
      ALLOW_CONNECT='TRUE';
    'VSS'<1044>:
      PIN_NUMBER='(0,0,0,0,0,0,0,0,0,0,0,0,0,0,0,0,0,0,0,0,0,0,0,M85,0,0,0,0,0,0~
)';
      PINUSE='GROUND';
      NO_LOAD_CHECK='Both';
      NO_IO_CHECK='Both';
      NO_ASSERT_CHECK='TRUE';
      NO_DIR_CHECK='TRUE';
      ALLOW_CONNECT='TRUE';
    'VSS'<1043>:
      PIN_NUMBER='(0,0,0,0,0,0,0,0,0,0,0,0,0,0,0,0,0,0,0,0,0,0,0,DM19,0,0,0,0,0,~
0)';
      PINUSE='GROUND';
      NO_LOAD_CHECK='Both';
      NO_IO_CHECK='Both';
      NO_ASSERT_CHECK='TRUE';
      NO_DIR_CHECK='TRUE';
      ALLOW_CONNECT='TRUE';
    'VSS'<1042>:
      PIN_NUMBER='(0,0,0,0,0,0,0,0,0,0,0,0,0,0,0,0,0,0,0,0,0,0,0,N20,0,0,0,0,0,0~
)';
      PINUSE='GROUND';
      NO_LOAD_CHECK='Both';
      NO_IO_CHECK='Both';
      NO_ASSERT_CHECK='TRUE';
      NO_DIR_CHECK='TRUE';
      ALLOW_CONNECT='TRUE';
    'VSS'<1041>:
      PIN_NUMBER='(0,0,0,0,0,0,0,0,0,0,0,0,0,0,0,0,0,0,0,0,0,0,0,N22,0,0,0,0,0,0~
)';
      PINUSE='GROUND';
      NO_LOAD_CHECK='Both';
      NO_IO_CHECK='Both';
      NO_ASSERT_CHECK='TRUE';
      NO_DIR_CHECK='TRUE';
      ALLOW_CONNECT='TRUE';
    'VSS'<1040>:
      PIN_NUMBER='(0,0,0,0,0,0,0,0,0,0,0,0,0,0,0,0,0,0,0,0,0,0,0,N6,0,0,0,0,0,0)~
';
      PINUSE='GROUND';
      NO_LOAD_CHECK='Both';
      NO_IO_CHECK='Both';
      NO_ASSERT_CHECK='TRUE';
      NO_DIR_CHECK='TRUE';
      ALLOW_CONNECT='TRUE';
    'VSS'<1039>:
      PIN_NUMBER='(0,0,0,0,0,0,0,0,0,0,0,0,0,0,0,0,0,0,0,0,0,0,0,N66,0,0,0,0,0,0~
)';
      PINUSE='GROUND';
      NO_LOAD_CHECK='Both';
      NO_IO_CHECK='Both';
      NO_ASSERT_CHECK='TRUE';
      NO_DIR_CHECK='TRUE';
      ALLOW_CONNECT='TRUE';
    'VSS'<1038>:
      PIN_NUMBER='(0,0,0,0,0,0,0,0,0,0,0,0,0,0,0,0,0,0,0,0,0,0,0,N70,0,0,0,0,0,0~
)';
      PINUSE='GROUND';
      NO_LOAD_CHECK='Both';
      NO_IO_CHECK='Both';
      NO_ASSERT_CHECK='TRUE';
      NO_DIR_CHECK='TRUE';
      ALLOW_CONNECT='TRUE';
    'VSS'<1037>:
      PIN_NUMBER='(0,0,0,0,0,0,0,0,0,0,0,0,0,0,0,0,0,0,0,0,0,0,0,N72,0,0,0,0,0,0~
)';
      PINUSE='GROUND';
      NO_LOAD_CHECK='Both';
      NO_IO_CHECK='Both';
      NO_ASSERT_CHECK='TRUE';
      NO_DIR_CHECK='TRUE';
      ALLOW_CONNECT='TRUE';
    'VSS'<1036>:
      PIN_NUMBER='(0,0,0,0,0,0,0,0,0,0,0,0,0,0,0,0,0,0,0,0,0,0,0,N74,0,0,0,0,0,0~
)';
      PINUSE='GROUND';
      NO_LOAD_CHECK='Both';
      NO_IO_CHECK='Both';
      NO_ASSERT_CHECK='TRUE';
      NO_DIR_CHECK='TRUE';
      ALLOW_CONNECT='TRUE';
    'VSS'<1035>:
      PIN_NUMBER='(0,0,0,0,0,0,0,0,0,0,0,0,0,0,0,0,0,0,0,0,0,0,0,N76,0,0,0,0,0,0~
)';
      PINUSE='GROUND';
      NO_LOAD_CHECK='Both';
      NO_IO_CHECK='Both';
      NO_ASSERT_CHECK='TRUE';
      NO_DIR_CHECK='TRUE';
      ALLOW_CONNECT='TRUE';
    'VSS'<1034>:
      PIN_NUMBER='(0,0,0,0,0,0,0,0,0,0,0,0,0,0,0,0,0,0,0,0,0,0,0,N78,0,0,0,0,0,0~
)';
      PINUSE='GROUND';
      NO_LOAD_CHECK='Both';
      NO_IO_CHECK='Both';
      NO_ASSERT_CHECK='TRUE';
      NO_DIR_CHECK='TRUE';
      ALLOW_CONNECT='TRUE';
    'VSS'<1033>:
      PIN_NUMBER='(0,0,0,0,0,0,0,0,0,0,0,0,0,0,0,0,0,0,0,0,0,0,0,N4,0,0,0,0,0,0)~
';
      PINUSE='GROUND';
      NO_LOAD_CHECK='Both';
      NO_IO_CHECK='Both';
      NO_ASSERT_CHECK='TRUE';
      NO_DIR_CHECK='TRUE';
      ALLOW_CONNECT='TRUE';
    'VSS'<1032>:
      PIN_NUMBER='(0,0,0,0,0,0,0,0,0,0,0,0,0,0,0,0,0,0,0,0,0,0,0,N8,0,0,0,0,0,0)~
';
      PINUSE='GROUND';
      NO_LOAD_CHECK='Both';
      NO_IO_CHECK='Both';
      NO_ASSERT_CHECK='TRUE';
      NO_DIR_CHECK='TRUE';
      ALLOW_CONNECT='TRUE';
    'VSS'<1031>:
      PIN_NUMBER='(0,0,0,0,0,0,0,0,0,0,0,0,0,0,0,0,0,0,0,0,0,0,0,P11,0,0,0,0,0,0~
)';
      PINUSE='GROUND';
      NO_LOAD_CHECK='Both';
      NO_IO_CHECK='Both';
      NO_ASSERT_CHECK='TRUE';
      NO_DIR_CHECK='TRUE';
      ALLOW_CONNECT='TRUE';
    'VSS'<1030>:
      PIN_NUMBER='(0,0,0,0,0,0,0,0,0,0,0,0,0,0,0,0,0,0,0,0,0,0,0,P15,0,0,0,0,0,0~
)';
      PINUSE='GROUND';
      NO_LOAD_CHECK='Both';
      NO_IO_CHECK='Both';
      NO_ASSERT_CHECK='TRUE';
      NO_DIR_CHECK='TRUE';
      ALLOW_CONNECT='TRUE';
    'VSS'<1029>:
      PIN_NUMBER='(0,0,0,0,0,0,0,0,0,0,0,0,0,0,0,0,0,0,0,0,0,0,0,P27,0,0,0,0,0,0~
)';
      PINUSE='GROUND';
      NO_LOAD_CHECK='Both';
      NO_IO_CHECK='Both';
      NO_ASSERT_CHECK='TRUE';
      NO_DIR_CHECK='TRUE';
      ALLOW_CONNECT='TRUE';
    'VSS'<1028>:
      PIN_NUMBER='(0,0,0,0,0,0,0,0,0,0,0,0,0,0,0,0,0,0,0,0,0,0,0,P33,0,0,0,0,0,0~
)';
      PINUSE='GROUND';
      NO_LOAD_CHECK='Both';
      NO_IO_CHECK='Both';
      NO_ASSERT_CHECK='TRUE';
      NO_DIR_CHECK='TRUE';
      ALLOW_CONNECT='TRUE';
    'VSS'<1027>:
      PIN_NUMBER='(0,0,0,0,0,0,0,0,0,0,0,0,0,0,0,0,0,0,0,0,0,0,0,P39,0,0,0,0,0,0~
)';
      PINUSE='GROUND';
      NO_LOAD_CHECK='Both';
      NO_IO_CHECK='Both';
      NO_ASSERT_CHECK='TRUE';
      NO_DIR_CHECK='TRUE';
      ALLOW_CONNECT='TRUE';
    'VSS'<1026>:
      PIN_NUMBER='(0,0,0,0,0,0,0,0,0,0,0,0,0,0,0,0,0,0,0,0,0,0,0,P67,0,0,0,0,0,0~
)';
      PINUSE='GROUND';
      NO_LOAD_CHECK='Both';
      NO_IO_CHECK='Both';
      NO_ASSERT_CHECK='TRUE';
      NO_DIR_CHECK='TRUE';
      ALLOW_CONNECT='TRUE';
    'VSS'<1025>:
      PIN_NUMBER='(0,0,0,0,0,0,0,0,0,0,0,0,0,0,0,0,0,0,0,0,0,0,0,P69,0,0,0,0,0,0~
)';
      PINUSE='GROUND';
      NO_LOAD_CHECK='Both';
      NO_IO_CHECK='Both';
      NO_ASSERT_CHECK='TRUE';
      NO_DIR_CHECK='TRUE';
      ALLOW_CONNECT='TRUE';
    'VSS'<1024>:
      PIN_NUMBER='(0,0,0,0,0,0,0,0,0,0,0,0,0,0,0,0,0,0,0,0,0,0,0,P71,0,0,0,0,0,0~
)';
      PINUSE='GROUND';
      NO_LOAD_CHECK='Both';
      NO_IO_CHECK='Both';
      NO_ASSERT_CHECK='TRUE';
      NO_DIR_CHECK='TRUE';
      ALLOW_CONNECT='TRUE';
    'VSS'<1023>:
      PIN_NUMBER='(0,0,0,0,0,0,0,0,0,0,0,0,0,0,0,0,0,0,0,0,0,0,0,P81,0,0,0,0,0,0~
)';
      PINUSE='GROUND';
      NO_LOAD_CHECK='Both';
      NO_IO_CHECK='Both';
      NO_ASSERT_CHECK='TRUE';
      NO_DIR_CHECK='TRUE';
      ALLOW_CONNECT='TRUE';
    'VSS'<1022>:
      PIN_NUMBER='(0,0,0,0,0,0,0,0,0,0,0,0,0,0,0,0,0,0,0,0,0,0,0,P83,0,0,0,0,0,0~
)';
      PINUSE='GROUND';
      NO_LOAD_CHECK='Both';
      NO_IO_CHECK='Both';
      NO_ASSERT_CHECK='TRUE';
      NO_DIR_CHECK='TRUE';
      ALLOW_CONNECT='TRUE';
    'VSS'<1021>:
      PIN_NUMBER='(0,0,0,0,0,0,0,0,0,0,0,0,0,0,0,0,0,0,0,0,0,0,0,R14,0,0,0,0,0,0~
)';
      PINUSE='GROUND';
      NO_LOAD_CHECK='Both';
      NO_IO_CHECK='Both';
      NO_ASSERT_CHECK='TRUE';
      NO_DIR_CHECK='TRUE';
      ALLOW_CONNECT='TRUE';
    'VSS'<1020>:
      PIN_NUMBER='(0,0,0,0,0,0,0,0,0,0,0,0,0,0,0,0,0,0,0,0,0,0,0,R18,0,0,0,0,0,0~
)';
      PINUSE='GROUND';
      NO_LOAD_CHECK='Both';
      NO_IO_CHECK='Both';
      NO_ASSERT_CHECK='TRUE';
      NO_DIR_CHECK='TRUE';
      ALLOW_CONNECT='TRUE';
    'VSS'<1019>:
      PIN_NUMBER='(0,0,0,0,0,0,0,0,0,0,0,0,0,0,0,0,0,0,0,0,0,0,0,R2,0,0,0,0,0,0)~
';
      PINUSE='GROUND';
      NO_LOAD_CHECK='Both';
      NO_IO_CHECK='Both';
      NO_ASSERT_CHECK='TRUE';
      NO_DIR_CHECK='TRUE';
      ALLOW_CONNECT='TRUE';
    'VSS'<1018>:
      PIN_NUMBER='(0,0,0,0,0,0,0,0,0,0,0,0,0,0,0,0,0,0,0,0,0,0,0,R4,0,0,0,0,0,0)~
';
      PINUSE='GROUND';
      NO_LOAD_CHECK='Both';
      NO_IO_CHECK='Both';
      NO_ASSERT_CHECK='TRUE';
      NO_DIR_CHECK='TRUE';
      ALLOW_CONNECT='TRUE';
    'VSS'<1017>:
      PIN_NUMBER='(0,0,0,0,0,0,0,0,0,0,0,0,0,0,0,0,0,0,0,0,0,0,0,R22,0,0,0,0,0,0~
)';
      PINUSE='GROUND';
      NO_LOAD_CHECK='Both';
      NO_IO_CHECK='Both';
      NO_ASSERT_CHECK='TRUE';
      NO_DIR_CHECK='TRUE';
      ALLOW_CONNECT='TRUE';
    'VSS'<1016>:
      PIN_NUMBER='(0,0,0,0,0,0,0,0,0,0,0,0,0,0,0,0,0,0,0,0,0,0,0,R26,0,0,0,0,0,0~
)';
      PINUSE='GROUND';
      NO_LOAD_CHECK='Both';
      NO_IO_CHECK='Both';
      NO_ASSERT_CHECK='TRUE';
      NO_DIR_CHECK='TRUE';
      ALLOW_CONNECT='TRUE';
    'VSS'<1015>:
      PIN_NUMBER='(0,0,0,0,0,0,0,0,0,0,0,0,0,0,0,0,0,0,0,0,0,0,0,R28,0,0,0,0,0,0~
)';
      PINUSE='GROUND';
      NO_LOAD_CHECK='Both';
      NO_IO_CHECK='Both';
      NO_ASSERT_CHECK='TRUE';
      NO_DIR_CHECK='TRUE';
      ALLOW_CONNECT='TRUE';
    'VSS'<1014>:
      PIN_NUMBER='(0,0,0,0,0,0,0,0,0,0,0,0,0,0,0,0,0,0,0,0,0,0,0,R32,0,0,0,0,0,0~
)';
      PINUSE='GROUND';
      NO_LOAD_CHECK='Both';
      NO_IO_CHECK='Both';
      NO_ASSERT_CHECK='TRUE';
      NO_DIR_CHECK='TRUE';
      ALLOW_CONNECT='TRUE';
    'VSS'<1013>:
      PIN_NUMBER='(0,0,0,0,0,0,0,0,0,0,0,0,0,0,0,0,0,0,0,0,0,0,0,R34,0,0,0,0,0,0~
)';
      PINUSE='GROUND';
      NO_LOAD_CHECK='Both';
      NO_IO_CHECK='Both';
      NO_ASSERT_CHECK='TRUE';
      NO_DIR_CHECK='TRUE';
      ALLOW_CONNECT='TRUE';
    'VSS'<1012>:
      PIN_NUMBER='(0,0,0,0,0,0,0,0,0,0,0,0,0,0,0,0,0,0,0,0,0,0,0,R38,0,0,0,0,0,0~
)';
      PINUSE='GROUND';
      NO_LOAD_CHECK='Both';
      NO_IO_CHECK='Both';
      NO_ASSERT_CHECK='TRUE';
      NO_DIR_CHECK='TRUE';
      ALLOW_CONNECT='TRUE';
    'VSS'<1011>:
      PIN_NUMBER='(0,0,0,0,0,0,0,0,0,0,0,0,0,0,0,0,0,0,0,0,0,0,0,R40,0,0,0,0,0,0~
)';
      PINUSE='GROUND';
      NO_LOAD_CHECK='Both';
      NO_IO_CHECK='Both';
      NO_ASSERT_CHECK='TRUE';
      NO_DIR_CHECK='TRUE';
      ALLOW_CONNECT='TRUE';
    'VSS'<1010>:
      PIN_NUMBER='(0,0,0,0,0,0,0,0,0,0,0,0,0,0,0,0,0,0,0,0,0,0,0,R68,0,0,0,0,0,0~
)';
      PINUSE='GROUND';
      NO_LOAD_CHECK='Both';
      NO_IO_CHECK='Both';
      NO_ASSERT_CHECK='TRUE';
      NO_DIR_CHECK='TRUE';
      ALLOW_CONNECT='TRUE';
    'VSS'<1009>:
      PIN_NUMBER='(0,0,0,0,0,0,0,0,0,0,0,0,0,0,0,0,0,0,0,0,0,0,0,R72,0,0,0,0,0,0~
)';
      PINUSE='GROUND';
      NO_LOAD_CHECK='Both';
      NO_IO_CHECK='Both';
      NO_ASSERT_CHECK='TRUE';
      NO_DIR_CHECK='TRUE';
      ALLOW_CONNECT='TRUE';
    'VSS'<1008>:
      PIN_NUMBER='(0,0,0,0,0,0,0,0,0,0,0,0,0,0,0,0,0,0,0,0,0,0,0,R78,0,0,0,0,0,0~
)';
      PINUSE='GROUND';
      NO_LOAD_CHECK='Both';
      NO_IO_CHECK='Both';
      NO_ASSERT_CHECK='TRUE';
      NO_DIR_CHECK='TRUE';
      ALLOW_CONNECT='TRUE';
    'VSS'<1007>:
      PIN_NUMBER='(0,0,0,0,0,0,0,0,0,0,0,0,0,0,0,0,0,0,0,0,0,0,0,R86,0,0,0,0,0,0~
)';
      PINUSE='GROUND';
      NO_LOAD_CHECK='Both';
      NO_IO_CHECK='Both';
      NO_ASSERT_CHECK='TRUE';
      NO_DIR_CHECK='TRUE';
      ALLOW_CONNECT='TRUE';
    'VSS'<1006>:
      PIN_NUMBER='(0,0,0,0,0,0,0,0,0,0,0,0,0,0,0,0,0,0,0,0,0,0,0,T13,0,0,0,0,0,0~
)';
      PINUSE='GROUND';
      NO_LOAD_CHECK='Both';
      NO_IO_CHECK='Both';
      NO_ASSERT_CHECK='TRUE';
      NO_DIR_CHECK='TRUE';
      ALLOW_CONNECT='TRUE';
    'VSS'<1005>:
      PIN_NUMBER='(0,0,0,0,0,0,0,0,0,0,0,0,0,0,0,0,0,0,0,0,0,0,0,T17,0,0,0,0,0,0~
)';
      PINUSE='GROUND';
      NO_LOAD_CHECK='Both';
      NO_IO_CHECK='Both';
      NO_ASSERT_CHECK='TRUE';
      NO_DIR_CHECK='TRUE';
      ALLOW_CONNECT='TRUE';
    'VSS'<1004>:
      PIN_NUMBER='(0,0,0,0,0,0,0,0,0,0,0,0,0,0,0,0,0,0,0,0,0,0,0,T25,0,0,0,0,0,0~
)';
      PINUSE='GROUND';
      NO_LOAD_CHECK='Both';
      NO_IO_CHECK='Both';
      NO_ASSERT_CHECK='TRUE';
      NO_DIR_CHECK='TRUE';
      ALLOW_CONNECT='TRUE';
    'VSS'<1003>:
      PIN_NUMBER='(0,0,0,0,0,0,0,0,0,0,0,0,0,0,0,0,0,0,0,0,0,0,0,T29,0,0,0,0,0,0~
)';
      PINUSE='GROUND';
      NO_LOAD_CHECK='Both';
      NO_IO_CHECK='Both';
      NO_ASSERT_CHECK='TRUE';
      NO_DIR_CHECK='TRUE';
      ALLOW_CONNECT='TRUE';
    'VSS'<1002>:
      PIN_NUMBER='(0,0,0,0,0,0,0,0,0,0,0,0,0,0,0,0,0,0,0,0,0,0,0,T31,0,0,0,0,0,0~
)';
      PINUSE='GROUND';
      NO_LOAD_CHECK='Both';
      NO_IO_CHECK='Both';
      NO_ASSERT_CHECK='TRUE';
      NO_DIR_CHECK='TRUE';
      ALLOW_CONNECT='TRUE';
    'VSS'<1001>:
      PIN_NUMBER='(0,0,0,0,0,0,0,0,0,0,0,0,0,0,0,0,0,0,0,0,0,0,0,T35,0,0,0,0,0,0~
)';
      PINUSE='GROUND';
      NO_LOAD_CHECK='Both';
      NO_IO_CHECK='Both';
      NO_ASSERT_CHECK='TRUE';
      NO_DIR_CHECK='TRUE';
      ALLOW_CONNECT='TRUE';
    'VSS'<1000>:
      PIN_NUMBER='(0,0,0,0,0,0,0,0,0,0,0,0,0,0,0,0,0,0,0,0,0,0,0,T37,0,0,0,0,0,0~
)';
      PINUSE='GROUND';
      NO_LOAD_CHECK='Both';
      NO_IO_CHECK='Both';
      NO_ASSERT_CHECK='TRUE';
      NO_DIR_CHECK='TRUE';
      ALLOW_CONNECT='TRUE';
    'VSS'<999>:
      PIN_NUMBER='(0,0,0,0,0,0,0,0,0,0,0,0,0,0,0,0,0,0,0,0,0,0,0,T41,0,0,0,0,0,0~
)';
      PINUSE='GROUND';
      NO_LOAD_CHECK='Both';
      NO_IO_CHECK='Both';
      NO_ASSERT_CHECK='TRUE';
      NO_DIR_CHECK='TRUE';
      ALLOW_CONNECT='TRUE';
    'VSS'<998>:
      PIN_NUMBER='(0,0,0,0,0,0,0,0,0,0,0,0,0,0,0,0,0,0,0,0,0,0,0,T65,0,0,0,0,0,0~
)';
      PINUSE='GROUND';
      NO_LOAD_CHECK='Both';
      NO_IO_CHECK='Both';
      NO_ASSERT_CHECK='TRUE';
      NO_DIR_CHECK='TRUE';
      ALLOW_CONNECT='TRUE';
    'VSS'<997>:
      PIN_NUMBER='(0,0,0,0,0,0,0,0,0,0,0,0,0,0,0,0,0,0,0,0,0,0,0,T73,0,0,0,0,0,0~
)';
      PINUSE='GROUND';
      NO_LOAD_CHECK='Both';
      NO_IO_CHECK='Both';
      NO_ASSERT_CHECK='TRUE';
      NO_DIR_CHECK='TRUE';
      ALLOW_CONNECT='TRUE';
    'VSS'<996>:
      PIN_NUMBER='(0,0,0,0,0,0,0,0,0,0,0,0,0,0,0,0,0,0,0,0,0,0,0,T77,0,0,0,0,0,0~
)';
      PINUSE='GROUND';
      NO_LOAD_CHECK='Both';
      NO_IO_CHECK='Both';
      NO_ASSERT_CHECK='TRUE';
      NO_DIR_CHECK='TRUE';
      ALLOW_CONNECT='TRUE';
    'VSS'<995>:
      PIN_NUMBER='(0,0,0,0,0,0,0,0,0,0,0,0,0,0,0,0,0,0,0,0,0,0,0,T83,0,0,0,0,0,0~
)';
      PINUSE='GROUND';
      NO_LOAD_CHECK='Both';
      NO_IO_CHECK='Both';
      NO_ASSERT_CHECK='TRUE';
      NO_DIR_CHECK='TRUE';
      ALLOW_CONNECT='TRUE';
    'VSS'<994>:
      PIN_NUMBER='(0,0,0,0,0,0,0,0,0,0,0,0,0,0,0,0,0,0,0,0,0,0,0,T85,0,0,0,0,0,0~
)';
      PINUSE='GROUND';
      NO_LOAD_CHECK='Both';
      NO_IO_CHECK='Both';
      NO_ASSERT_CHECK='TRUE';
      NO_DIR_CHECK='TRUE';
      ALLOW_CONNECT='TRUE';
    'VSS'<993>:
      PIN_NUMBER='(0,0,0,0,0,0,0,0,0,0,0,0,0,0,0,0,0,0,0,0,0,0,0,U2,0,0,0,0,0,0)~
';
      PINUSE='GROUND';
      NO_LOAD_CHECK='Both';
      NO_IO_CHECK='Both';
      NO_ASSERT_CHECK='TRUE';
      NO_DIR_CHECK='TRUE';
      ALLOW_CONNECT='TRUE';
    'VSS'<992>:
      PIN_NUMBER='(0,0,0,0,0,0,0,0,0,0,0,0,0,0,0,0,0,0,0,0,0,0,0,U4,0,0,0,0,0,0)~
';
      PINUSE='GROUND';
      NO_LOAD_CHECK='Both';
      NO_IO_CHECK='Both';
      NO_ASSERT_CHECK='TRUE';
      NO_DIR_CHECK='TRUE';
      ALLOW_CONNECT='TRUE';
    'VSS'<991>:
      PIN_NUMBER='(0,0,0,0,0,0,0,0,0,0,0,0,0,0,0,0,0,0,0,0,0,0,0,U6,0,0,0,0,0,0)~
';
      PINUSE='GROUND';
      NO_LOAD_CHECK='Both';
      NO_IO_CHECK='Both';
      NO_ASSERT_CHECK='TRUE';
      NO_DIR_CHECK='TRUE';
      ALLOW_CONNECT='TRUE';
    'VSS'<990>:
      PIN_NUMBER='(0,0,0,0,0,0,0,0,0,0,0,0,0,0,0,0,0,0,0,0,0,0,0,U20,0,0,0,0,0,0~
)';
      PINUSE='GROUND';
      NO_LOAD_CHECK='Both';
      NO_IO_CHECK='Both';
      NO_ASSERT_CHECK='TRUE';
      NO_DIR_CHECK='TRUE';
      ALLOW_CONNECT='TRUE';
    'VSS'<989>:
      PIN_NUMBER='(0,0,0,0,0,0,0,0,0,0,0,0,0,0,0,0,0,0,0,0,0,0,0,U22,0,0,0,0,0,0~
)';
      PINUSE='GROUND';
      NO_LOAD_CHECK='Both';
      NO_IO_CHECK='Both';
      NO_ASSERT_CHECK='TRUE';
      NO_DIR_CHECK='TRUE';
      ALLOW_CONNECT='TRUE';
    'VSS'<988>:
      PIN_NUMBER='(0,0,0,0,0,0,0,0,0,0,0,0,0,0,0,0,0,0,0,0,0,0,0,U24,0,0,0,0,0,0~
)';
      PINUSE='GROUND';
      NO_LOAD_CHECK='Both';
      NO_IO_CHECK='Both';
      NO_ASSERT_CHECK='TRUE';
      NO_DIR_CHECK='TRUE';
      ALLOW_CONNECT='TRUE';
    'VSS'<987>:
      PIN_NUMBER='(0,0,0,0,0,0,0,0,0,0,0,0,0,0,0,0,0,0,0,0,0,0,0,U30,0,0,0,0,0,0~
)';
      PINUSE='GROUND';
      NO_LOAD_CHECK='Both';
      NO_IO_CHECK='Both';
      NO_ASSERT_CHECK='TRUE';
      NO_DIR_CHECK='TRUE';
      ALLOW_CONNECT='TRUE';
    'VSS'<986>:
      PIN_NUMBER='(0,0,0,0,0,0,0,0,0,0,0,0,0,0,0,0,0,0,0,0,0,0,0,U36,0,0,0,0,0,0~
)';
      PINUSE='GROUND';
      NO_LOAD_CHECK='Both';
      NO_IO_CHECK='Both';
      NO_ASSERT_CHECK='TRUE';
      NO_DIR_CHECK='TRUE';
      ALLOW_CONNECT='TRUE';
    'VSS'<985>:
      PIN_NUMBER='(0,0,0,0,0,0,0,0,0,0,0,0,0,0,0,0,0,0,0,0,0,0,0,U42,0,0,0,0,0,0~
)';
      PINUSE='GROUND';
      NO_LOAD_CHECK='Both';
      NO_IO_CHECK='Both';
      NO_ASSERT_CHECK='TRUE';
      NO_DIR_CHECK='TRUE';
      ALLOW_CONNECT='TRUE';
    'VSS'<984>:
      PIN_NUMBER='(0,0,0,0,0,0,0,0,0,0,0,0,0,0,0,0,0,0,0,0,0,0,0,U68,0,0,0,0,0,0~
)';
      PINUSE='GROUND';
      NO_LOAD_CHECK='Both';
      NO_IO_CHECK='Both';
      NO_ASSERT_CHECK='TRUE';
      NO_DIR_CHECK='TRUE';
      ALLOW_CONNECT='TRUE';
    'VSS'<983>:
      PIN_NUMBER='(0,0,0,0,0,0,0,0,0,0,0,0,0,0,0,0,0,0,0,0,0,0,0,U70,0,0,0,0,0,0~
)';
      PINUSE='GROUND';
      NO_LOAD_CHECK='Both';
      NO_IO_CHECK='Both';
      NO_ASSERT_CHECK='TRUE';
      NO_DIR_CHECK='TRUE';
      ALLOW_CONNECT='TRUE';
    'VSS'<982>:
      PIN_NUMBER='(0,0,0,0,0,0,0,0,0,0,0,0,0,0,0,0,0,0,0,0,0,0,0,U74,0,0,0,0,0,0~
)';
      PINUSE='GROUND';
      NO_LOAD_CHECK='Both';
      NO_IO_CHECK='Both';
      NO_ASSERT_CHECK='TRUE';
      NO_DIR_CHECK='TRUE';
      ALLOW_CONNECT='TRUE';
    'VSS'<981>:
      PIN_NUMBER='(0,0,0,0,0,0,0,0,0,0,0,0,0,0,0,0,0,0,0,0,0,0,0,U76,0,0,0,0,0,0~
)';
      PINUSE='GROUND';
      NO_LOAD_CHECK='Both';
      NO_IO_CHECK='Both';
      NO_ASSERT_CHECK='TRUE';
      NO_DIR_CHECK='TRUE';
      ALLOW_CONNECT='TRUE';
    'VSS'<980>:
      PIN_NUMBER='(0,0,0,0,0,0,0,0,0,0,0,0,0,0,0,0,0,0,0,0,0,0,0,U78,0,0,0,0,0,0~
)';
      PINUSE='GROUND';
      NO_LOAD_CHECK='Both';
      NO_IO_CHECK='Both';
      NO_ASSERT_CHECK='TRUE';
      NO_DIR_CHECK='TRUE';
      ALLOW_CONNECT='TRUE';
    'VSS'<979>:
      PIN_NUMBER='(0,0,0,0,0,0,0,0,0,0,0,0,0,0,0,0,0,0,0,0,0,0,0,U80,0,0,0,0,0,0~
)';
      PINUSE='GROUND';
      NO_LOAD_CHECK='Both';
      NO_IO_CHECK='Both';
      NO_ASSERT_CHECK='TRUE';
      NO_DIR_CHECK='TRUE';
      ALLOW_CONNECT='TRUE';
    'VSS'<978>:
      PIN_NUMBER='(0,0,0,0,0,0,0,0,0,0,0,0,0,0,0,0,0,0,0,0,0,0,0,U86,0,0,0,0,0,0~
)';
      PINUSE='GROUND';
      NO_LOAD_CHECK='Both';
      NO_IO_CHECK='Both';
      NO_ASSERT_CHECK='TRUE';
      NO_DIR_CHECK='TRUE';
      ALLOW_CONNECT='TRUE';
    'VSS'<977>:
      PIN_NUMBER='(0,0,0,0,0,0,0,0,0,0,0,0,0,0,0,0,0,0,0,0,0,0,0,V1,0,0,0,0,0,0)~
';
      PINUSE='GROUND';
      NO_LOAD_CHECK='Both';
      NO_IO_CHECK='Both';
      NO_ASSERT_CHECK='TRUE';
      NO_DIR_CHECK='TRUE';
      ALLOW_CONNECT='TRUE';
    'VSS'<976>:
      PIN_NUMBER='(0,0,0,0,0,0,0,0,0,0,0,0,0,0,0,0,0,0,0,0,0,0,0,V5,0,0,0,0,0,0)~
';
      PINUSE='GROUND';
      NO_LOAD_CHECK='Both';
      NO_IO_CHECK='Both';
      NO_ASSERT_CHECK='TRUE';
      NO_DIR_CHECK='TRUE';
      ALLOW_CONNECT='TRUE';
    'VSS'<975>:
      PIN_NUMBER='(0,0,0,0,0,0,0,0,0,0,0,0,0,0,0,0,0,0,0,0,0,0,0,V9,0,0,0,0,0,0)~
';
      PINUSE='GROUND';
      NO_LOAD_CHECK='Both';
      NO_IO_CHECK='Both';
      NO_ASSERT_CHECK='TRUE';
      NO_DIR_CHECK='TRUE';
      ALLOW_CONNECT='TRUE';
    'VSS'<974>:
      PIN_NUMBER='(0,0,0,0,0,0,0,0,0,0,0,0,0,0,0,0,0,0,0,0,0,0,0,V13,0,0,0,0,0,0~
)';
      PINUSE='GROUND';
      NO_LOAD_CHECK='Both';
      NO_IO_CHECK='Both';
      NO_ASSERT_CHECK='TRUE';
      NO_DIR_CHECK='TRUE';
      ALLOW_CONNECT='TRUE';
    'VSS'<973>:
      PIN_NUMBER='(0,0,0,0,0,0,0,0,0,0,0,0,0,0,0,0,0,0,0,0,0,0,0,V15,0,0,0,0,0,0~
)';
      PINUSE='GROUND';
      NO_LOAD_CHECK='Both';
      NO_IO_CHECK='Both';
      NO_ASSERT_CHECK='TRUE';
      NO_DIR_CHECK='TRUE';
      ALLOW_CONNECT='TRUE';
    'VSS'<972>:
      PIN_NUMBER='(0,0,0,0,0,0,0,0,0,0,0,0,0,0,0,0,0,0,0,0,0,0,0,V21,0,0,0,0,0,0~
)';
      PINUSE='GROUND';
      NO_LOAD_CHECK='Both';
      NO_IO_CHECK='Both';
      NO_ASSERT_CHECK='TRUE';
      NO_DIR_CHECK='TRUE';
      ALLOW_CONNECT='TRUE';
    'VSS'<971>:
      PIN_NUMBER='(0,0,0,0,0,0,0,0,0,0,0,0,0,0,0,0,0,0,0,0,0,0,0,V23,0,0,0,0,0,0~
)';
      PINUSE='GROUND';
      NO_LOAD_CHECK='Both';
      NO_IO_CHECK='Both';
      NO_ASSERT_CHECK='TRUE';
      NO_DIR_CHECK='TRUE';
      ALLOW_CONNECT='TRUE';
    'VSS'<970>:
      PIN_NUMBER='(0,0,0,0,0,0,0,0,0,0,0,0,0,0,0,0,0,0,0,0,0,0,0,V43,0,0,0,0,0,0~
)';
      PINUSE='GROUND';
      NO_LOAD_CHECK='Both';
      NO_IO_CHECK='Both';
      NO_ASSERT_CHECK='TRUE';
      NO_DIR_CHECK='TRUE';
      ALLOW_CONNECT='TRUE';
    'VSS'<969>:
      PIN_NUMBER='(0,0,0,0,0,0,0,0,0,0,0,0,0,0,0,0,0,0,0,0,0,0,0,V73,0,0,0,0,0,0~
)';
      PINUSE='GROUND';
      NO_LOAD_CHECK='Both';
      NO_IO_CHECK='Both';
      NO_ASSERT_CHECK='TRUE';
      NO_DIR_CHECK='TRUE';
      ALLOW_CONNECT='TRUE';
    'VSS'<968>:
      PIN_NUMBER='(0,0,0,0,0,0,0,0,0,0,0,0,0,0,0,0,0,0,0,0,0,0,0,V75,0,0,0,0,0,0~
)';
      PINUSE='GROUND';
      NO_LOAD_CHECK='Both';
      NO_IO_CHECK='Both';
      NO_ASSERT_CHECK='TRUE';
      NO_DIR_CHECK='TRUE';
      ALLOW_CONNECT='TRUE';
    'VSS'<967>:
      PIN_NUMBER='(0,0,0,0,0,0,0,0,0,0,0,0,0,0,0,0,0,0,0,0,0,0,0,V77,0,0,0,0,0,0~
)';
      PINUSE='GROUND';
      NO_LOAD_CHECK='Both';
      NO_IO_CHECK='Both';
      NO_ASSERT_CHECK='TRUE';
      NO_DIR_CHECK='TRUE';
      ALLOW_CONNECT='TRUE';
    'VSS'<966>:
      PIN_NUMBER='(0,0,0,0,0,0,0,0,0,0,0,0,0,0,0,0,0,0,0,0,0,0,0,V83,0,0,0,0,0,0~
)';
      PINUSE='GROUND';
      NO_LOAD_CHECK='Both';
      NO_IO_CHECK='Both';
      NO_ASSERT_CHECK='TRUE';
      NO_DIR_CHECK='TRUE';
      ALLOW_CONNECT='TRUE';
    'VSS'<965>:
      PIN_NUMBER='(0,0,0,0,0,0,0,0,0,0,0,0,0,0,0,0,0,0,0,0,0,0,0,W8,0,0,0,0,0,0)~
';
      PINUSE='GROUND';
      NO_LOAD_CHECK='Both';
      NO_IO_CHECK='Both';
      NO_ASSERT_CHECK='TRUE';
      NO_DIR_CHECK='TRUE';
      ALLOW_CONNECT='TRUE';
    'VSS'<964>:
      PIN_NUMBER='(0,0,0,0,0,0,0,0,0,0,0,0,0,0,0,0,0,0,0,0,0,0,0,AC56,0,0,0,0,0,~
0)';
      PINUSE='GROUND';
      NO_LOAD_CHECK='Both';
      NO_IO_CHECK='Both';
      NO_ASSERT_CHECK='TRUE';
      NO_DIR_CHECK='TRUE';
      ALLOW_CONNECT='TRUE';
    'VSS'<963>:
      PIN_NUMBER='(0,0,0,0,0,0,0,0,0,0,0,0,0,0,0,0,0,0,0,0,0,0,0,W12,0,0,0,0,0,0~
)';
      PINUSE='GROUND';
      NO_LOAD_CHECK='Both';
      NO_IO_CHECK='Both';
      NO_ASSERT_CHECK='TRUE';
      NO_DIR_CHECK='TRUE';
      ALLOW_CONNECT='TRUE';
    'VSS'<962>:
      PIN_NUMBER='(0,0,0,0,0,0,0,0,0,0,0,0,0,0,0,0,0,0,0,0,0,0,0,W22,0,0,0,0,0,0~
)';
      PINUSE='GROUND';
      NO_LOAD_CHECK='Both';
      NO_IO_CHECK='Both';
      NO_ASSERT_CHECK='TRUE';
      NO_DIR_CHECK='TRUE';
      ALLOW_CONNECT='TRUE';
    'VSS'<961>:
      PIN_NUMBER='(0,0,0,0,0,0,0,0,0,0,0,0,0,0,0,0,0,0,0,0,0,0,0,W24,0,0,0,0,0,0~
)';
      PINUSE='GROUND';
      NO_LOAD_CHECK='Both';
      NO_IO_CHECK='Both';
      NO_ASSERT_CHECK='TRUE';
      NO_DIR_CHECK='TRUE';
      ALLOW_CONNECT='TRUE';
    'VSS'<960>:
      PIN_NUMBER='(0,0,0,0,0,0,0,0,0,0,0,0,0,0,0,0,0,0,0,0,0,0,0,W26,0,0,0,0,0,0~
)';
      PINUSE='GROUND';
      NO_LOAD_CHECK='Both';
      NO_IO_CHECK='Both';
      NO_ASSERT_CHECK='TRUE';
      NO_DIR_CHECK='TRUE';
      ALLOW_CONNECT='TRUE';
    'VSS'<959>:
      PIN_NUMBER='(0,0,0,0,0,0,0,0,0,0,0,0,0,0,0,0,0,0,0,0,0,0,0,W28,0,0,0,0,0,0~
)';
      PINUSE='GROUND';
      NO_LOAD_CHECK='Both';
      NO_IO_CHECK='Both';
      NO_ASSERT_CHECK='TRUE';
      NO_DIR_CHECK='TRUE';
      ALLOW_CONNECT='TRUE';
    'VSS'<958>:
      PIN_NUMBER='(0,0,0,0,0,0,0,0,0,0,0,0,0,0,0,0,0,0,0,0,0,0,0,W30,0,0,0,0,0,0~
)';
      PINUSE='GROUND';
      NO_LOAD_CHECK='Both';
      NO_IO_CHECK='Both';
      NO_ASSERT_CHECK='TRUE';
      NO_DIR_CHECK='TRUE';
      ALLOW_CONNECT='TRUE';
    'VSS'<957>:
      PIN_NUMBER='(0,0,0,0,0,0,0,0,0,0,0,0,0,0,0,0,0,0,0,0,0,0,0,W32,0,0,0,0,0,0~
)';
      PINUSE='GROUND';
      NO_LOAD_CHECK='Both';
      NO_IO_CHECK='Both';
      NO_ASSERT_CHECK='TRUE';
      NO_DIR_CHECK='TRUE';
      ALLOW_CONNECT='TRUE';
    'VSS'<956>:
      PIN_NUMBER='(0,0,0,0,0,0,0,0,0,0,0,0,0,0,0,0,0,0,0,0,0,0,0,W34,0,0,0,0,0,0~
)';
      PINUSE='GROUND';
      NO_LOAD_CHECK='Both';
      NO_IO_CHECK='Both';
      NO_ASSERT_CHECK='TRUE';
      NO_DIR_CHECK='TRUE';
      ALLOW_CONNECT='TRUE';
    'VSS'<955>:
      PIN_NUMBER='(0,0,0,0,0,0,0,0,0,0,0,0,0,0,0,0,0,0,0,0,0,0,0,W36,0,0,0,0,0,0~
)';
      PINUSE='GROUND';
      NO_LOAD_CHECK='Both';
      NO_IO_CHECK='Both';
      NO_ASSERT_CHECK='TRUE';
      NO_DIR_CHECK='TRUE';
      ALLOW_CONNECT='TRUE';
    'VSS'<954>:
      PIN_NUMBER='(0,0,0,0,0,0,0,0,0,0,0,0,0,0,0,0,0,0,0,0,0,0,0,W38,0,0,0,0,0,0~
)';
      PINUSE='GROUND';
      NO_LOAD_CHECK='Both';
      NO_IO_CHECK='Both';
      NO_ASSERT_CHECK='TRUE';
      NO_DIR_CHECK='TRUE';
      ALLOW_CONNECT='TRUE';
    'VSS'<953>:
      PIN_NUMBER='(0,0,0,0,0,0,0,0,0,0,0,0,0,0,0,0,0,0,0,0,0,0,0,W40,0,0,0,0,0,0~
)';
      PINUSE='GROUND';
      NO_LOAD_CHECK='Both';
      NO_IO_CHECK='Both';
      NO_ASSERT_CHECK='TRUE';
      NO_DIR_CHECK='TRUE';
      ALLOW_CONNECT='TRUE';
    'VSS'<952>:
      PIN_NUMBER='(0,0,0,0,0,0,0,0,0,0,0,0,0,0,0,0,0,0,0,0,0,0,0,W42,0,0,0,0,0,0~
)';
      PINUSE='GROUND';
      NO_LOAD_CHECK='Both';
      NO_IO_CHECK='Both';
      NO_ASSERT_CHECK='TRUE';
      NO_DIR_CHECK='TRUE';
      ALLOW_CONNECT='TRUE';
    'VSS'<951>:
      PIN_NUMBER='(0,0,0,0,0,0,0,0,0,0,0,0,0,0,0,0,0,0,0,0,0,0,0,W68,0,0,0,0,0,0~
)';
      PINUSE='GROUND';
      NO_LOAD_CHECK='Both';
      NO_IO_CHECK='Both';
      NO_ASSERT_CHECK='TRUE';
      NO_DIR_CHECK='TRUE';
      ALLOW_CONNECT='TRUE';
    'VSS'<950>:
      PIN_NUMBER='(0,0,0,0,0,0,0,0,0,0,0,0,0,0,0,0,0,0,0,0,0,0,0,W74,0,0,0,0,0,0~
)';
      PINUSE='GROUND';
      NO_LOAD_CHECK='Both';
      NO_IO_CHECK='Both';
      NO_ASSERT_CHECK='TRUE';
      NO_DIR_CHECK='TRUE';
      ALLOW_CONNECT='TRUE';
    'VSS'<949>:
      PIN_NUMBER='(0,0,0,0,0,0,0,0,0,0,0,0,0,0,0,0,0,0,0,0,0,0,0,W78,0,0,0,0,0,0~
)';
      PINUSE='GROUND';
      NO_LOAD_CHECK='Both';
      NO_IO_CHECK='Both';
      NO_ASSERT_CHECK='TRUE';
      NO_DIR_CHECK='TRUE';
      ALLOW_CONNECT='TRUE';
    'VSS'<948>:
      PIN_NUMBER='(0,0,0,0,0,0,0,0,0,0,0,0,0,0,0,0,0,0,0,0,0,0,0,W82,0,0,0,0,0,0~
)';
      PINUSE='GROUND';
      NO_LOAD_CHECK='Both';
      NO_IO_CHECK='Both';
      NO_ASSERT_CHECK='TRUE';
      NO_DIR_CHECK='TRUE';
      ALLOW_CONNECT='TRUE';
    'VSS'<947>:
      PIN_NUMBER='(0,0,0,0,0,0,0,0,0,0,0,0,0,0,0,0,0,0,0,0,0,0,0,Y15,0,0,0,0,0,0~
)';
      PINUSE='GROUND';
      NO_LOAD_CHECK='Both';
      NO_IO_CHECK='Both';
      NO_ASSERT_CHECK='TRUE';
      NO_DIR_CHECK='TRUE';
      ALLOW_CONNECT='TRUE';
    'VSS'<946>:
      PIN_NUMBER='(0,0,0,0,0,0,0,0,0,0,0,0,0,0,0,0,0,0,0,0,0,0,0,Y17,0,0,0,0,0,0~
)';
      PINUSE='GROUND';
      NO_LOAD_CHECK='Both';
      NO_IO_CHECK='Both';
      NO_ASSERT_CHECK='TRUE';
      NO_DIR_CHECK='TRUE';
      ALLOW_CONNECT='TRUE';
    'VSS'<945>:
      PIN_NUMBER='(0,0,0,0,0,0,0,0,0,0,0,0,0,0,0,0,0,0,0,0,0,0,0,Y5,0,0,0,0,0,0)~
';
      PINUSE='GROUND';
      NO_LOAD_CHECK='Both';
      NO_IO_CHECK='Both';
      NO_ASSERT_CHECK='TRUE';
      NO_DIR_CHECK='TRUE';
      ALLOW_CONNECT='TRUE';
    'VSS'<944>:
      PIN_NUMBER='(0,0,0,0,0,0,0,0,0,0,0,0,0,0,0,0,0,0,0,0,0,0,0,Y67,0,0,0,0,0,0~
)';
      PINUSE='GROUND';
      NO_LOAD_CHECK='Both';
      NO_IO_CHECK='Both';
      NO_ASSERT_CHECK='TRUE';
      NO_DIR_CHECK='TRUE';
      ALLOW_CONNECT='TRUE';
    'VSS'<943>:
      PIN_NUMBER='(0,0,0,0,0,0,0,0,0,0,0,0,0,0,0,0,0,0,0,0,0,0,0,Y7,0,0,0,0,0,0)~
';
      PINUSE='GROUND';
      NO_LOAD_CHECK='Both';
      NO_IO_CHECK='Both';
      NO_ASSERT_CHECK='TRUE';
      NO_DIR_CHECK='TRUE';
      ALLOW_CONNECT='TRUE';
    'VSS'<942>:
      PIN_NUMBER='(0,0,0,0,0,0,0,0,0,0,0,0,0,0,0,0,0,0,0,0,0,0,0,Y9,0,0,0,0,0,0)~
';
      PINUSE='GROUND';
      NO_LOAD_CHECK='Both';
      NO_IO_CHECK='Both';
      NO_ASSERT_CHECK='TRUE';
      NO_DIR_CHECK='TRUE';
      ALLOW_CONNECT='TRUE';
    'VSS'<941>:
      PIN_NUMBER='(0,0,0,0,0,0,0,0,0,0,0,0,0,0,0,0,0,0,0,0,0,0,0,Y71,0,0,0,0,0,0~
)';
      PINUSE='GROUND';
      NO_LOAD_CHECK='Both';
      NO_IO_CHECK='Both';
      NO_ASSERT_CHECK='TRUE';
      NO_DIR_CHECK='TRUE';
      ALLOW_CONNECT='TRUE';
    'VSS'<940>:
      PIN_NUMBER='(0,0,0,0,0,0,0,0,0,0,0,0,0,0,0,0,0,0,0,0,0,0,0,Y73,0,0,0,0,0,0~
)';
      PINUSE='GROUND';
      NO_LOAD_CHECK='Both';
      NO_IO_CHECK='Both';
      NO_ASSERT_CHECK='TRUE';
      NO_DIR_CHECK='TRUE';
      ALLOW_CONNECT='TRUE';
    'VSS'<939>:
      PIN_NUMBER='(0,0,0,0,0,0,0,0,0,0,0,0,0,0,0,0,0,0,0,0,0,0,0,Y79,0,0,0,0,0,0~
)';
      PINUSE='GROUND';
      NO_LOAD_CHECK='Both';
      NO_IO_CHECK='Both';
      NO_ASSERT_CHECK='TRUE';
      NO_DIR_CHECK='TRUE';
      ALLOW_CONNECT='TRUE';
    'VSS'<938>:
      PIN_NUMBER='(0,0,0,0,0,0,0,0,0,0,0,0,0,0,0,0,0,0,0,0,0,0,0,Y81,0,0,0,0,0,0~
)';
      PINUSE='GROUND';
      NO_LOAD_CHECK='Both';
      NO_IO_CHECK='Both';
      NO_ASSERT_CHECK='TRUE';
      NO_DIR_CHECK='TRUE';
      ALLOW_CONNECT='TRUE';
    'VSS'<937>:
      PIN_NUMBER='(0,0,0,0,0,0,0,0,0,0,0,0,0,0,0,0,0,0,0,0,0,0,0,Y83,0,0,0,0,0,0~
)';
      PINUSE='GROUND';
      NO_LOAD_CHECK='Both';
      NO_IO_CHECK='Both';
      NO_ASSERT_CHECK='TRUE';
      NO_DIR_CHECK='TRUE';
      ALLOW_CONNECT='TRUE';
    'VSS'<936>:
      PIN_NUMBER='(0,0,0,0,0,0,0,0,0,0,0,0,0,0,0,0,0,0,0,0,0,0,0,Y85,0,0,0,0,0,0~
)';
      PINUSE='GROUND';
      NO_LOAD_CHECK='Both';
      NO_IO_CHECK='Both';
      NO_ASSERT_CHECK='TRUE';
      NO_DIR_CHECK='TRUE';
      ALLOW_CONNECT='TRUE';
    'VSS'<935>:
      PIN_NUMBER='(0,0,0,0,0,0,0,0,0,0,0,0,0,0,0,0,0,0,0,0,0,0,0,AA4,0,0,0,0,0,0~
)';
      PINUSE='GROUND';
      NO_LOAD_CHECK='Both';
      NO_IO_CHECK='Both';
      NO_ASSERT_CHECK='TRUE';
      NO_DIR_CHECK='TRUE';
      ALLOW_CONNECT='TRUE';
    'VSS'<934>:
      PIN_NUMBER='(0,0,0,0,0,0,0,0,0,0,0,0,0,0,0,0,0,0,0,0,0,0,0,AA16,0,0,0,0,0,~
0)';
      PINUSE='GROUND';
      NO_LOAD_CHECK='Both';
      NO_IO_CHECK='Both';
      NO_ASSERT_CHECK='TRUE';
      NO_DIR_CHECK='TRUE';
      ALLOW_CONNECT='TRUE';
    'VSS'<933>:
      PIN_NUMBER='(0,0,0,0,0,0,0,0,0,0,0,0,0,0,0,0,0,0,0,0,0,0,0,0,AA18,0,0,0,0,~
0)';
      PINUSE='GROUND';
      NO_LOAD_CHECK='Both';
      NO_IO_CHECK='Both';
      NO_ASSERT_CHECK='TRUE';
      NO_DIR_CHECK='TRUE';
      ALLOW_CONNECT='TRUE';
    'VSS'<932>:
      PIN_NUMBER='(0,0,0,0,0,0,0,0,0,0,0,0,0,0,0,0,0,0,0,0,0,0,0,0,AA22,0,0,0,0,~
0)';
      PINUSE='GROUND';
      NO_LOAD_CHECK='Both';
      NO_IO_CHECK='Both';
      NO_ASSERT_CHECK='TRUE';
      NO_DIR_CHECK='TRUE';
      ALLOW_CONNECT='TRUE';
    'VSS'<931>:
      PIN_NUMBER='(0,0,0,0,0,0,0,0,0,0,0,0,0,0,0,0,0,0,0,0,0,0,0,0,AA24,0,0,0,0,~
0)';
      PINUSE='GROUND';
      NO_LOAD_CHECK='Both';
      NO_IO_CHECK='Both';
      NO_ASSERT_CHECK='TRUE';
      NO_DIR_CHECK='TRUE';
      ALLOW_CONNECT='TRUE';
    'VSS'<930>:
      PIN_NUMBER='(0,0,0,0,0,0,0,0,0,0,0,0,0,0,0,0,0,0,0,0,0,0,0,0,AA30,0,0,0,0,~
0)';
      PINUSE='GROUND';
      NO_LOAD_CHECK='Both';
      NO_IO_CHECK='Both';
      NO_ASSERT_CHECK='TRUE';
      NO_DIR_CHECK='TRUE';
      ALLOW_CONNECT='TRUE';
    'VSS'<929>:
      PIN_NUMBER='(0,0,0,0,0,0,0,0,0,0,0,0,0,0,0,0,0,0,0,0,0,0,0,0,AA36,0,0,0,0,~
0)';
      PINUSE='GROUND';
      NO_LOAD_CHECK='Both';
      NO_IO_CHECK='Both';
      NO_ASSERT_CHECK='TRUE';
      NO_DIR_CHECK='TRUE';
      ALLOW_CONNECT='TRUE';
    'VSS'<928>:
      PIN_NUMBER='(0,0,0,0,0,0,0,0,0,0,0,0,0,0,0,0,0,0,0,0,0,0,0,0,AA42,0,0,0,0,~
0)';
      PINUSE='GROUND';
      NO_LOAD_CHECK='Both';
      NO_IO_CHECK='Both';
      NO_ASSERT_CHECK='TRUE';
      NO_DIR_CHECK='TRUE';
      ALLOW_CONNECT='TRUE';
    'VSS'<927>:
      PIN_NUMBER='(0,0,0,0,0,0,0,0,0,0,0,0,0,0,0,0,0,0,0,0,0,0,0,0,AA64,0,0,0,0,~
0)';
      PINUSE='GROUND';
      NO_LOAD_CHECK='Both';
      NO_IO_CHECK='Both';
      NO_ASSERT_CHECK='TRUE';
      NO_DIR_CHECK='TRUE';
      ALLOW_CONNECT='TRUE';
    'VSS'<926>:
      PIN_NUMBER='(0,0,0,0,0,0,0,0,0,0,0,0,0,0,0,0,0,0,0,0,0,0,0,0,AA66,0,0,0,0,~
0)';
      PINUSE='GROUND';
      NO_LOAD_CHECK='Both';
      NO_IO_CHECK='Both';
      NO_ASSERT_CHECK='TRUE';
      NO_DIR_CHECK='TRUE';
      ALLOW_CONNECT='TRUE';
    'VSS'<925>:
      PIN_NUMBER='(0,0,0,0,0,0,0,0,0,0,0,0,0,0,0,0,0,0,0,0,0,0,0,0,AA68,0,0,0,0,~
0)';
      PINUSE='GROUND';
      NO_LOAD_CHECK='Both';
      NO_IO_CHECK='Both';
      NO_ASSERT_CHECK='TRUE';
      NO_DIR_CHECK='TRUE';
      ALLOW_CONNECT='TRUE';
    'VSS'<924>:
      PIN_NUMBER='(0,0,0,0,0,0,0,0,0,0,0,0,0,0,0,0,0,0,0,0,0,0,0,0,AA76,0,0,0,0,~
0)';
      PINUSE='GROUND';
      NO_LOAD_CHECK='Both';
      NO_IO_CHECK='Both';
      NO_ASSERT_CHECK='TRUE';
      NO_DIR_CHECK='TRUE';
      ALLOW_CONNECT='TRUE';
    'VSS'<923>:
      PIN_NUMBER='(0,0,0,0,0,0,0,0,0,0,0,0,0,0,0,0,0,0,0,0,0,0,0,0,AA78,0,0,0,0,~
0)';
      PINUSE='GROUND';
      NO_LOAD_CHECK='Both';
      NO_IO_CHECK='Both';
      NO_ASSERT_CHECK='TRUE';
      NO_DIR_CHECK='TRUE';
      ALLOW_CONNECT='TRUE';
    'VSS'<922>:
      PIN_NUMBER='(0,0,0,0,0,0,0,0,0,0,0,0,0,0,0,0,0,0,0,0,0,0,0,0,AA80,0,0,0,0,~
0)';
      PINUSE='GROUND';
      NO_LOAD_CHECK='Both';
      NO_IO_CHECK='Both';
      NO_ASSERT_CHECK='TRUE';
      NO_DIR_CHECK='TRUE';
      ALLOW_CONNECT='TRUE';
    'VSS'<921>:
      PIN_NUMBER='(0,0,0,0,0,0,0,0,0,0,0,0,0,0,0,0,0,0,0,0,0,0,0,0,AA82,0,0,0,0,~
0)';
      PINUSE='GROUND';
      NO_LOAD_CHECK='Both';
      NO_IO_CHECK='Both';
      NO_ASSERT_CHECK='TRUE';
      NO_DIR_CHECK='TRUE';
      ALLOW_CONNECT='TRUE';
    'VSS'<920>:
      PIN_NUMBER='(0,0,0,0,0,0,0,0,0,0,0,0,0,0,0,0,0,0,0,0,0,0,0,0,AB1,0,0,0,0,0~
)';
      PINUSE='GROUND';
      NO_LOAD_CHECK='Both';
      NO_IO_CHECK='Both';
      NO_ASSERT_CHECK='TRUE';
      NO_DIR_CHECK='TRUE';
      ALLOW_CONNECT='TRUE';
    'VSS'<919>:
      PIN_NUMBER='(0,0,0,0,0,0,0,0,0,0,0,0,0,0,0,0,0,0,0,0,0,0,0,0,AB5,0,0,0,0,0~
)';
      PINUSE='GROUND';
      NO_LOAD_CHECK='Both';
      NO_IO_CHECK='Both';
      NO_ASSERT_CHECK='TRUE';
      NO_DIR_CHECK='TRUE';
      ALLOW_CONNECT='TRUE';
    'VSS'<918>:
      PIN_NUMBER='(0,0,0,0,0,0,0,0,0,0,0,0,0,0,0,0,0,0,0,0,0,0,0,0,AB11,0,0,0,0,~
0)';
      PINUSE='GROUND';
      NO_LOAD_CHECK='Both';
      NO_IO_CHECK='Both';
      NO_ASSERT_CHECK='TRUE';
      NO_DIR_CHECK='TRUE';
      ALLOW_CONNECT='TRUE';
    'VSS'<917>:
      PIN_NUMBER='(0,0,0,0,0,0,0,0,0,0,0,0,0,0,0,0,0,0,0,0,0,0,0,0,AB21,0,0,0,0,~
0)';
      PINUSE='GROUND';
      NO_LOAD_CHECK='Both';
      NO_IO_CHECK='Both';
      NO_ASSERT_CHECK='TRUE';
      NO_DIR_CHECK='TRUE';
      ALLOW_CONNECT='TRUE';
    'VSS'<916>:
      PIN_NUMBER='(0,0,0,0,0,0,0,0,0,0,0,0,0,0,0,0,0,0,0,0,0,0,0,0,AB23,0,0,0,0,~
0)';
      PINUSE='GROUND';
      NO_LOAD_CHECK='Both';
      NO_IO_CHECK='Both';
      NO_ASSERT_CHECK='TRUE';
      NO_DIR_CHECK='TRUE';
      ALLOW_CONNECT='TRUE';
    'VSS'<915>:
      PIN_NUMBER='(0,0,0,0,0,0,0,0,0,0,0,0,0,0,0,0,0,0,0,0,0,0,0,0,AB25,0,0,0,0,~
0)';
      PINUSE='GROUND';
      NO_LOAD_CHECK='Both';
      NO_IO_CHECK='Both';
      NO_ASSERT_CHECK='TRUE';
      NO_DIR_CHECK='TRUE';
      ALLOW_CONNECT='TRUE';
    'VSS'<914>:
      PIN_NUMBER='(0,0,0,0,0,0,0,0,0,0,0,0,0,0,0,0,0,0,0,0,0,0,0,0,AB29,0,0,0,0,~
0)';
      PINUSE='GROUND';
      NO_LOAD_CHECK='Both';
      NO_IO_CHECK='Both';
      NO_ASSERT_CHECK='TRUE';
      NO_DIR_CHECK='TRUE';
      ALLOW_CONNECT='TRUE';
    'VSS'<913>:
      PIN_NUMBER='(0,0,0,0,0,0,0,0,0,0,0,0,0,0,0,0,0,0,0,0,0,0,0,0,AB31,0,0,0,0,~
0)';
      PINUSE='GROUND';
      NO_LOAD_CHECK='Both';
      NO_IO_CHECK='Both';
      NO_ASSERT_CHECK='TRUE';
      NO_DIR_CHECK='TRUE';
      ALLOW_CONNECT='TRUE';
    'VSS'<912>:
      PIN_NUMBER='(0,0,0,0,0,0,0,0,0,0,0,0,0,0,0,0,0,0,0,0,0,0,0,0,AB35,0,0,0,0,~
0)';
      PINUSE='GROUND';
      NO_LOAD_CHECK='Both';
      NO_IO_CHECK='Both';
      NO_ASSERT_CHECK='TRUE';
      NO_DIR_CHECK='TRUE';
      ALLOW_CONNECT='TRUE';
    'VSS'<911>:
      PIN_NUMBER='(0,0,0,0,0,0,0,0,0,0,0,0,0,0,0,0,0,0,0,0,0,0,0,0,AB37,0,0,0,0,~
0)';
      PINUSE='GROUND';
      NO_LOAD_CHECK='Both';
      NO_IO_CHECK='Both';
      NO_ASSERT_CHECK='TRUE';
      NO_DIR_CHECK='TRUE';
      ALLOW_CONNECT='TRUE';
    'VSS'<910>:
      PIN_NUMBER='(0,0,0,0,0,0,0,0,0,0,0,0,0,0,0,0,0,0,0,0,0,0,0,0,AB41,0,0,0,0,~
0)';
      PINUSE='GROUND';
      NO_LOAD_CHECK='Both';
      NO_IO_CHECK='Both';
      NO_ASSERT_CHECK='TRUE';
      NO_DIR_CHECK='TRUE';
      ALLOW_CONNECT='TRUE';
    'VSS'<909>:
      PIN_NUMBER='(0,0,0,0,0,0,0,0,0,0,0,0,0,0,0,0,0,0,0,0,0,0,0,0,AB65,0,0,0,0,~
0)';
      PINUSE='GROUND';
      NO_LOAD_CHECK='Both';
      NO_IO_CHECK='Both';
      NO_ASSERT_CHECK='TRUE';
      NO_DIR_CHECK='TRUE';
      ALLOW_CONNECT='TRUE';
    'VSS'<908>:
      PIN_NUMBER='(0,0,0,0,0,0,0,0,0,0,0,0,0,0,0,0,0,0,0,0,0,0,0,0,AB69,0,0,0,0,~
0)';
      PINUSE='GROUND';
      NO_LOAD_CHECK='Both';
      NO_IO_CHECK='Both';
      NO_ASSERT_CHECK='TRUE';
      NO_DIR_CHECK='TRUE';
      ALLOW_CONNECT='TRUE';
    'VSS'<907>:
      PIN_NUMBER='(0,0,0,0,0,0,0,0,0,0,0,0,0,0,0,0,0,0,0,0,0,0,0,0,AB73,0,0,0,0,~
0)';
      PINUSE='GROUND';
      NO_LOAD_CHECK='Both';
      NO_IO_CHECK='Both';
      NO_ASSERT_CHECK='TRUE';
      NO_DIR_CHECK='TRUE';
      ALLOW_CONNECT='TRUE';
    'VSS'<906>:
      PIN_NUMBER='(0,0,0,0,0,0,0,0,0,0,0,0,0,0,0,0,0,0,0,0,0,0,0,0,AB79,0,0,0,0,~
0)';
      PINUSE='GROUND';
      NO_LOAD_CHECK='Both';
      NO_IO_CHECK='Both';
      NO_ASSERT_CHECK='TRUE';
      NO_DIR_CHECK='TRUE';
      ALLOW_CONNECT='TRUE';
    'VSS'<905>:
      PIN_NUMBER='(0,0,0,0,0,0,0,0,0,0,0,0,0,0,0,0,0,0,0,0,0,0,0,0,AB83,0,0,0,0,~
0)';
      PINUSE='GROUND';
      NO_LOAD_CHECK='Both';
      NO_IO_CHECK='Both';
      NO_ASSERT_CHECK='TRUE';
      NO_DIR_CHECK='TRUE';
      ALLOW_CONNECT='TRUE';
    'VSS'<904>:
      PIN_NUMBER='(0,0,0,0,0,0,0,0,0,0,0,0,0,0,0,0,0,0,0,0,0,0,0,0,AB85,0,0,0,0,~
0)';
      PINUSE='GROUND';
      NO_LOAD_CHECK='Both';
      NO_IO_CHECK='Both';
      NO_ASSERT_CHECK='TRUE';
      NO_DIR_CHECK='TRUE';
      ALLOW_CONNECT='TRUE';
    'VSS'<903>:
      PIN_NUMBER='(0,0,0,0,0,0,0,0,0,0,0,0,0,0,0,0,0,0,0,0,0,0,0,0,AC18,0,0,0,0,~
0)';
      PINUSE='GROUND';
      NO_LOAD_CHECK='Both';
      NO_IO_CHECK='Both';
      NO_ASSERT_CHECK='TRUE';
      NO_DIR_CHECK='TRUE';
      ALLOW_CONNECT='TRUE';
    'VSS'<902>:
      PIN_NUMBER='(0,0,0,0,0,0,0,0,0,0,0,0,0,0,0,0,0,0,0,0,0,0,0,0,AC22,0,0,0,0,~
0)';
      PINUSE='GROUND';
      NO_LOAD_CHECK='Both';
      NO_IO_CHECK='Both';
      NO_ASSERT_CHECK='TRUE';
      NO_DIR_CHECK='TRUE';
      ALLOW_CONNECT='TRUE';
    'VSS'<901>:
      PIN_NUMBER='(0,0,0,0,0,0,0,0,0,0,0,0,0,0,0,0,0,0,0,0,0,0,0,0,AC26,0,0,0,0,~
0)';
      PINUSE='GROUND';
      NO_LOAD_CHECK='Both';
      NO_IO_CHECK='Both';
      NO_ASSERT_CHECK='TRUE';
      NO_DIR_CHECK='TRUE';
      ALLOW_CONNECT='TRUE';
    'VSS'<900>:
      PIN_NUMBER='(0,0,0,0,0,0,0,0,0,0,0,0,0,0,0,0,0,0,0,0,0,0,0,0,AC28,0,0,0,0,~
0)';
      PINUSE='GROUND';
      NO_LOAD_CHECK='Both';
      NO_IO_CHECK='Both';
      NO_ASSERT_CHECK='TRUE';
      NO_DIR_CHECK='TRUE';
      ALLOW_CONNECT='TRUE';
    'VSS'<899>:
      PIN_NUMBER='(0,0,0,0,0,0,0,0,0,0,0,0,0,0,0,0,0,0,0,0,0,0,0,0,AC32,0,0,0,0,~
0)';
      PINUSE='GROUND';
      NO_LOAD_CHECK='Both';
      NO_IO_CHECK='Both';
      NO_ASSERT_CHECK='TRUE';
      NO_DIR_CHECK='TRUE';
      ALLOW_CONNECT='TRUE';
    'VSS'<898>:
      PIN_NUMBER='(0,0,0,0,0,0,0,0,0,0,0,0,0,0,0,0,0,0,0,0,0,0,0,0,AC34,0,0,0,0,~
0)';
      PINUSE='GROUND';
      NO_LOAD_CHECK='Both';
      NO_IO_CHECK='Both';
      NO_ASSERT_CHECK='TRUE';
      NO_DIR_CHECK='TRUE';
      ALLOW_CONNECT='TRUE';
    'VSS'<897>:
      PIN_NUMBER='(0,0,0,0,0,0,0,0,0,0,0,0,0,0,0,0,0,0,0,0,0,0,0,0,AC38,0,0,0,0,~
0)';
      PINUSE='GROUND';
      NO_LOAD_CHECK='Both';
      NO_IO_CHECK='Both';
      NO_ASSERT_CHECK='TRUE';
      NO_DIR_CHECK='TRUE';
      ALLOW_CONNECT='TRUE';
    'VSS'<896>:
      PIN_NUMBER='(0,0,0,0,0,0,0,0,0,0,0,0,0,0,0,0,0,0,0,0,0,0,0,0,AC40,0,0,0,0,~
0)';
      PINUSE='GROUND';
      NO_LOAD_CHECK='Both';
      NO_IO_CHECK='Both';
      NO_ASSERT_CHECK='TRUE';
      NO_DIR_CHECK='TRUE';
      ALLOW_CONNECT='TRUE';
    'VSS'<895>:
      PIN_NUMBER='(0,0,0,0,0,0,0,0,0,0,0,0,0,0,0,0,0,0,0,0,0,0,0,0,AC64,0,0,0,0,~
0)';
      PINUSE='GROUND';
      NO_LOAD_CHECK='Both';
      NO_IO_CHECK='Both';
      NO_ASSERT_CHECK='TRUE';
      NO_DIR_CHECK='TRUE';
      ALLOW_CONNECT='TRUE';
    'VSS'<894>:
      PIN_NUMBER='(0,0,0,0,0,0,0,0,0,0,0,0,0,0,0,0,0,0,0,0,0,0,0,0,AC70,0,0,0,0,~
0)';
      PINUSE='GROUND';
      NO_LOAD_CHECK='Both';
      NO_IO_CHECK='Both';
      NO_ASSERT_CHECK='TRUE';
      NO_DIR_CHECK='TRUE';
      ALLOW_CONNECT='TRUE';
    'VSS'<893>:
      PIN_NUMBER='(0,0,0,0,0,0,0,0,0,0,0,0,0,0,0,0,0,0,0,0,0,0,0,0,AC72,0,0,0,0,~
0)';
      PINUSE='GROUND';
      NO_LOAD_CHECK='Both';
      NO_IO_CHECK='Both';
      NO_ASSERT_CHECK='TRUE';
      NO_DIR_CHECK='TRUE';
      ALLOW_CONNECT='TRUE';
    'VSS'<892>:
      PIN_NUMBER='(0,0,0,0,0,0,0,0,0,0,0,0,0,0,0,0,0,0,0,0,0,0,0,0,AC78,0,0,0,0,~
0)';
      PINUSE='GROUND';
      NO_LOAD_CHECK='Both';
      NO_IO_CHECK='Both';
      NO_ASSERT_CHECK='TRUE';
      NO_DIR_CHECK='TRUE';
      ALLOW_CONNECT='TRUE';
    'VSS'<891>:
      PIN_NUMBER='(0,0,0,0,0,0,0,0,0,0,0,0,0,0,0,0,0,0,0,0,0,0,0,0,AC84,0,0,0,0,~
0)';
      PINUSE='GROUND';
      NO_LOAD_CHECK='Both';
      NO_IO_CHECK='Both';
      NO_ASSERT_CHECK='TRUE';
      NO_DIR_CHECK='TRUE';
      ALLOW_CONNECT='TRUE';
    'VSS'<890>:
      PIN_NUMBER='(0,0,0,0,0,0,0,0,0,0,0,0,0,0,0,0,0,0,0,0,0,0,0,0,AC86,0,0,0,0,~
0)';
      PINUSE='GROUND';
      NO_LOAD_CHECK='Both';
      NO_IO_CHECK='Both';
      NO_ASSERT_CHECK='TRUE';
      NO_DIR_CHECK='TRUE';
      ALLOW_CONNECT='TRUE';
    'VSS'<889>:
      PIN_NUMBER='(0,0,0,0,0,0,0,0,0,0,0,0,0,0,0,0,0,0,0,0,0,0,0,0,AD3,0,0,0,0,0~
)';
      PINUSE='GROUND';
      NO_LOAD_CHECK='Both';
      NO_IO_CHECK='Both';
      NO_ASSERT_CHECK='TRUE';
      NO_DIR_CHECK='TRUE';
      ALLOW_CONNECT='TRUE';
    'VSS'<888>:
      PIN_NUMBER='(0,0,0,0,0,0,0,0,0,0,0,0,0,0,0,0,0,0,0,0,0,0,0,0,AD7,0,0,0,0,0~
)';
      PINUSE='GROUND';
      NO_LOAD_CHECK='Both';
      NO_IO_CHECK='Both';
      NO_ASSERT_CHECK='TRUE';
      NO_DIR_CHECK='TRUE';
      ALLOW_CONNECT='TRUE';
    'VSS'<887>:
      PIN_NUMBER='(0,0,0,0,0,0,0,0,0,0,0,0,0,0,0,0,0,0,0,0,0,0,0,0,AD9,0,0,0,0,0~
)';
      PINUSE='GROUND';
      NO_LOAD_CHECK='Both';
      NO_IO_CHECK='Both';
      NO_ASSERT_CHECK='TRUE';
      NO_DIR_CHECK='TRUE';
      ALLOW_CONNECT='TRUE';
    'VSS'<886>:
      PIN_NUMBER='(0,0,0,0,0,0,0,0,0,0,0,0,0,0,0,0,0,0,0,0,0,0,0,0,AD11,0,0,0,0,~
0)';
      PINUSE='GROUND';
      NO_LOAD_CHECK='Both';
      NO_IO_CHECK='Both';
      NO_ASSERT_CHECK='TRUE';
      NO_DIR_CHECK='TRUE';
      ALLOW_CONNECT='TRUE';
    'VSS'<885>:
      PIN_NUMBER='(0,0,0,0,0,0,0,0,0,0,0,0,0,0,0,0,0,0,0,0,0,0,0,0,AD13,0,0,0,0,~
0)';
      PINUSE='GROUND';
      NO_LOAD_CHECK='Both';
      NO_IO_CHECK='Both';
      NO_ASSERT_CHECK='TRUE';
      NO_DIR_CHECK='TRUE';
      ALLOW_CONNECT='TRUE';
    'VSS'<884>:
      PIN_NUMBER='(0,0,0,0,0,0,0,0,0,0,0,0,0,0,0,0,0,0,0,0,0,0,0,0,AD15,0,0,0,0,~
0)';
      PINUSE='GROUND';
      NO_LOAD_CHECK='Both';
      NO_IO_CHECK='Both';
      NO_ASSERT_CHECK='TRUE';
      NO_DIR_CHECK='TRUE';
      ALLOW_CONNECT='TRUE';
    'VSS'<883>:
      PIN_NUMBER='(0,0,0,0,0,0,0,0,0,0,0,0,0,0,0,0,0,0,0,0,0,0,0,0,AD19,0,0,0,0,~
0)';
      PINUSE='GROUND';
      NO_LOAD_CHECK='Both';
      NO_IO_CHECK='Both';
      NO_ASSERT_CHECK='TRUE';
      NO_DIR_CHECK='TRUE';
      ALLOW_CONNECT='TRUE';
    'VSS'<882>:
      PIN_NUMBER='(0,0,0,0,0,0,0,0,0,0,0,0,0,0,0,0,0,0,0,0,0,0,0,0,AD21,0,0,0,0,~
0)';
      PINUSE='GROUND';
      NO_LOAD_CHECK='Both';
      NO_IO_CHECK='Both';
      NO_ASSERT_CHECK='TRUE';
      NO_DIR_CHECK='TRUE';
      ALLOW_CONNECT='TRUE';
    'VSS'<881>:
      PIN_NUMBER='(0,0,0,0,0,0,0,0,0,0,0,0,0,0,0,0,0,0,0,0,0,0,0,0,AD27,0,0,0,0,~
0)';
      PINUSE='GROUND';
      NO_LOAD_CHECK='Both';
      NO_IO_CHECK='Both';
      NO_ASSERT_CHECK='TRUE';
      NO_DIR_CHECK='TRUE';
      ALLOW_CONNECT='TRUE';
    'VSS'<880>:
      PIN_NUMBER='(0,0,0,0,0,0,0,0,0,0,0,0,0,0,0,0,0,0,0,0,0,0,0,0,AD33,0,0,0,0,~
0)';
      PINUSE='GROUND';
      NO_LOAD_CHECK='Both';
      NO_IO_CHECK='Both';
      NO_ASSERT_CHECK='TRUE';
      NO_DIR_CHECK='TRUE';
      ALLOW_CONNECT='TRUE';
    'VSS'<879>:
      PIN_NUMBER='(0,0,0,0,0,0,0,0,0,0,0,0,0,0,0,0,0,0,0,0,0,0,0,0,AD39,0,0,0,0,~
0)';
      PINUSE='GROUND';
      NO_LOAD_CHECK='Both';
      NO_IO_CHECK='Both';
      NO_ASSERT_CHECK='TRUE';
      NO_DIR_CHECK='TRUE';
      ALLOW_CONNECT='TRUE';
    'VSS'<878>:
      PIN_NUMBER='(0,0,0,0,0,0,0,0,0,0,0,0,0,0,0,0,0,0,0,0,0,0,0,0,AD43,0,0,0,0,~
0)';
      PINUSE='GROUND';
      NO_LOAD_CHECK='Both';
      NO_IO_CHECK='Both';
      NO_ASSERT_CHECK='TRUE';
      NO_DIR_CHECK='TRUE';
      ALLOW_CONNECT='TRUE';
    'VSS'<877>:
      PIN_NUMBER='(0,0,0,0,0,0,0,0,0,0,0,0,0,0,0,0,0,0,0,0,0,0,0,0,AD71,0,0,0,0,~
0)';
      PINUSE='GROUND';
      NO_LOAD_CHECK='Both';
      NO_IO_CHECK='Both';
      NO_ASSERT_CHECK='TRUE';
      NO_DIR_CHECK='TRUE';
      ALLOW_CONNECT='TRUE';
    'VSS'<876>:
      PIN_NUMBER='(0,0,0,0,0,0,0,0,0,0,0,0,0,0,0,0,0,0,0,0,0,0,0,0,AD73,0,0,0,0,~
0)';
      PINUSE='GROUND';
      NO_LOAD_CHECK='Both';
      NO_IO_CHECK='Both';
      NO_ASSERT_CHECK='TRUE';
      NO_DIR_CHECK='TRUE';
      ALLOW_CONNECT='TRUE';
    'VSS'<875>:
      PIN_NUMBER='(0,0,0,0,0,0,0,0,0,0,0,0,0,0,0,0,0,0,0,0,0,0,0,0,AD75,0,0,0,0,~
0)';
      PINUSE='GROUND';
      NO_LOAD_CHECK='Both';
      NO_IO_CHECK='Both';
      NO_ASSERT_CHECK='TRUE';
      NO_DIR_CHECK='TRUE';
      ALLOW_CONNECT='TRUE';
    'VSS'<874>:
      PIN_NUMBER='(0,0,0,0,0,0,0,0,0,0,0,0,0,0,0,0,0,0,0,0,0,0,0,0,AD81,0,0,0,0,~
0)';
      PINUSE='GROUND';
      NO_LOAD_CHECK='Both';
      NO_IO_CHECK='Both';
      NO_ASSERT_CHECK='TRUE';
      NO_DIR_CHECK='TRUE';
      ALLOW_CONNECT='TRUE';
    'VSS'<873>:
      PIN_NUMBER='(0,0,0,0,0,0,0,0,0,0,0,0,0,0,0,0,0,0,0,0,0,0,0,0,AD83,0,0,0,0,~
0)';
      PINUSE='GROUND';
      NO_LOAD_CHECK='Both';
      NO_IO_CHECK='Both';
      NO_ASSERT_CHECK='TRUE';
      NO_DIR_CHECK='TRUE';
      ALLOW_CONNECT='TRUE';
    'VSS'<872>:
      PIN_NUMBER='(0,0,0,0,0,0,0,0,0,0,0,0,0,0,0,0,0,0,0,0,0,0,0,0,AD85,0,0,0,0,~
0)';
      PINUSE='GROUND';
      NO_LOAD_CHECK='Both';
      NO_IO_CHECK='Both';
      NO_ASSERT_CHECK='TRUE';
      NO_DIR_CHECK='TRUE';
      ALLOW_CONNECT='TRUE';
    'VSS'<871>:
      PIN_NUMBER='(0,0,0,0,0,0,0,0,0,0,0,0,0,0,0,0,0,0,0,0,0,0,0,0,AE4,0,0,0,0,0~
)';
      PINUSE='GROUND';
      NO_LOAD_CHECK='Both';
      NO_IO_CHECK='Both';
      NO_ASSERT_CHECK='TRUE';
      NO_DIR_CHECK='TRUE';
      ALLOW_CONNECT='TRUE';
    'VSS'<870>:
      PIN_NUMBER='(0,0,0,0,0,0,0,0,0,0,0,0,0,0,0,0,0,0,0,0,0,0,0,0,AE8,0,0,0,0,0~
)';
      PINUSE='GROUND';
      NO_LOAD_CHECK='Both';
      NO_IO_CHECK='Both';
      NO_ASSERT_CHECK='TRUE';
      NO_DIR_CHECK='TRUE';
      ALLOW_CONNECT='TRUE';
    'VSS'<869>:
      PIN_NUMBER='(0,0,0,0,0,0,0,0,0,0,0,0,0,0,0,0,0,0,0,0,0,0,0,0,AC54,0,0,0,0,~
0)';
      PINUSE='GROUND';
      NO_LOAD_CHECK='Both';
      NO_IO_CHECK='Both';
      NO_ASSERT_CHECK='TRUE';
      NO_DIR_CHECK='TRUE';
      ALLOW_CONNECT='TRUE';
    'VSS'<868>:
      PIN_NUMBER='(0,0,0,0,0,0,0,0,0,0,0,0,0,0,0,0,0,0,0,0,0,0,0,0,AE16,0,0,0,0,~
0)';
      PINUSE='GROUND';
      NO_LOAD_CHECK='Both';
      NO_IO_CHECK='Both';
      NO_ASSERT_CHECK='TRUE';
      NO_DIR_CHECK='TRUE';
      ALLOW_CONNECT='TRUE';
    'VSS'<867>:
      PIN_NUMBER='(0,0,0,0,0,0,0,0,0,0,0,0,0,0,0,0,0,0,0,0,0,0,0,0,AE38,0,0,0,0,~
0)';
      PINUSE='GROUND';
      NO_LOAD_CHECK='Both';
      NO_IO_CHECK='Both';
      NO_ASSERT_CHECK='TRUE';
      NO_DIR_CHECK='TRUE';
      ALLOW_CONNECT='TRUE';
    'VSS'<866>:
      PIN_NUMBER='(0,0,0,0,0,0,0,0,0,0,0,0,0,0,0,0,0,0,0,0,0,0,0,0,AE40,0,0,0,0,~
0)';
      PINUSE='GROUND';
      NO_LOAD_CHECK='Both';
      NO_IO_CHECK='Both';
      NO_ASSERT_CHECK='TRUE';
      NO_DIR_CHECK='TRUE';
      ALLOW_CONNECT='TRUE';
    'VSS'<865>:
      PIN_NUMBER='(0,0,0,0,0,0,0,0,0,0,0,0,0,0,0,0,0,0,0,0,0,0,0,0,AE42,0,0,0,0,~
0)';
      PINUSE='GROUND';
      NO_LOAD_CHECK='Both';
      NO_IO_CHECK='Both';
      NO_ASSERT_CHECK='TRUE';
      NO_DIR_CHECK='TRUE';
      ALLOW_CONNECT='TRUE';
    'VSS'<864>:
      PIN_NUMBER='(0,0,0,0,0,0,0,0,0,0,0,0,0,0,0,0,0,0,0,0,0,0,0,0,AE64,0,0,0,0,~
0)';
      PINUSE='GROUND';
      NO_LOAD_CHECK='Both';
      NO_IO_CHECK='Both';
      NO_ASSERT_CHECK='TRUE';
      NO_DIR_CHECK='TRUE';
      ALLOW_CONNECT='TRUE';
    'VSS'<863>:
      PIN_NUMBER='(0,0,0,0,0,0,0,0,0,0,0,0,0,0,0,0,0,0,0,0,0,0,0,0,AE66,0,0,0,0,~
0)';
      PINUSE='GROUND';
      NO_LOAD_CHECK='Both';
      NO_IO_CHECK='Both';
      NO_ASSERT_CHECK='TRUE';
      NO_DIR_CHECK='TRUE';
      ALLOW_CONNECT='TRUE';
    'VSS'<862>:
      PIN_NUMBER='(0,0,0,0,0,0,0,0,0,0,0,0,0,0,0,0,0,0,0,0,0,0,0,0,AE68,0,0,0,0,~
0)';
      PINUSE='GROUND';
      NO_LOAD_CHECK='Both';
      NO_IO_CHECK='Both';
      NO_ASSERT_CHECK='TRUE';
      NO_DIR_CHECK='TRUE';
      ALLOW_CONNECT='TRUE';
    'VSS'<861>:
      PIN_NUMBER='(0,0,0,0,0,0,0,0,0,0,0,0,0,0,0,0,0,0,0,0,0,0,0,0,AE70,0,0,0,0,~
0)';
      PINUSE='GROUND';
      NO_LOAD_CHECK='Both';
      NO_IO_CHECK='Both';
      NO_ASSERT_CHECK='TRUE';
      NO_DIR_CHECK='TRUE';
      ALLOW_CONNECT='TRUE';
    'VSS'<860>:
      PIN_NUMBER='(0,0,0,0,0,0,0,0,0,0,0,0,0,0,0,0,0,0,0,0,0,0,0,0,AE78,0,0,0,0,~
0)';
      PINUSE='GROUND';
      NO_LOAD_CHECK='Both';
      NO_IO_CHECK='Both';
      NO_ASSERT_CHECK='TRUE';
      NO_DIR_CHECK='TRUE';
      ALLOW_CONNECT='TRUE';
    'VSS'<859>:
      PIN_NUMBER='(0,0,0,0,0,0,0,0,0,0,0,0,0,0,0,0,0,0,0,0,0,0,0,0,AF1,0,0,0,0,0~
)';
      PINUSE='GROUND';
      NO_LOAD_CHECK='Both';
      NO_IO_CHECK='Both';
      NO_ASSERT_CHECK='TRUE';
      NO_DIR_CHECK='TRUE';
      ALLOW_CONNECT='TRUE';
    'VSS'<858>:
      PIN_NUMBER='(0,0,0,0,0,0,0,0,0,0,0,0,0,0,0,0,0,0,0,0,0,0,0,0,AC52,0,0,0,0,~
0)';
      PINUSE='GROUND';
      NO_LOAD_CHECK='Both';
      NO_IO_CHECK='Both';
      NO_ASSERT_CHECK='TRUE';
      NO_DIR_CHECK='TRUE';
      ALLOW_CONNECT='TRUE';
    'VSS'<857>:
      PIN_NUMBER='(0,0,0,0,0,0,0,0,0,0,0,0,0,0,0,0,0,0,0,0,0,0,0,0,AF9,0,0,0,0,0~
)';
      PINUSE='GROUND';
      NO_LOAD_CHECK='Both';
      NO_IO_CHECK='Both';
      NO_ASSERT_CHECK='TRUE';
      NO_DIR_CHECK='TRUE';
      ALLOW_CONNECT='TRUE';
    'VSS'<856>:
      PIN_NUMBER='(0,0,0,0,0,0,0,0,0,0,0,0,0,0,0,0,0,0,0,0,0,0,0,0,AF21,0,0,0,0,~
0)';
      PINUSE='GROUND';
      NO_LOAD_CHECK='Both';
      NO_IO_CHECK='Both';
      NO_ASSERT_CHECK='TRUE';
      NO_DIR_CHECK='TRUE';
      ALLOW_CONNECT='TRUE';
    'VSS'<855>:
      PIN_NUMBER='(0,0,0,0,0,0,0,0,0,0,0,0,0,0,0,0,0,0,0,0,0,0,0,0,AF23,0,0,0,0,~
0)';
      PINUSE='GROUND';
      NO_LOAD_CHECK='Both';
      NO_IO_CHECK='Both';
      NO_ASSERT_CHECK='TRUE';
      NO_DIR_CHECK='TRUE';
      ALLOW_CONNECT='TRUE';
    'VSS'<854>:
      PIN_NUMBER='(0,0,0,0,0,0,0,0,0,0,0,0,0,0,0,0,0,0,0,0,0,0,0,0,AF25,0,0,0,0,~
0)';
      PINUSE='GROUND';
      NO_LOAD_CHECK='Both';
      NO_IO_CHECK='Both';
      NO_ASSERT_CHECK='TRUE';
      NO_DIR_CHECK='TRUE';
      ALLOW_CONNECT='TRUE';
    'VSS'<853>:
      PIN_NUMBER='(0,0,0,0,0,0,0,0,0,0,0,0,0,0,0,0,0,0,0,0,0,0,0,0,AF27,0,0,0,0,~
0)';
      PINUSE='GROUND';
      NO_LOAD_CHECK='Both';
      NO_IO_CHECK='Both';
      NO_ASSERT_CHECK='TRUE';
      NO_DIR_CHECK='TRUE';
      ALLOW_CONNECT='TRUE';
    'VSS'<852>:
      PIN_NUMBER='(0,0,0,0,0,0,0,0,0,0,0,0,0,0,0,0,0,0,0,0,0,0,0,0,AF29,0,0,0,0,~
0)';
      PINUSE='GROUND';
      NO_LOAD_CHECK='Both';
      NO_IO_CHECK='Both';
      NO_ASSERT_CHECK='TRUE';
      NO_DIR_CHECK='TRUE';
      ALLOW_CONNECT='TRUE';
    'VSS'<851>:
      PIN_NUMBER='(0,0,0,0,0,0,0,0,0,0,0,0,0,0,0,0,0,0,0,0,0,0,0,0,AF31,0,0,0,0,~
0)';
      PINUSE='GROUND';
      NO_LOAD_CHECK='Both';
      NO_IO_CHECK='Both';
      NO_ASSERT_CHECK='TRUE';
      NO_DIR_CHECK='TRUE';
      ALLOW_CONNECT='TRUE';
    'VSS'<850>:
      PIN_NUMBER='(0,0,0,0,0,0,0,0,0,0,0,0,0,0,0,0,0,0,0,0,0,0,0,0,AF33,0,0,0,0,~
0)';
      PINUSE='GROUND';
      NO_LOAD_CHECK='Both';
      NO_IO_CHECK='Both';
      NO_ASSERT_CHECK='TRUE';
      NO_DIR_CHECK='TRUE';
      ALLOW_CONNECT='TRUE';
    'VSS'<849>:
      PIN_NUMBER='(0,0,0,0,0,0,0,0,0,0,0,0,0,0,0,0,0,0,0,0,0,0,0,0,AF37,0,0,0,0,~
0)';
      PINUSE='GROUND';
      NO_LOAD_CHECK='Both';
      NO_IO_CHECK='Both';
      NO_ASSERT_CHECK='TRUE';
      NO_DIR_CHECK='TRUE';
      ALLOW_CONNECT='TRUE';
    'VSS'<848>:
      PIN_NUMBER='(0,0,0,0,0,0,0,0,0,0,0,0,0,0,0,0,0,0,0,0,0,0,0,0,AF39,0,0,0,0,~
0)';
      PINUSE='GROUND';
      NO_LOAD_CHECK='Both';
      NO_IO_CHECK='Both';
      NO_ASSERT_CHECK='TRUE';
      NO_DIR_CHECK='TRUE';
      ALLOW_CONNECT='TRUE';
    'VSS'<847>:
      PIN_NUMBER='(0,0,0,0,0,0,0,0,0,0,0,0,0,0,0,0,0,0,0,0,0,0,0,0,AF41,0,0,0,0,~
0)';
      PINUSE='GROUND';
      NO_LOAD_CHECK='Both';
      NO_IO_CHECK='Both';
      NO_ASSERT_CHECK='TRUE';
      NO_DIR_CHECK='TRUE';
      ALLOW_CONNECT='TRUE';
    'VSS'<846>:
      PIN_NUMBER='(0,0,0,0,0,0,0,0,0,0,0,0,0,0,0,0,0,0,0,0,0,0,0,0,AF73,0,0,0,0,~
0)';
      PINUSE='GROUND';
      NO_LOAD_CHECK='Both';
      NO_IO_CHECK='Both';
      NO_ASSERT_CHECK='TRUE';
      NO_DIR_CHECK='TRUE';
      ALLOW_CONNECT='TRUE';
    'VSS'<845>:
      PIN_NUMBER='(0,0,0,0,0,0,0,0,0,0,0,0,0,0,0,0,0,0,0,0,0,0,0,0,AF77,0,0,0,0,~
0)';
      PINUSE='GROUND';
      NO_LOAD_CHECK='Both';
      NO_IO_CHECK='Both';
      NO_ASSERT_CHECK='TRUE';
      NO_DIR_CHECK='TRUE';
      ALLOW_CONNECT='TRUE';
    'VSS'<844>:
      PIN_NUMBER='(0,0,0,0,0,0,0,0,0,0,0,0,0,0,0,0,0,0,0,0,0,0,0,0,AF83,0,0,0,0,~
0)';
      PINUSE='GROUND';
      NO_LOAD_CHECK='Both';
      NO_IO_CHECK='Both';
      NO_ASSERT_CHECK='TRUE';
      NO_DIR_CHECK='TRUE';
      ALLOW_CONNECT='TRUE';
    'VSS'<843>:
      PIN_NUMBER='(0,0,0,0,0,0,0,0,0,0,0,0,0,0,0,0,0,0,0,0,0,0,0,0,AF85,0,0,0,0,~
0)';
      PINUSE='GROUND';
      NO_LOAD_CHECK='Both';
      NO_IO_CHECK='Both';
      NO_ASSERT_CHECK='TRUE';
      NO_DIR_CHECK='TRUE';
      ALLOW_CONNECT='TRUE';
    'VSS'<842>:
      PIN_NUMBER='(0,0,0,0,0,0,0,0,0,0,0,0,0,0,0,0,0,0,0,0,0,0,0,0,AG12,0,0,0,0,~
0)';
      PINUSE='GROUND';
      NO_LOAD_CHECK='Both';
      NO_IO_CHECK='Both';
      NO_ASSERT_CHECK='TRUE';
      NO_DIR_CHECK='TRUE';
      ALLOW_CONNECT='TRUE';
    'VSS'<841>:
      PIN_NUMBER='(0,0,0,0,0,0,0,0,0,0,0,0,0,0,0,0,0,0,0,0,0,0,0,0,AG14,0,0,0,0,~
0)';
      PINUSE='GROUND';
      NO_LOAD_CHECK='Both';
      NO_IO_CHECK='Both';
      NO_ASSERT_CHECK='TRUE';
      NO_DIR_CHECK='TRUE';
      ALLOW_CONNECT='TRUE';
    'VSS'<840>:
      PIN_NUMBER='(0,0,0,0,0,0,0,0,0,0,0,0,0,0,0,0,0,0,0,0,0,0,0,0,AG18,0,0,0,0,~
0)';
      PINUSE='GROUND';
      NO_LOAD_CHECK='Both';
      NO_IO_CHECK='Both';
      NO_ASSERT_CHECK='TRUE';
      NO_DIR_CHECK='TRUE';
      ALLOW_CONNECT='TRUE';
    'VSS'<839>:
      PIN_NUMBER='(0,0,0,0,0,0,0,0,0,0,0,0,0,0,0,0,0,0,0,0,0,0,0,0,AG36,0,0,0,0,~
0)';
      PINUSE='GROUND';
      NO_LOAD_CHECK='Both';
      NO_IO_CHECK='Both';
      NO_ASSERT_CHECK='TRUE';
      NO_DIR_CHECK='TRUE';
      ALLOW_CONNECT='TRUE';
    'VSS'<838>:
      PIN_NUMBER='(0,0,0,0,0,0,0,0,0,0,0,0,0,0,0,0,0,0,0,0,0,0,0,0,AG64,0,0,0,0,~
0)';
      PINUSE='GROUND';
      NO_LOAD_CHECK='Both';
      NO_IO_CHECK='Both';
      NO_ASSERT_CHECK='TRUE';
      NO_DIR_CHECK='TRUE';
      ALLOW_CONNECT='TRUE';
    'VSS'<837>:
      PIN_NUMBER='(0,0,0,0,0,0,0,0,0,0,0,0,0,0,0,0,0,0,0,0,0,0,0,0,AG70,0,0,0,0,~
0)';
      PINUSE='GROUND';
      NO_LOAD_CHECK='Both';
      NO_IO_CHECK='Both';
      NO_ASSERT_CHECK='TRUE';
      NO_DIR_CHECK='TRUE';
      ALLOW_CONNECT='TRUE';
    'VSS'<836>:
      PIN_NUMBER='(0,0,0,0,0,0,0,0,0,0,0,0,0,0,0,0,0,0,0,0,0,0,0,0,AG74,0,0,0,0,~
0)';
      PINUSE='GROUND';
      NO_LOAD_CHECK='Both';
      NO_IO_CHECK='Both';
      NO_ASSERT_CHECK='TRUE';
      NO_DIR_CHECK='TRUE';
      ALLOW_CONNECT='TRUE';
    'VSS'<835>:
      PIN_NUMBER='(0,0,0,0,0,0,0,0,0,0,0,0,0,0,0,0,0,0,0,0,0,0,0,0,AG76,0,0,0,0,~
0)';
      PINUSE='GROUND';
      NO_LOAD_CHECK='Both';
      NO_IO_CHECK='Both';
      NO_ASSERT_CHECK='TRUE';
      NO_DIR_CHECK='TRUE';
      ALLOW_CONNECT='TRUE';
    'VSS'<834>:
      PIN_NUMBER='(0,0,0,0,0,0,0,0,0,0,0,0,0,0,0,0,0,0,0,0,0,0,0,0,AG78,0,0,0,0,~
0)';
      PINUSE='GROUND';
      NO_LOAD_CHECK='Both';
      NO_IO_CHECK='Both';
      NO_ASSERT_CHECK='TRUE';
      NO_DIR_CHECK='TRUE';
      ALLOW_CONNECT='TRUE';
    'VSS'<833>:
      PIN_NUMBER='(0,0,0,0,0,0,0,0,0,0,0,0,0,0,0,0,0,0,0,0,0,0,0,0,AG80,0,0,0,0,~
0)';
      PINUSE='GROUND';
      NO_LOAD_CHECK='Both';
      NO_IO_CHECK='Both';
      NO_ASSERT_CHECK='TRUE';
      NO_DIR_CHECK='TRUE';
      ALLOW_CONNECT='TRUE';
    'VSS'<832>:
      PIN_NUMBER='(0,0,0,0,0,0,0,0,0,0,0,0,0,0,0,0,0,0,0,0,0,0,0,0,AH1,0,0,0,0,0~
)';
      PINUSE='GROUND';
      NO_LOAD_CHECK='Both';
      NO_IO_CHECK='Both';
      NO_ASSERT_CHECK='TRUE';
      NO_DIR_CHECK='TRUE';
      ALLOW_CONNECT='TRUE';
    'VSS'<831>:
      PIN_NUMBER='(0,0,0,0,0,0,0,0,0,0,0,0,0,0,0,0,0,0,0,0,0,0,0,0,AH5,0,0,0,0,0~
)';
      PINUSE='GROUND';
      NO_LOAD_CHECK='Both';
      NO_IO_CHECK='Both';
      NO_ASSERT_CHECK='TRUE';
      NO_DIR_CHECK='TRUE';
      ALLOW_CONNECT='TRUE';
    'VSS'<830>:
      PIN_NUMBER='(0,0,0,0,0,0,0,0,0,0,0,0,0,0,0,0,0,0,0,0,0,0,0,0,AH21,0,0,0,0,~
0)';
      PINUSE='GROUND';
      NO_LOAD_CHECK='Both';
      NO_IO_CHECK='Both';
      NO_ASSERT_CHECK='TRUE';
      NO_DIR_CHECK='TRUE';
      ALLOW_CONNECT='TRUE';
    'VSS'<829>:
      PIN_NUMBER='(0,0,0,0,0,0,0,0,0,0,0,0,0,0,0,0,0,0,0,0,0,0,0,0,AH27,0,0,0,0,~
0)';
      PINUSE='GROUND';
      NO_LOAD_CHECK='Both';
      NO_IO_CHECK='Both';
      NO_ASSERT_CHECK='TRUE';
      NO_DIR_CHECK='TRUE';
      ALLOW_CONNECT='TRUE';
    'VSS'<828>:
      PIN_NUMBER='(0,0,0,0,0,0,0,0,0,0,0,0,0,0,0,0,0,0,0,0,0,0,0,0,AH33,0,0,0,0,~
0)';
      PINUSE='GROUND';
      NO_LOAD_CHECK='Both';
      NO_IO_CHECK='Both';
      NO_ASSERT_CHECK='TRUE';
      NO_DIR_CHECK='TRUE';
      ALLOW_CONNECT='TRUE';
    'VSS'<827>:
      PIN_NUMBER='(0,0,0,0,0,0,0,0,0,0,0,0,0,0,0,0,0,0,0,0,0,0,0,0,AH35,0,0,0,0,~
0)';
      PINUSE='GROUND';
      NO_LOAD_CHECK='Both';
      NO_IO_CHECK='Both';
      NO_ASSERT_CHECK='TRUE';
      NO_DIR_CHECK='TRUE';
      ALLOW_CONNECT='TRUE';
    'VSS'<826>:
      PIN_NUMBER='(0,0,0,0,0,0,0,0,0,0,0,0,0,0,0,0,0,0,0,0,0,0,0,0,AH45,0,0,0,0,~
0)';
      PINUSE='GROUND';
      NO_LOAD_CHECK='Both';
      NO_IO_CHECK='Both';
      NO_ASSERT_CHECK='TRUE';
      NO_DIR_CHECK='TRUE';
      ALLOW_CONNECT='TRUE';
    'VSS'<825>:
      PIN_NUMBER='(0,0,0,0,0,0,0,0,0,0,0,0,0,0,0,0,0,0,0,0,0,0,0,0,AH47,0,0,0,0,~
0)';
      PINUSE='GROUND';
      NO_LOAD_CHECK='Both';
      NO_IO_CHECK='Both';
      NO_ASSERT_CHECK='TRUE';
      NO_DIR_CHECK='TRUE';
      ALLOW_CONNECT='TRUE';
    'VSS'<824>:
      PIN_NUMBER='(0,0,0,0,0,0,0,0,0,0,0,0,0,0,0,0,0,0,0,0,0,0,0,0,AH49,0,0,0,0,~
0)';
      PINUSE='GROUND';
      NO_LOAD_CHECK='Both';
      NO_IO_CHECK='Both';
      NO_ASSERT_CHECK='TRUE';
      NO_DIR_CHECK='TRUE';
      ALLOW_CONNECT='TRUE';
    'VSS'<823>:
      PIN_NUMBER='(0,0,0,0,0,0,0,0,0,0,0,0,0,0,0,0,0,0,0,0,0,0,0,0,AH51,0,0,0,0,~
0)';
      PINUSE='GROUND';
      NO_LOAD_CHECK='Both';
      NO_IO_CHECK='Both';
      NO_ASSERT_CHECK='TRUE';
      NO_DIR_CHECK='TRUE';
      ALLOW_CONNECT='TRUE';
    'VSS'<822>:
      PIN_NUMBER='(0,0,0,0,0,0,0,0,0,0,0,0,0,0,0,0,0,0,0,0,0,0,0,0,AH53,0,0,0,0,~
0)';
      PINUSE='GROUND';
      NO_LOAD_CHECK='Both';
      NO_IO_CHECK='Both';
      NO_ASSERT_CHECK='TRUE';
      NO_DIR_CHECK='TRUE';
      ALLOW_CONNECT='TRUE';
    'VSS'<821>:
      PIN_NUMBER='(0,0,0,0,0,0,0,0,0,0,0,0,0,0,0,0,0,0,0,0,0,0,0,0,AH59,0,0,0,0,~
0)';
      PINUSE='GROUND';
      NO_LOAD_CHECK='Both';
      NO_IO_CHECK='Both';
      NO_ASSERT_CHECK='TRUE';
      NO_DIR_CHECK='TRUE';
      ALLOW_CONNECT='TRUE';
    'VSS'<820>:
      PIN_NUMBER='(0,0,0,0,0,0,0,0,0,0,0,0,0,0,0,0,0,0,0,0,0,0,0,0,AH61,0,0,0,0,~
0)';
      PINUSE='GROUND';
      NO_LOAD_CHECK='Both';
      NO_IO_CHECK='Both';
      NO_ASSERT_CHECK='TRUE';
      NO_DIR_CHECK='TRUE';
      ALLOW_CONNECT='TRUE';
    'VSS'<819>:
      PIN_NUMBER='(0,0,0,0,0,0,0,0,0,0,0,0,0,0,0,0,0,0,0,0,0,0,0,0,AH65,0,0,0,0,~
0)';
      PINUSE='GROUND';
      NO_LOAD_CHECK='Both';
      NO_IO_CHECK='Both';
      NO_ASSERT_CHECK='TRUE';
      NO_DIR_CHECK='TRUE';
      ALLOW_CONNECT='TRUE';
    'VSS'<818>:
      PIN_NUMBER='(0,0,0,0,0,0,0,0,0,0,0,0,0,0,0,0,0,0,0,0,0,0,0,0,AH69,0,0,0,0,~
0)';
      PINUSE='GROUND';
      NO_LOAD_CHECK='Both';
      NO_IO_CHECK='Both';
      NO_ASSERT_CHECK='TRUE';
      NO_DIR_CHECK='TRUE';
      ALLOW_CONNECT='TRUE';
    'VSS'<817>:
      PIN_NUMBER='(0,0,0,0,0,0,0,0,0,0,0,0,0,0,0,0,0,0,0,0,0,0,0,0,AH75,0,0,0,0,~
0)';
      PINUSE='GROUND';
      NO_LOAD_CHECK='Both';
      NO_IO_CHECK='Both';
      NO_ASSERT_CHECK='TRUE';
      NO_DIR_CHECK='TRUE';
      ALLOW_CONNECT='TRUE';
    'VSS'<816>:
      PIN_NUMBER='(0,0,0,0,0,0,0,0,0,0,0,0,0,0,0,0,0,0,0,0,0,0,0,0,AH77,0,0,0,0,~
0)';
      PINUSE='GROUND';
      NO_LOAD_CHECK='Both';
      NO_IO_CHECK='Both';
      NO_ASSERT_CHECK='TRUE';
      NO_DIR_CHECK='TRUE';
      ALLOW_CONNECT='TRUE';
    'VSS'<815>:
      PIN_NUMBER='(0,0,0,0,0,0,0,0,0,0,0,0,0,0,0,0,0,0,0,0,0,0,0,0,AH83,0,0,0,0,~
0)';
      PINUSE='GROUND';
      NO_LOAD_CHECK='Both';
      NO_IO_CHECK='Both';
      NO_ASSERT_CHECK='TRUE';
      NO_DIR_CHECK='TRUE';
      ALLOW_CONNECT='TRUE';
    'VSS'<814>:
      PIN_NUMBER='(0,0,0,0,0,0,0,0,0,0,0,0,0,0,0,0,0,0,0,0,0,0,0,0,AJ8,0,0,0,0,0~
)';
      PINUSE='GROUND';
      NO_LOAD_CHECK='Both';
      NO_IO_CHECK='Both';
      NO_ASSERT_CHECK='TRUE';
      NO_DIR_CHECK='TRUE';
      ALLOW_CONNECT='TRUE';
    'VSS'<813>:
      PIN_NUMBER='(0,0,0,0,0,0,0,0,0,0,0,0,0,0,0,0,0,0,0,0,0,0,0,0,AJ22,0,0,0,0,~
0)';
      PINUSE='GROUND';
      NO_LOAD_CHECK='Both';
      NO_IO_CHECK='Both';
      NO_ASSERT_CHECK='TRUE';
      NO_DIR_CHECK='TRUE';
      ALLOW_CONNECT='TRUE';
    'VSS'<812>:
      PIN_NUMBER='(0,0,0,0,0,0,0,0,0,0,0,0,0,0,0,0,0,0,0,0,0,0,0,0,AJ26,0,0,0,0,~
0)';
      PINUSE='GROUND';
      NO_LOAD_CHECK='Both';
      NO_IO_CHECK='Both';
      NO_ASSERT_CHECK='TRUE';
      NO_DIR_CHECK='TRUE';
      ALLOW_CONNECT='TRUE';
    'VSS'<811>:
      PIN_NUMBER='(0,0,0,0,0,0,0,0,0,0,0,0,0,0,0,0,0,0,0,0,0,0,0,0,AJ28,0,0,0,0,~
0)';
      PINUSE='GROUND';
      NO_LOAD_CHECK='Both';
      NO_IO_CHECK='Both';
      NO_ASSERT_CHECK='TRUE';
      NO_DIR_CHECK='TRUE';
      ALLOW_CONNECT='TRUE';
    'VSS'<810>:
      PIN_NUMBER='(0,0,0,0,0,0,0,0,0,0,0,0,0,0,0,0,0,0,0,0,0,0,0,0,AJ32,0,0,0,0,~
0)';
      PINUSE='GROUND';
      NO_LOAD_CHECK='Both';
      NO_IO_CHECK='Both';
      NO_ASSERT_CHECK='TRUE';
      NO_DIR_CHECK='TRUE';
      ALLOW_CONNECT='TRUE';
    'VSS'<809>:
      PIN_NUMBER='(0,0,0,0,0,0,0,0,0,0,0,0,0,0,0,0,0,0,0,0,0,0,0,0,AJ34,0,0,0,0,~
0)';
      PINUSE='GROUND';
      NO_LOAD_CHECK='Both';
      NO_IO_CHECK='Both';
      NO_ASSERT_CHECK='TRUE';
      NO_DIR_CHECK='TRUE';
      ALLOW_CONNECT='TRUE';
    'VSS'<808>:
      PIN_NUMBER='(0,0,0,0,0,0,0,0,0,0,0,0,0,0,0,0,0,0,0,0,0,0,0,0,AJ46,0,0,0,0,~
0)';
      PINUSE='GROUND';
      NO_LOAD_CHECK='Both';
      NO_IO_CHECK='Both';
      NO_ASSERT_CHECK='TRUE';
      NO_DIR_CHECK='TRUE';
      ALLOW_CONNECT='TRUE';
    'VSS'<807>:
      PIN_NUMBER='(0,0,0,0,0,0,0,0,0,0,0,0,0,0,0,0,0,0,0,0,0,0,0,0,AJ48,0,0,0,0,~
0)';
      PINUSE='GROUND';
      NO_LOAD_CHECK='Both';
      NO_IO_CHECK='Both';
      NO_ASSERT_CHECK='TRUE';
      NO_DIR_CHECK='TRUE';
      ALLOW_CONNECT='TRUE';
    'VSS'<806>:
      PIN_NUMBER='(0,0,0,0,0,0,0,0,0,0,0,0,0,0,0,0,0,0,0,0,0,0,0,0,AJ50,0,0,0,0,~
0)';
      PINUSE='GROUND';
      NO_LOAD_CHECK='Both';
      NO_IO_CHECK='Both';
      NO_ASSERT_CHECK='TRUE';
      NO_DIR_CHECK='TRUE';
      ALLOW_CONNECT='TRUE';
    'VSS'<805>:
      PIN_NUMBER='(0,0,0,0,0,0,0,0,0,0,0,0,0,0,0,0,0,0,0,0,0,0,0,0,AJ52,0,0,0,0,~
0)';
      PINUSE='GROUND';
      NO_LOAD_CHECK='Both';
      NO_IO_CHECK='Both';
      NO_ASSERT_CHECK='TRUE';
      NO_DIR_CHECK='TRUE';
      ALLOW_CONNECT='TRUE';
    'VSS'<804>:
      PIN_NUMBER='(0,0,0,0,0,0,0,0,0,0,0,0,0,0,0,0,0,0,0,0,0,0,0,0,AJ54,0,0,0,0,~
0)';
      PINUSE='GROUND';
      NO_LOAD_CHECK='Both';
      NO_IO_CHECK='Both';
      NO_ASSERT_CHECK='TRUE';
      NO_DIR_CHECK='TRUE';
      ALLOW_CONNECT='TRUE';
    'VSS'<803>:
      PIN_NUMBER='(0,0,0,0,0,0,0,0,0,0,0,0,0,0,0,0,0,0,0,0,0,0,0,0,AJ66,0,0,0,0,~
0)';
      PINUSE='GROUND';
      NO_LOAD_CHECK='Both';
      NO_IO_CHECK='Both';
      NO_ASSERT_CHECK='TRUE';
      NO_DIR_CHECK='TRUE';
      ALLOW_CONNECT='TRUE';
    'VSS'<802>:
      PIN_NUMBER='(0,0,0,0,0,0,0,0,0,0,0,0,0,0,0,0,0,0,0,0,0,0,0,0,AJ68,0,0,0,0,~
0)';
      PINUSE='GROUND';
      NO_LOAD_CHECK='Both';
      NO_IO_CHECK='Both';
      NO_ASSERT_CHECK='TRUE';
      NO_DIR_CHECK='TRUE';
      ALLOW_CONNECT='TRUE';
    'VSS'<801>:
      PIN_NUMBER='(0,0,0,0,0,0,0,0,0,0,0,0,0,0,0,0,0,0,0,0,0,0,0,0,AJ74,0,0,0,0,~
0)';
      PINUSE='GROUND';
      NO_LOAD_CHECK='Both';
      NO_IO_CHECK='Both';
      NO_ASSERT_CHECK='TRUE';
      NO_DIR_CHECK='TRUE';
      ALLOW_CONNECT='TRUE';
    'VSS'<800>:
      PIN_NUMBER='(0,0,0,0,0,0,0,0,0,0,0,0,0,0,0,0,0,0,0,0,0,0,0,0,AJ78,0,0,0,0,~
0)';
      PINUSE='GROUND';
      NO_LOAD_CHECK='Both';
      NO_IO_CHECK='Both';
      NO_ASSERT_CHECK='TRUE';
      NO_DIR_CHECK='TRUE';
      ALLOW_CONNECT='TRUE';
    'VSS'<799>:
      PIN_NUMBER='(0,0,0,0,0,0,0,0,0,0,0,0,0,0,0,0,0,0,0,0,0,0,0,0,AJ82,0,0,0,0,~
0)';
      PINUSE='GROUND';
      NO_LOAD_CHECK='Both';
      NO_IO_CHECK='Both';
      NO_ASSERT_CHECK='TRUE';
      NO_DIR_CHECK='TRUE';
      ALLOW_CONNECT='TRUE';
    'VSS'<798>:
      PIN_NUMBER='(0,0,0,0,0,0,0,0,0,0,0,0,0,0,0,0,0,0,0,0,0,0,0,0,AJ86,0,0,0,0,~
0)';
      PINUSE='GROUND';
      NO_LOAD_CHECK='Both';
      NO_IO_CHECK='Both';
      NO_ASSERT_CHECK='TRUE';
      NO_DIR_CHECK='TRUE';
      ALLOW_CONNECT='TRUE';
    'VSS'<797>:
      PIN_NUMBER='(0,0,0,0,0,0,0,0,0,0,0,0,0,0,0,0,0,0,0,0,0,0,0,0,AK9,0,0,0,0,0~
)';
      PINUSE='GROUND';
      NO_LOAD_CHECK='Both';
      NO_IO_CHECK='Both';
      NO_ASSERT_CHECK='TRUE';
      NO_DIR_CHECK='TRUE';
      ALLOW_CONNECT='TRUE';
    'VSS'<796>:
      PIN_NUMBER='(0,0,0,0,0,0,0,0,0,0,0,0,0,0,0,0,0,0,0,0,0,0,0,0,AK13,0,0,0,0,~
0)';
      PINUSE='GROUND';
      NO_LOAD_CHECK='Both';
      NO_IO_CHECK='Both';
      NO_ASSERT_CHECK='TRUE';
      NO_DIR_CHECK='TRUE';
      ALLOW_CONNECT='TRUE';
    'VSS'<795>:
      PIN_NUMBER='(0,0,0,0,0,0,0,0,0,0,0,0,0,0,0,0,0,0,0,0,0,0,0,0,AK19,0,0,0,0,~
0)';
      PINUSE='GROUND';
      NO_LOAD_CHECK='Both';
      NO_IO_CHECK='Both';
      NO_ASSERT_CHECK='TRUE';
      NO_DIR_CHECK='TRUE';
      ALLOW_CONNECT='TRUE';
    'VSS'<794>:
      PIN_NUMBER='(0,0,0,0,0,0,0,0,0,0,0,0,0,0,0,0,0,0,0,0,0,0,0,0,AK23,0,0,0,0,~
0)';
      PINUSE='GROUND';
      NO_LOAD_CHECK='Both';
      NO_IO_CHECK='Both';
      NO_ASSERT_CHECK='TRUE';
      NO_DIR_CHECK='TRUE';
      ALLOW_CONNECT='TRUE';
    'VSS'<793>:
      PIN_NUMBER='(0,0,0,0,0,0,0,0,0,0,0,0,0,0,0,0,0,0,0,0,0,0,0,0,AK25,0,0,0,0,~
0)';
      PINUSE='GROUND';
      NO_LOAD_CHECK='Both';
      NO_IO_CHECK='Both';
      NO_ASSERT_CHECK='TRUE';
      NO_DIR_CHECK='TRUE';
      ALLOW_CONNECT='TRUE';
    'VSS'<792>:
      PIN_NUMBER='(0,0,0,0,0,0,0,0,0,0,0,0,0,0,0,0,0,0,0,0,0,0,0,0,AK29,0,0,0,0,~
0)';
      PINUSE='GROUND';
      NO_LOAD_CHECK='Both';
      NO_IO_CHECK='Both';
      NO_ASSERT_CHECK='TRUE';
      NO_DIR_CHECK='TRUE';
      ALLOW_CONNECT='TRUE';
    'VSS'<791>:
      PIN_NUMBER='(0,0,0,0,0,0,0,0,0,0,0,0,0,0,0,0,0,0,0,0,0,0,0,0,AK31,0,0,0,0,~
0)';
      PINUSE='GROUND';
      NO_LOAD_CHECK='Both';
      NO_IO_CHECK='Both';
      NO_ASSERT_CHECK='TRUE';
      NO_DIR_CHECK='TRUE';
      ALLOW_CONNECT='TRUE';
    'VSS'<790>:
      PIN_NUMBER='(0,0,0,0,0,0,0,0,0,0,0,0,0,0,0,0,0,0,0,0,0,0,0,0,AK33,0,0,0,0,~
0)';
      PINUSE='GROUND';
      NO_LOAD_CHECK='Both';
      NO_IO_CHECK='Both';
      NO_ASSERT_CHECK='TRUE';
      NO_DIR_CHECK='TRUE';
      ALLOW_CONNECT='TRUE';
    'VSS'<789>:
      PIN_NUMBER='(0,0,0,0,0,0,0,0,0,0,0,0,0,0,0,0,0,0,0,0,0,0,0,0,AK55,0,0,0,0,~
0)';
      PINUSE='GROUND';
      NO_LOAD_CHECK='Both';
      NO_IO_CHECK='Both';
      NO_ASSERT_CHECK='TRUE';
      NO_DIR_CHECK='TRUE';
      ALLOW_CONNECT='TRUE';
    'VSS'<788>:
      PIN_NUMBER='(0,0,0,0,0,0,0,0,0,0,0,0,0,0,0,0,0,0,0,0,0,0,0,0,AK65,0,0,0,0,~
0)';
      PINUSE='GROUND';
      NO_LOAD_CHECK='Both';
      NO_IO_CHECK='Both';
      NO_ASSERT_CHECK='TRUE';
      NO_DIR_CHECK='TRUE';
      ALLOW_CONNECT='TRUE';
    'VSS'<787>:
      PIN_NUMBER='(0,0,0,0,0,0,0,0,0,0,0,0,0,0,0,0,0,0,0,0,0,0,0,0,AK67,0,0,0,0,~
0)';
      PINUSE='GROUND';
      NO_LOAD_CHECK='Both';
      NO_IO_CHECK='Both';
      NO_ASSERT_CHECK='TRUE';
      NO_DIR_CHECK='TRUE';
      ALLOW_CONNECT='TRUE';
    'VSS'<786>:
      PIN_NUMBER='(0,0,0,0,0,0,0,0,0,0,0,0,0,0,0,0,0,0,0,0,0,0,0,0,AK73,0,0,0,0,~
0)';
      PINUSE='GROUND';
      NO_LOAD_CHECK='Both';
      NO_IO_CHECK='Both';
      NO_ASSERT_CHECK='TRUE';
      NO_DIR_CHECK='TRUE';
      ALLOW_CONNECT='TRUE';
    'VSS'<785>:
      PIN_NUMBER='(0,0,0,0,0,0,0,0,0,0,0,0,0,0,0,0,0,0,0,0,0,0,0,0,AK79,0,0,0,0,~
0)';
      PINUSE='GROUND';
      NO_LOAD_CHECK='Both';
      NO_IO_CHECK='Both';
      NO_ASSERT_CHECK='TRUE';
      NO_DIR_CHECK='TRUE';
      ALLOW_CONNECT='TRUE';
    'VSS'<784>:
      PIN_NUMBER='(0,0,0,0,0,0,0,0,0,0,0,0,0,0,0,0,0,0,0,0,0,0,0,0,AK81,0,0,0,0,~
0)';
      PINUSE='GROUND';
      NO_LOAD_CHECK='Both';
      NO_IO_CHECK='Both';
      NO_ASSERT_CHECK='TRUE';
      NO_DIR_CHECK='TRUE';
      ALLOW_CONNECT='TRUE';
    'VSS'<783>:
      PIN_NUMBER='(0,0,0,0,0,0,0,0,0,0,0,0,0,0,0,0,0,0,0,0,0,0,0,0,AK83,0,0,0,0,~
0)';
      PINUSE='GROUND';
      NO_LOAD_CHECK='Both';
      NO_IO_CHECK='Both';
      NO_ASSERT_CHECK='TRUE';
      NO_DIR_CHECK='TRUE';
      ALLOW_CONNECT='TRUE';
    'VSS'<782>:
      PIN_NUMBER='(0,0,0,0,0,0,0,0,0,0,0,0,0,0,0,0,0,0,0,0,0,0,0,0,AK85,0,0,0,0,~
0)';
      PINUSE='GROUND';
      NO_LOAD_CHECK='Both';
      NO_IO_CHECK='Both';
      NO_ASSERT_CHECK='TRUE';
      NO_DIR_CHECK='TRUE';
      ALLOW_CONNECT='TRUE';
    'VSS'<781>:
      PIN_NUMBER='(0,0,0,0,0,0,0,0,0,0,0,0,0,0,0,0,0,0,0,0,0,0,0,0,AL4,0,0,0,0,0~
)';
      PINUSE='GROUND';
      NO_LOAD_CHECK='Both';
      NO_IO_CHECK='Both';
      NO_ASSERT_CHECK='TRUE';
      NO_DIR_CHECK='TRUE';
      ALLOW_CONNECT='TRUE';
    'VSS'<780>:
      PIN_NUMBER='(0,0,0,0,0,0,0,0,0,0,0,0,0,0,0,0,0,0,0,0,0,0,0,0,AL10,0,0,0,0,~
0)';
      PINUSE='GROUND';
      NO_LOAD_CHECK='Both';
      NO_IO_CHECK='Both';
      NO_ASSERT_CHECK='TRUE';
      NO_DIR_CHECK='TRUE';
      ALLOW_CONNECT='TRUE';
    'VSS'<779>:
      PIN_NUMBER='(0,0,0,0,0,0,0,0,0,0,0,0,0,0,0,0,0,0,0,0,0,0,0,0,AL24,0,0,0,0,~
0)';
      PINUSE='GROUND';
      NO_LOAD_CHECK='Both';
      NO_IO_CHECK='Both';
      NO_ASSERT_CHECK='TRUE';
      NO_DIR_CHECK='TRUE';
      ALLOW_CONNECT='TRUE';
    'VSS'<778>:
      PIN_NUMBER='(0,0,0,0,0,0,0,0,0,0,0,0,0,0,0,0,0,0,0,0,0,0,0,0,AL30,0,0,0,0,~
0)';
      PINUSE='GROUND';
      NO_LOAD_CHECK='Both';
      NO_IO_CHECK='Both';
      NO_ASSERT_CHECK='TRUE';
      NO_DIR_CHECK='TRUE';
      ALLOW_CONNECT='TRUE';
    'VSS'<777>:
      PIN_NUMBER='(0,0,0,0,0,0,0,0,0,0,0,0,0,0,0,0,0,0,0,0,0,0,0,0,AL32,0,0,0,0,~
0)';
      PINUSE='GROUND';
      NO_LOAD_CHECK='Both';
      NO_IO_CHECK='Both';
      NO_ASSERT_CHECK='TRUE';
      NO_DIR_CHECK='TRUE';
      ALLOW_CONNECT='TRUE';
    'VSS'<776>:
      PIN_NUMBER='(0,0,0,0,0,0,0,0,0,0,0,0,0,0,0,0,0,0,0,0,0,0,0,0,AL56,0,0,0,0,~
0)';
      PINUSE='GROUND';
      NO_LOAD_CHECK='Both';
      NO_IO_CHECK='Both';
      NO_ASSERT_CHECK='TRUE';
      NO_DIR_CHECK='TRUE';
      ALLOW_CONNECT='TRUE';
    'VSS'<775>:
      PIN_NUMBER='(0,0,0,0,0,0,0,0,0,0,0,0,0,0,0,0,0,0,0,0,0,0,0,0,AL64,0,0,0,0,~
0)';
      PINUSE='GROUND';
      NO_LOAD_CHECK='Both';
      NO_IO_CHECK='Both';
      NO_ASSERT_CHECK='TRUE';
      NO_DIR_CHECK='TRUE';
      ALLOW_CONNECT='TRUE';
    'VSS'<774>:
      PIN_NUMBER='(0,0,0,0,0,0,0,0,0,0,0,0,0,0,0,0,0,0,0,0,0,0,0,0,AL68,0,0,0,0,~
0)';
      PINUSE='GROUND';
      NO_LOAD_CHECK='Both';
      NO_IO_CHECK='Both';
      NO_ASSERT_CHECK='TRUE';
      NO_DIR_CHECK='TRUE';
      ALLOW_CONNECT='TRUE';
    'VSS'<773>:
      PIN_NUMBER='(0,0,0,0,0,0,0,0,0,0,0,0,0,0,0,0,0,0,0,0,0,0,0,0,0,AL76,0,0,0,~
0)';
      PINUSE='GROUND';
      NO_LOAD_CHECK='Both';
      NO_IO_CHECK='Both';
      NO_ASSERT_CHECK='TRUE';
      NO_DIR_CHECK='TRUE';
      ALLOW_CONNECT='TRUE';
    'VSS'<772>:
      PIN_NUMBER='(0,0,0,0,0,0,0,0,0,0,0,0,0,0,0,0,0,0,0,0,0,0,0,0,0,AL78,0,0,0,~
0)';
      PINUSE='GROUND';
      NO_LOAD_CHECK='Both';
      NO_IO_CHECK='Both';
      NO_ASSERT_CHECK='TRUE';
      NO_DIR_CHECK='TRUE';
      ALLOW_CONNECT='TRUE';
    'VSS'<771>:
      PIN_NUMBER='(0,0,0,0,0,0,0,0,0,0,0,0,0,0,0,0,0,0,0,0,0,0,0,0,0,AL80,0,0,0,~
0)';
      PINUSE='GROUND';
      NO_LOAD_CHECK='Both';
      NO_IO_CHECK='Both';
      NO_ASSERT_CHECK='TRUE';
      NO_DIR_CHECK='TRUE';
      ALLOW_CONNECT='TRUE';
    'VSS'<770>:
      PIN_NUMBER='(0,0,0,0,0,0,0,0,0,0,0,0,0,0,0,0,0,0,0,0,0,0,0,0,0,AL82,0,0,0,~
0)';
      PINUSE='GROUND';
      NO_LOAD_CHECK='Both';
      NO_IO_CHECK='Both';
      NO_ASSERT_CHECK='TRUE';
      NO_DIR_CHECK='TRUE';
      ALLOW_CONNECT='TRUE';
    'VSS'<769>:
      PIN_NUMBER='(0,0,0,0,0,0,0,0,0,0,0,0,0,0,0,0,0,0,0,0,0,0,0,0,0,AL86,0,0,0,~
0)';
      PINUSE='GROUND';
      NO_LOAD_CHECK='Both';
      NO_IO_CHECK='Both';
      NO_ASSERT_CHECK='TRUE';
      NO_DIR_CHECK='TRUE';
      ALLOW_CONNECT='TRUE';
    'VSS'<768>:
      PIN_NUMBER='(0,0,0,0,0,0,0,0,0,0,0,0,0,0,0,0,0,0,0,0,0,0,0,0,0,AM1,0,0,0,0~
)';
      PINUSE='GROUND';
      NO_LOAD_CHECK='Both';
      NO_IO_CHECK='Both';
      NO_ASSERT_CHECK='TRUE';
      NO_DIR_CHECK='TRUE';
      ALLOW_CONNECT='TRUE';
    'VSS'<767>:
      PIN_NUMBER='(0,0,0,0,0,0,0,0,0,0,0,0,0,0,0,0,0,0,0,0,0,0,0,0,0,AC50,0,0,0,~
0)';
      PINUSE='GROUND';
      NO_LOAD_CHECK='Both';
      NO_IO_CHECK='Both';
      NO_ASSERT_CHECK='TRUE';
      NO_DIR_CHECK='TRUE';
      ALLOW_CONNECT='TRUE';
    'VSS'<766>:
      PIN_NUMBER='(0,0,0,0,0,0,0,0,0,0,0,0,0,0,0,0,0,0,0,0,0,0,0,0,0,AM31,0,0,0,~
0)';
      PINUSE='GROUND';
      NO_LOAD_CHECK='Both';
      NO_IO_CHECK='Both';
      NO_ASSERT_CHECK='TRUE';
      NO_DIR_CHECK='TRUE';
      ALLOW_CONNECT='TRUE';
    'VSS'<765>:
      PIN_NUMBER='(0,0,0,0,0,0,0,0,0,0,0,0,0,0,0,0,0,0,0,0,0,0,0,0,0,AM57,0,0,0,~
0)';
      PINUSE='GROUND';
      NO_LOAD_CHECK='Both';
      NO_IO_CHECK='Both';
      NO_ASSERT_CHECK='TRUE';
      NO_DIR_CHECK='TRUE';
      ALLOW_CONNECT='TRUE';
    'VSS'<764>:
      PIN_NUMBER='(0,0,0,0,0,0,0,0,0,0,0,0,0,0,0,0,0,0,0,0,0,0,0,0,0,AM63,0,0,0,~
0)';
      PINUSE='GROUND';
      NO_LOAD_CHECK='Both';
      NO_IO_CHECK='Both';
      NO_ASSERT_CHECK='TRUE';
      NO_DIR_CHECK='TRUE';
      ALLOW_CONNECT='TRUE';
    'VSS'<763>:
      PIN_NUMBER='(0,0,0,0,0,0,0,0,0,0,0,0,0,0,0,0,0,0,0,0,0,0,0,0,0,AM69,0,0,0,~
0)';
      PINUSE='GROUND';
      NO_LOAD_CHECK='Both';
      NO_IO_CHECK='Both';
      NO_ASSERT_CHECK='TRUE';
      NO_DIR_CHECK='TRUE';
      ALLOW_CONNECT='TRUE';
    'VSS'<762>:
      PIN_NUMBER='(0,0,0,0,0,0,0,0,0,0,0,0,0,0,0,0,0,0,0,0,0,0,0,0,0,AM73,0,0,0,~
0)';
      PINUSE='GROUND';
      NO_LOAD_CHECK='Both';
      NO_IO_CHECK='Both';
      NO_ASSERT_CHECK='TRUE';
      NO_DIR_CHECK='TRUE';
      ALLOW_CONNECT='TRUE';
    'VSS'<761>:
      PIN_NUMBER='(0,0,0,0,0,0,0,0,0,0,0,0,0,0,0,0,0,0,0,0,0,0,0,0,0,AM79,0,0,0,~
0)';
      PINUSE='GROUND';
      NO_LOAD_CHECK='Both';
      NO_IO_CHECK='Both';
      NO_ASSERT_CHECK='TRUE';
      NO_DIR_CHECK='TRUE';
      ALLOW_CONNECT='TRUE';
    'VSS'<760>:
      PIN_NUMBER='(0,0,0,0,0,0,0,0,0,0,0,0,0,0,0,0,0,0,0,0,0,0,0,0,0,AM83,0,0,0,~
0)';
      PINUSE='GROUND';
      NO_LOAD_CHECK='Both';
      NO_IO_CHECK='Both';
      NO_ASSERT_CHECK='TRUE';
      NO_DIR_CHECK='TRUE';
      ALLOW_CONNECT='TRUE';
    'VSS'<759>:
      PIN_NUMBER='(0,0,0,0,0,0,0,0,0,0,0,0,0,0,0,0,0,0,0,0,0,0,0,0,0,AN2,0,0,0,0~
)';
      PINUSE='GROUND';
      NO_LOAD_CHECK='Both';
      NO_IO_CHECK='Both';
      NO_ASSERT_CHECK='TRUE';
      NO_DIR_CHECK='TRUE';
      ALLOW_CONNECT='TRUE';
    'VSS'<758>:
      PIN_NUMBER='(0,0,0,0,0,0,0,0,0,0,0,0,0,0,0,0,0,0,0,0,0,0,0,0,0,AN6,0,0,0,0~
)';
      PINUSE='GROUND';
      NO_LOAD_CHECK='Both';
      NO_IO_CHECK='Both';
      NO_ASSERT_CHECK='TRUE';
      NO_DIR_CHECK='TRUE';
      ALLOW_CONNECT='TRUE';
    'VSS'<757>:
      PIN_NUMBER='(0,0,0,0,0,0,0,0,0,0,0,0,0,0,0,0,0,0,0,0,0,0,0,0,0,AN28,0,0,0,~
0)';
      PINUSE='GROUND';
      NO_LOAD_CHECK='Both';
      NO_IO_CHECK='Both';
      NO_ASSERT_CHECK='TRUE';
      NO_DIR_CHECK='TRUE';
      ALLOW_CONNECT='TRUE';
    'VSS'<756>:
      PIN_NUMBER='(0,0,0,0,0,0,0,0,0,0,0,0,0,0,0,0,0,0,0,0,0,0,0,0,0,AN58,0,0,0,~
0)';
      PINUSE='GROUND';
      NO_LOAD_CHECK='Both';
      NO_IO_CHECK='Both';
      NO_ASSERT_CHECK='TRUE';
      NO_DIR_CHECK='TRUE';
      ALLOW_CONNECT='TRUE';
    'VSS'<755>:
      PIN_NUMBER='(0,0,0,0,0,0,0,0,0,0,0,0,0,0,0,0,0,0,0,0,0,0,0,0,0,AN78,0,0,0,~
0)';
      PINUSE='GROUND';
      NO_LOAD_CHECK='Both';
      NO_IO_CHECK='Both';
      NO_ASSERT_CHECK='TRUE';
      NO_DIR_CHECK='TRUE';
      ALLOW_CONNECT='TRUE';
    'VSS'<754>:
      PIN_NUMBER='(0,0,0,0,0,0,0,0,0,0,0,0,0,0,0,0,0,0,0,0,0,0,0,0,0,AP5,0,0,0,0~
)';
      PINUSE='GROUND';
      NO_LOAD_CHECK='Both';
      NO_IO_CHECK='Both';
      NO_ASSERT_CHECK='TRUE';
      NO_DIR_CHECK='TRUE';
      ALLOW_CONNECT='TRUE';
    'VSS'<753>:
      PIN_NUMBER='(0,0,0,0,0,0,0,0,0,0,0,0,0,0,0,0,0,0,0,0,0,0,0,0,0,AP9,0,0,0,0~
)';
      PINUSE='GROUND';
      NO_LOAD_CHECK='Both';
      NO_IO_CHECK='Both';
      NO_ASSERT_CHECK='TRUE';
      NO_DIR_CHECK='TRUE';
      ALLOW_CONNECT='TRUE';
    'VSS'<752>:
      PIN_NUMBER='(0,0,0,0,0,0,0,0,0,0,0,0,0,0,0,0,0,0,0,0,0,0,0,0,0,AP13,0,0,0,~
0)';
      PINUSE='GROUND';
      NO_LOAD_CHECK='Both';
      NO_IO_CHECK='Both';
      NO_ASSERT_CHECK='TRUE';
      NO_DIR_CHECK='TRUE';
      ALLOW_CONNECT='TRUE';
    'VSS'<751>:
      PIN_NUMBER='(0,0,0,0,0,0,0,0,0,0,0,0,0,0,0,0,0,0,0,0,0,0,0,0,0,AP19,0,0,0,~
0)';
      PINUSE='GROUND';
      NO_LOAD_CHECK='Both';
      NO_IO_CHECK='Both';
      NO_ASSERT_CHECK='TRUE';
      NO_DIR_CHECK='TRUE';
      ALLOW_CONNECT='TRUE';
    'VSS'<750>:
      PIN_NUMBER='(0,0,0,0,0,0,0,0,0,0,0,0,0,0,0,0,0,0,0,0,0,0,0,0,0,AP31,0,0,0,~
0)';
      PINUSE='GROUND';
      NO_LOAD_CHECK='Both';
      NO_IO_CHECK='Both';
      NO_ASSERT_CHECK='TRUE';
      NO_DIR_CHECK='TRUE';
      ALLOW_CONNECT='TRUE';
    'VSS'<749>:
      PIN_NUMBER='(0,0,0,0,0,0,0,0,0,0,0,0,0,0,0,0,0,0,0,0,0,0,0,0,0,AP59,0,0,0,~
0)';
      PINUSE='GROUND';
      NO_LOAD_CHECK='Both';
      NO_IO_CHECK='Both';
      NO_ASSERT_CHECK='TRUE';
      NO_DIR_CHECK='TRUE';
      ALLOW_CONNECT='TRUE';
    'VSS'<748>:
      PIN_NUMBER='(0,0,0,0,0,0,0,0,0,0,0,0,0,0,0,0,0,0,0,0,0,0,0,0,0,AP63,0,0,0,~
0)';
      PINUSE='GROUND';
      NO_LOAD_CHECK='Both';
      NO_IO_CHECK='Both';
      NO_ASSERT_CHECK='TRUE';
      NO_DIR_CHECK='TRUE';
      ALLOW_CONNECT='TRUE';
    'VSS'<747>:
      PIN_NUMBER='(0,0,0,0,0,0,0,0,0,0,0,0,0,0,0,0,0,0,0,0,0,0,0,0,0,AP65,0,0,0,~
0)';
      PINUSE='GROUND';
      NO_LOAD_CHECK='Both';
      NO_IO_CHECK='Both';
      NO_ASSERT_CHECK='TRUE';
      NO_DIR_CHECK='TRUE';
      ALLOW_CONNECT='TRUE';
    'VSS'<746>:
      PIN_NUMBER='(0,0,0,0,0,0,0,0,0,0,0,0,0,0,0,0,0,0,0,0,0,0,0,0,0,AP67,0,0,0,~
0)';
      PINUSE='GROUND';
      NO_LOAD_CHECK='Both';
      NO_IO_CHECK='Both';
      NO_ASSERT_CHECK='TRUE';
      NO_DIR_CHECK='TRUE';
      ALLOW_CONNECT='TRUE';
    'VSS'<745>:
      PIN_NUMBER='(0,0,0,0,0,0,0,0,0,0,0,0,0,0,0,0,0,0,0,0,0,0,0,0,0,AP69,0,0,0,~
0)';
      PINUSE='GROUND';
      NO_LOAD_CHECK='Both';
      NO_IO_CHECK='Both';
      NO_ASSERT_CHECK='TRUE';
      NO_DIR_CHECK='TRUE';
      ALLOW_CONNECT='TRUE';
    'VSS'<744>:
      PIN_NUMBER='(0,0,0,0,0,0,0,0,0,0,0,0,0,0,0,0,0,0,0,0,0,0,0,0,0,AP73,0,0,0,~
0)';
      PINUSE='GROUND';
      NO_LOAD_CHECK='Both';
      NO_IO_CHECK='Both';
      NO_ASSERT_CHECK='TRUE';
      NO_DIR_CHECK='TRUE';
      ALLOW_CONNECT='TRUE';
    'VSS'<743>:
      PIN_NUMBER='(0,0,0,0,0,0,0,0,0,0,0,0,0,0,0,0,0,0,0,0,0,0,0,0,0,AP75,0,0,0,~
0)';
      PINUSE='GROUND';
      NO_LOAD_CHECK='Both';
      NO_IO_CHECK='Both';
      NO_ASSERT_CHECK='TRUE';
      NO_DIR_CHECK='TRUE';
      ALLOW_CONNECT='TRUE';
    'VSS'<742>:
      PIN_NUMBER='(0,0,0,0,0,0,0,0,0,0,0,0,0,0,0,0,0,0,0,0,0,0,0,0,0,AP81,0,0,0,~
0)';
      PINUSE='GROUND';
      NO_LOAD_CHECK='Both';
      NO_IO_CHECK='Both';
      NO_ASSERT_CHECK='TRUE';
      NO_DIR_CHECK='TRUE';
      ALLOW_CONNECT='TRUE';
    'VSS'<741>:
      PIN_NUMBER='(0,0,0,0,0,0,0,0,0,0,0,0,0,0,0,0,0,0,0,0,0,0,0,0,0,AP83,0,0,0,~
0)';
      PINUSE='GROUND';
      NO_LOAD_CHECK='Both';
      NO_IO_CHECK='Both';
      NO_ASSERT_CHECK='TRUE';
      NO_DIR_CHECK='TRUE';
      ALLOW_CONNECT='TRUE';
    'VSS'<740>:
      PIN_NUMBER='(0,0,0,0,0,0,0,0,0,0,0,0,0,0,0,0,0,0,0,0,0,0,0,0,0,AP85,0,0,0,~
0)';
      PINUSE='GROUND';
      NO_LOAD_CHECK='Both';
      NO_IO_CHECK='Both';
      NO_ASSERT_CHECK='TRUE';
      NO_DIR_CHECK='TRUE';
      ALLOW_CONNECT='TRUE';
    'VSS'<739>:
      PIN_NUMBER='(0,0,0,0,0,0,0,0,0,0,0,0,0,0,0,0,0,0,0,0,0,0,0,0,0,AR10,0,0,0,~
0)';
      PINUSE='GROUND';
      NO_LOAD_CHECK='Both';
      NO_IO_CHECK='Both';
      NO_ASSERT_CHECK='TRUE';
      NO_DIR_CHECK='TRUE';
      ALLOW_CONNECT='TRUE';
    'VSS'<738>:
      PIN_NUMBER='(0,0,0,0,0,0,0,0,0,0,0,0,0,0,0,0,0,0,0,0,0,0,0,0,0,AR24,0,0,0,~
0)';
      PINUSE='GROUND';
      NO_LOAD_CHECK='Both';
      NO_IO_CHECK='Both';
      NO_ASSERT_CHECK='TRUE';
      NO_DIR_CHECK='TRUE';
      ALLOW_CONNECT='TRUE';
    'VSS'<737>:
      PIN_NUMBER='(0,0,0,0,0,0,0,0,0,0,0,0,0,0,0,0,0,0,0,0,0,0,0,0,0,AR30,0,0,0,~
0)';
      PINUSE='GROUND';
      NO_LOAD_CHECK='Both';
      NO_IO_CHECK='Both';
      NO_ASSERT_CHECK='TRUE';
      NO_DIR_CHECK='TRUE';
      ALLOW_CONNECT='TRUE';
    'VSS'<736>:
      PIN_NUMBER='(0,0,0,0,0,0,0,0,0,0,0,0,0,0,0,0,0,0,0,0,0,0,0,0,0,AR60,0,0,0,~
0)';
      PINUSE='GROUND';
      NO_LOAD_CHECK='Both';
      NO_IO_CHECK='Both';
      NO_ASSERT_CHECK='TRUE';
      NO_DIR_CHECK='TRUE';
      ALLOW_CONNECT='TRUE';
    'VSS'<735>:
      PIN_NUMBER='(0,0,0,0,0,0,0,0,0,0,0,0,0,0,0,0,0,0,0,0,0,0,0,0,0,AR72,0,0,0,~
0)';
      PINUSE='GROUND';
      NO_LOAD_CHECK='Both';
      NO_IO_CHECK='Both';
      NO_ASSERT_CHECK='TRUE';
      NO_DIR_CHECK='TRUE';
      ALLOW_CONNECT='TRUE';
    'VSS'<734>:
      PIN_NUMBER='(0,0,0,0,0,0,0,0,0,0,0,0,0,0,0,0,0,0,0,0,0,0,0,0,0,AR78,0,0,0,~
0)';
      PINUSE='GROUND';
      NO_LOAD_CHECK='Both';
      NO_IO_CHECK='Both';
      NO_ASSERT_CHECK='TRUE';
      NO_DIR_CHECK='TRUE';
      ALLOW_CONNECT='TRUE';
    'VSS'<733>:
      PIN_NUMBER='(0,0,0,0,0,0,0,0,0,0,0,0,0,0,0,0,0,0,0,0,0,0,0,0,0,AC48,0,0,0,~
0)';
      PINUSE='GROUND';
      NO_LOAD_CHECK='Both';
      NO_IO_CHECK='Both';
      NO_ASSERT_CHECK='TRUE';
      NO_DIR_CHECK='TRUE';
      ALLOW_CONNECT='TRUE';
    'VSS'<732>:
      PIN_NUMBER='(0,0,0,0,0,0,0,0,0,0,0,0,0,0,0,0,0,0,0,0,0,0,0,0,0,P63,0,0,0,0~
)';
      PINUSE='GROUND';
      NO_LOAD_CHECK='Both';
      NO_IO_CHECK='Both';
      NO_ASSERT_CHECK='TRUE';
      NO_DIR_CHECK='TRUE';
      ALLOW_CONNECT='TRUE';
    'VSS'<731>:
      PIN_NUMBER='(0,0,0,0,0,0,0,0,0,0,0,0,0,0,0,0,0,0,0,0,0,0,0,0,0,AT15,0,0,0,~
0)';
      PINUSE='GROUND';
      NO_LOAD_CHECK='Both';
      NO_IO_CHECK='Both';
      NO_ASSERT_CHECK='TRUE';
      NO_DIR_CHECK='TRUE';
      ALLOW_CONNECT='TRUE';
    'VSS'<730>:
      PIN_NUMBER='(0,0,0,0,0,0,0,0,0,0,0,0,0,0,0,0,0,0,0,0,0,0,0,0,0,AT17,0,0,0,~
0)';
      PINUSE='GROUND';
      NO_LOAD_CHECK='Both';
      NO_IO_CHECK='Both';
      NO_ASSERT_CHECK='TRUE';
      NO_DIR_CHECK='TRUE';
      ALLOW_CONNECT='TRUE';
    'VSS'<729>:
      PIN_NUMBER='(0,0,0,0,0,0,0,0,0,0,0,0,0,0,0,0,0,0,0,0,0,0,0,0,0,AT21,0,0,0,~
0)';
      PINUSE='GROUND';
      NO_LOAD_CHECK='Both';
      NO_IO_CHECK='Both';
      NO_ASSERT_CHECK='TRUE';
      NO_DIR_CHECK='TRUE';
      ALLOW_CONNECT='TRUE';
    'VSS'<728>:
      PIN_NUMBER='(0,0,0,0,0,0,0,0,0,0,0,0,0,0,0,0,0,0,0,0,0,0,0,0,0,AT27,0,0,0,~
0)';
      PINUSE='GROUND';
      NO_LOAD_CHECK='Both';
      NO_IO_CHECK='Both';
      NO_ASSERT_CHECK='TRUE';
      NO_DIR_CHECK='TRUE';
      ALLOW_CONNECT='TRUE';
    'VSS'<727>:
      PIN_NUMBER='(0,0,0,0,0,0,0,0,0,0,0,0,0,0,0,0,0,0,0,0,0,0,0,0,0,AT61,0,0,0,~
0)';
      PINUSE='GROUND';
      NO_LOAD_CHECK='Both';
      NO_IO_CHECK='Both';
      NO_ASSERT_CHECK='TRUE';
      NO_DIR_CHECK='TRUE';
      ALLOW_CONNECT='TRUE';
    'VSS'<726>:
      PIN_NUMBER='(0,0,0,0,0,0,0,0,0,0,0,0,0,0,0,0,0,0,0,0,0,0,0,0,0,AT63,0,0,0,~
0)';
      PINUSE='GROUND';
      NO_LOAD_CHECK='Both';
      NO_IO_CHECK='Both';
      NO_ASSERT_CHECK='TRUE';
      NO_DIR_CHECK='TRUE';
      ALLOW_CONNECT='TRUE';
    'VSS'<725>:
      PIN_NUMBER='(0,0,0,0,0,0,0,0,0,0,0,0,0,0,0,0,0,0,0,0,0,0,0,0,0,AT69,0,0,0,~
0)';
      PINUSE='GROUND';
      NO_LOAD_CHECK='Both';
      NO_IO_CHECK='Both';
      NO_ASSERT_CHECK='TRUE';
      NO_DIR_CHECK='TRUE';
      ALLOW_CONNECT='TRUE';
    'VSS'<724>:
      PIN_NUMBER='(0,0,0,0,0,0,0,0,0,0,0,0,0,0,0,0,0,0,0,0,0,0,0,0,0,AT73,0,0,0,~
0)';
      PINUSE='GROUND';
      NO_LOAD_CHECK='Both';
      NO_IO_CHECK='Both';
      NO_ASSERT_CHECK='TRUE';
      NO_DIR_CHECK='TRUE';
      ALLOW_CONNECT='TRUE';
    'VSS'<723>:
      PIN_NUMBER='(0,0,0,0,0,0,0,0,0,0,0,0,0,0,0,0,0,0,0,0,0,0,0,0,0,AT77,0,0,0,~
0)';
      PINUSE='GROUND';
      NO_LOAD_CHECK='Both';
      NO_IO_CHECK='Both';
      NO_ASSERT_CHECK='TRUE';
      NO_DIR_CHECK='TRUE';
      ALLOW_CONNECT='TRUE';
    'VSS'<722>:
      PIN_NUMBER='(0,0,0,0,0,0,0,0,0,0,0,0,0,0,0,0,0,0,0,0,0,0,0,0,0,AT83,0,0,0,~
0)';
      PINUSE='GROUND';
      NO_LOAD_CHECK='Both';
      NO_IO_CHECK='Both';
      NO_ASSERT_CHECK='TRUE';
      NO_DIR_CHECK='TRUE';
      ALLOW_CONNECT='TRUE';
    'VSS'<721>:
      PIN_NUMBER='(0,0,0,0,0,0,0,0,0,0,0,0,0,0,0,0,0,0,0,0,0,0,0,0,0,AT85,0,0,0,~
0)';
      PINUSE='GROUND';
      NO_LOAD_CHECK='Both';
      NO_IO_CHECK='Both';
      NO_ASSERT_CHECK='TRUE';
      NO_DIR_CHECK='TRUE';
      ALLOW_CONNECT='TRUE';
    'VSS'<720>:
      PIN_NUMBER='(0,0,0,0,0,0,0,0,0,0,0,0,0,0,0,0,0,0,0,0,0,0,0,0,0,AU2,0,0,0,0~
)';
      PINUSE='GROUND';
      NO_LOAD_CHECK='Both';
      NO_IO_CHECK='Both';
      NO_ASSERT_CHECK='TRUE';
      NO_DIR_CHECK='TRUE';
      ALLOW_CONNECT='TRUE';
    'VSS'<719>:
      PIN_NUMBER='(0,0,0,0,0,0,0,0,0,0,0,0,0,0,0,0,0,0,0,0,0,0,0,0,0,AU6,0,0,0,0~
)';
      PINUSE='GROUND';
      NO_LOAD_CHECK='Both';
      NO_IO_CHECK='Both';
      NO_ASSERT_CHECK='TRUE';
      NO_DIR_CHECK='TRUE';
      ALLOW_CONNECT='TRUE';
    'VSS'<718>:
      PIN_NUMBER='(0,0,0,0,0,0,0,0,0,0,0,0,0,0,0,0,0,0,0,0,0,0,0,0,0,AU26,0,0,0,~
0)';
      PINUSE='GROUND';
      NO_LOAD_CHECK='Both';
      NO_IO_CHECK='Both';
      NO_ASSERT_CHECK='TRUE';
      NO_DIR_CHECK='TRUE';
      ALLOW_CONNECT='TRUE';
    'VSS'<717>:
      PIN_NUMBER='(0,0,0,0,0,0,0,0,0,0,0,0,0,0,0,0,0,0,0,0,0,0,0,0,0,AU28,0,0,0,~
0)';
      PINUSE='GROUND';
      NO_LOAD_CHECK='Both';
      NO_IO_CHECK='Both';
      NO_ASSERT_CHECK='TRUE';
      NO_DIR_CHECK='TRUE';
      ALLOW_CONNECT='TRUE';
    'VSS'<716>:
      PIN_NUMBER='(0,0,0,0,0,0,0,0,0,0,0,0,0,0,0,0,0,0,0,0,0,0,0,0,0,AU62,0,0,0,~
0)';
      PINUSE='GROUND';
      NO_LOAD_CHECK='Both';
      NO_IO_CHECK='Both';
      NO_ASSERT_CHECK='TRUE';
      NO_DIR_CHECK='TRUE';
      ALLOW_CONNECT='TRUE';
    'VSS'<715>:
      PIN_NUMBER='(0,0,0,0,0,0,0,0,0,0,0,0,0,0,0,0,0,0,0,0,0,0,0,0,0,AU64,0,0,0,~
0)';
      PINUSE='GROUND';
      NO_LOAD_CHECK='Both';
      NO_IO_CHECK='Both';
      NO_ASSERT_CHECK='TRUE';
      NO_DIR_CHECK='TRUE';
      ALLOW_CONNECT='TRUE';
    'VSS'<714>:
      PIN_NUMBER='(0,0,0,0,0,0,0,0,0,0,0,0,0,0,0,0,0,0,0,0,0,0,0,0,0,AU68,0,0,0,~
0)';
      PINUSE='GROUND';
      NO_LOAD_CHECK='Both';
      NO_IO_CHECK='Both';
      NO_ASSERT_CHECK='TRUE';
      NO_DIR_CHECK='TRUE';
      ALLOW_CONNECT='TRUE';
    'VSS'<713>:
      PIN_NUMBER='(0,0,0,0,0,0,0,0,0,0,0,0,0,0,0,0,0,0,0,0,0,0,0,0,0,AU74,0,0,0,~
0)';
      PINUSE='GROUND';
      NO_LOAD_CHECK='Both';
      NO_IO_CHECK='Both';
      NO_ASSERT_CHECK='TRUE';
      NO_DIR_CHECK='TRUE';
      ALLOW_CONNECT='TRUE';
    'VSS'<712>:
      PIN_NUMBER='(0,0,0,0,0,0,0,0,0,0,0,0,0,0,0,0,0,0,0,0,0,0,0,0,0,AU76,0,0,0,~
0)';
      PINUSE='GROUND';
      NO_LOAD_CHECK='Both';
      NO_IO_CHECK='Both';
      NO_ASSERT_CHECK='TRUE';
      NO_DIR_CHECK='TRUE';
      ALLOW_CONNECT='TRUE';
    'VSS'<711>:
      PIN_NUMBER='(0,0,0,0,0,0,0,0,0,0,0,0,0,0,0,0,0,0,0,0,0,0,0,0,0,AU78,0,0,0,~
0)';
      PINUSE='GROUND';
      NO_LOAD_CHECK='Both';
      NO_IO_CHECK='Both';
      NO_ASSERT_CHECK='TRUE';
      NO_DIR_CHECK='TRUE';
      ALLOW_CONNECT='TRUE';
    'VSS'<710>:
      PIN_NUMBER='(0,0,0,0,0,0,0,0,0,0,0,0,0,0,0,0,0,0,0,0,0,0,0,0,0,AU80,0,0,0,~
0)';
      PINUSE='GROUND';
      NO_LOAD_CHECK='Both';
      NO_IO_CHECK='Both';
      NO_ASSERT_CHECK='TRUE';
      NO_DIR_CHECK='TRUE';
      ALLOW_CONNECT='TRUE';
    'VSS'<709>:
      PIN_NUMBER='(0,0,0,0,0,0,0,0,0,0,0,0,0,0,0,0,0,0,0,0,0,0,0,0,0,AU84,0,0,0,~
0)';
      PINUSE='GROUND';
      NO_LOAD_CHECK='Both';
      NO_IO_CHECK='Both';
      NO_ASSERT_CHECK='TRUE';
      NO_DIR_CHECK='TRUE';
      ALLOW_CONNECT='TRUE';
    'VSS'<708>:
      PIN_NUMBER='(0,0,0,0,0,0,0,0,0,0,0,0,0,0,0,0,0,0,0,0,0,0,0,0,0,AU86,0,0,0,~
0)';
      PINUSE='GROUND';
      NO_LOAD_CHECK='Both';
      NO_IO_CHECK='Both';
      NO_ASSERT_CHECK='TRUE';
      NO_DIR_CHECK='TRUE';
      ALLOW_CONNECT='TRUE';
    'VSS'<707>:
      PIN_NUMBER='(0,0,0,0,0,0,0,0,0,0,0,0,0,0,0,0,0,0,0,0,0,0,0,0,0,AV1,0,0,0,0~
)';
      PINUSE='GROUND';
      NO_LOAD_CHECK='Both';
      NO_IO_CHECK='Both';
      NO_ASSERT_CHECK='TRUE';
      NO_DIR_CHECK='TRUE';
      ALLOW_CONNECT='TRUE';
    'VSS'<706>:
      PIN_NUMBER='(0,0,0,0,0,0,0,0,0,0,0,0,0,0,0,0,0,0,0,0,0,0,0,0,0,AV3,0,0,0,0~
)';
      PINUSE='GROUND';
      NO_LOAD_CHECK='Both';
      NO_IO_CHECK='Both';
      NO_ASSERT_CHECK='TRUE';
      NO_DIR_CHECK='TRUE';
      ALLOW_CONNECT='TRUE';
    'VSS'<705>:
      PIN_NUMBER='(0,0,0,0,0,0,0,0,0,0,0,0,0,0,0,0,0,0,0,0,0,0,0,0,0,AV7,0,0,0,0~
)';
      PINUSE='GROUND';
      NO_LOAD_CHECK='Both';
      NO_IO_CHECK='Both';
      NO_ASSERT_CHECK='TRUE';
      NO_DIR_CHECK='TRUE';
      ALLOW_CONNECT='TRUE';
    'VSS'<704>:
      PIN_NUMBER='(0,0,0,0,0,0,0,0,0,0,0,0,0,0,0,0,0,0,0,0,0,0,0,0,0,AV11,0,0,0,~
0)';
      PINUSE='GROUND';
      NO_LOAD_CHECK='Both';
      NO_IO_CHECK='Both';
      NO_ASSERT_CHECK='TRUE';
      NO_DIR_CHECK='TRUE';
      ALLOW_CONNECT='TRUE';
    'VSS'<703>:
      PIN_NUMBER='(0,0,0,0,0,0,0,0,0,0,0,0,0,0,0,0,0,0,0,0,0,0,0,0,0,AV13,0,0,0,~
0)';
      PINUSE='GROUND';
      NO_LOAD_CHECK='Both';
      NO_IO_CHECK='Both';
      NO_ASSERT_CHECK='TRUE';
      NO_DIR_CHECK='TRUE';
      ALLOW_CONNECT='TRUE';
    'VSS'<702>:
      PIN_NUMBER='(0,0,0,0,0,0,0,0,0,0,0,0,0,0,0,0,0,0,0,0,0,0,0,0,0,AV19,0,0,0,~
0)';
      PINUSE='GROUND';
      NO_LOAD_CHECK='Both';
      NO_IO_CHECK='Both';
      NO_ASSERT_CHECK='TRUE';
      NO_DIR_CHECK='TRUE';
      ALLOW_CONNECT='TRUE';
    'VSS'<701>:
      PIN_NUMBER='(0,0,0,0,0,0,0,0,0,0,0,0,0,0,0,0,0,0,0,0,0,0,0,0,0,AV23,0,0,0,~
0)';
      PINUSE='GROUND';
      NO_LOAD_CHECK='Both';
      NO_IO_CHECK='Both';
      NO_ASSERT_CHECK='TRUE';
      NO_DIR_CHECK='TRUE';
      ALLOW_CONNECT='TRUE';
    'VSS'<700>:
      PIN_NUMBER='(0,0,0,0,0,0,0,0,0,0,0,0,0,0,0,0,0,0,0,0,0,0,0,0,0,AV25,0,0,0,~
0)';
      PINUSE='GROUND';
      NO_LOAD_CHECK='Both';
      NO_IO_CHECK='Both';
      NO_ASSERT_CHECK='TRUE';
      NO_DIR_CHECK='TRUE';
      ALLOW_CONNECT='TRUE';
    'VSS'<699>:
      PIN_NUMBER='(0,0,0,0,0,0,0,0,0,0,0,0,0,0,0,0,0,0,0,0,0,0,0,0,0,AV63,0,0,0,~
0)';
      PINUSE='GROUND';
      NO_LOAD_CHECK='Both';
      NO_IO_CHECK='Both';
      NO_ASSERT_CHECK='TRUE';
      NO_DIR_CHECK='TRUE';
      ALLOW_CONNECT='TRUE';
    'VSS'<698>:
      PIN_NUMBER='(0,0,0,0,0,0,0,0,0,0,0,0,0,0,0,0,0,0,0,0,0,0,0,0,0,AV65,0,0,0,~
0)';
      PINUSE='GROUND';
      NO_LOAD_CHECK='Both';
      NO_IO_CHECK='Both';
      NO_ASSERT_CHECK='TRUE';
      NO_DIR_CHECK='TRUE';
      ALLOW_CONNECT='TRUE';
    'VSS'<697>:
      PIN_NUMBER='(0,0,0,0,0,0,0,0,0,0,0,0,0,0,0,0,0,0,0,0,0,0,0,0,0,AV67,0,0,0,~
0)';
      PINUSE='GROUND';
      NO_LOAD_CHECK='Both';
      NO_IO_CHECK='Both';
      NO_ASSERT_CHECK='TRUE';
      NO_DIR_CHECK='TRUE';
      ALLOW_CONNECT='TRUE';
    'VSS'<696>:
      PIN_NUMBER='(0,0,0,0,0,0,0,0,0,0,0,0,0,0,0,0,0,0,0,0,0,0,0,0,0,AV75,0,0,0,~
0)';
      PINUSE='GROUND';
      NO_LOAD_CHECK='Both';
      NO_IO_CHECK='Both';
      NO_ASSERT_CHECK='TRUE';
      NO_DIR_CHECK='TRUE';
      ALLOW_CONNECT='TRUE';
    'VSS'<695>:
      PIN_NUMBER='(0,0,0,0,0,0,0,0,0,0,0,0,0,0,0,0,0,0,0,0,0,0,0,0,0,AV83,0,0,0,~
0)';
      PINUSE='GROUND';
      NO_LOAD_CHECK='Both';
      NO_IO_CHECK='Both';
      NO_ASSERT_CHECK='TRUE';
      NO_DIR_CHECK='TRUE';
      ALLOW_CONNECT='TRUE';
    'VSS'<694>:
      PIN_NUMBER='(0,0,0,0,0,0,0,0,0,0,0,0,0,0,0,0,0,0,0,0,0,0,0,0,0,AW2,0,0,0,0~
)';
      PINUSE='GROUND';
      NO_LOAD_CHECK='Both';
      NO_IO_CHECK='Both';
      NO_ASSERT_CHECK='TRUE';
      NO_DIR_CHECK='TRUE';
      ALLOW_CONNECT='TRUE';
    'VSS'<693>:
      PIN_NUMBER='(0,0,0,0,0,0,0,0,0,0,0,0,0,0,0,0,0,0,0,0,0,0,0,0,0,AW10,0,0,0,~
0)';
      PINUSE='GROUND';
      NO_LOAD_CHECK='Both';
      NO_IO_CHECK='Both';
      NO_ASSERT_CHECK='TRUE';
      NO_DIR_CHECK='TRUE';
      ALLOW_CONNECT='TRUE';
    'VSS'<692>:
      PIN_NUMBER='(0,0,0,0,0,0,0,0,0,0,0,0,0,0,0,0,0,0,0,0,0,0,0,0,0,AW62,0,0,0,~
0)';
      PINUSE='GROUND';
      NO_LOAD_CHECK='Both';
      NO_IO_CHECK='Both';
      NO_ASSERT_CHECK='TRUE';
      NO_DIR_CHECK='TRUE';
      ALLOW_CONNECT='TRUE';
    'VSS'<691>:
      PIN_NUMBER='(0,0,0,0,0,0,0,0,0,0,0,0,0,0,0,0,0,0,0,0,0,0,0,0,0,AW66,0,0,0,~
0)';
      PINUSE='GROUND';
      NO_LOAD_CHECK='Both';
      NO_IO_CHECK='Both';
      NO_ASSERT_CHECK='TRUE';
      NO_DIR_CHECK='TRUE';
      ALLOW_CONNECT='TRUE';
    'VSS'<690>:
      PIN_NUMBER='(0,0,0,0,0,0,0,0,0,0,0,0,0,0,0,0,0,0,0,0,0,0,0,0,0,AW68,0,0,0,~
0)';
      PINUSE='GROUND';
      NO_LOAD_CHECK='Both';
      NO_IO_CHECK='Both';
      NO_ASSERT_CHECK='TRUE';
      NO_DIR_CHECK='TRUE';
      ALLOW_CONNECT='TRUE';
    'VSS'<689>:
      PIN_NUMBER='(0,0,0,0,0,0,0,0,0,0,0,0,0,0,0,0,0,0,0,0,0,0,0,0,0,AW70,0,0,0,~
0)';
      PINUSE='GROUND';
      NO_LOAD_CHECK='Both';
      NO_IO_CHECK='Both';
      NO_ASSERT_CHECK='TRUE';
      NO_DIR_CHECK='TRUE';
      ALLOW_CONNECT='TRUE';
    'VSS'<688>:
      PIN_NUMBER='(0,0,0,0,0,0,0,0,0,0,0,0,0,0,0,0,0,0,0,0,0,0,0,0,0,AW72,0,0,0,~
0)';
      PINUSE='GROUND';
      NO_LOAD_CHECK='Both';
      NO_IO_CHECK='Both';
      NO_ASSERT_CHECK='TRUE';
      NO_DIR_CHECK='TRUE';
      ALLOW_CONNECT='TRUE';
    'VSS'<687>:
      PIN_NUMBER='(0,0,0,0,0,0,0,0,0,0,0,0,0,0,0,0,0,0,0,0,0,0,0,0,0,AW74,0,0,0,~
0)';
      PINUSE='GROUND';
      NO_LOAD_CHECK='Both';
      NO_IO_CHECK='Both';
      NO_ASSERT_CHECK='TRUE';
      NO_DIR_CHECK='TRUE';
      ALLOW_CONNECT='TRUE';
    'VSS'<686>:
      PIN_NUMBER='(0,0,0,0,0,0,0,0,0,0,0,0,0,0,0,0,0,0,0,0,0,0,0,0,0,AW78,0,0,0,~
0)';
      PINUSE='GROUND';
      NO_LOAD_CHECK='Both';
      NO_IO_CHECK='Both';
      NO_ASSERT_CHECK='TRUE';
      NO_DIR_CHECK='TRUE';
      ALLOW_CONNECT='TRUE';
    'VSS'<685>:
      PIN_NUMBER='(0,0,0,0,0,0,0,0,0,0,0,0,0,0,0,0,0,0,0,0,0,0,0,0,0,AW82,0,0,0,~
0)';
      PINUSE='GROUND';
      NO_LOAD_CHECK='Both';
      NO_IO_CHECK='Both';
      NO_ASSERT_CHECK='TRUE';
      NO_DIR_CHECK='TRUE';
      ALLOW_CONNECT='TRUE';
    'VSS'<684>:
      PIN_NUMBER='(0,0,0,0,0,0,0,0,0,0,0,0,0,0,0,0,0,0,0,0,0,0,0,0,0,AW84,0,0,0,~
0)';
      PINUSE='GROUND';
      NO_LOAD_CHECK='Both';
      NO_IO_CHECK='Both';
      NO_ASSERT_CHECK='TRUE';
      NO_DIR_CHECK='TRUE';
      ALLOW_CONNECT='TRUE';
    'VSS'<683>:
      PIN_NUMBER='(0,0,0,0,0,0,0,0,0,0,0,0,0,0,0,0,0,0,0,0,0,0,0,0,0,AY5,0,0,0,0~
)';
      PINUSE='GROUND';
      NO_LOAD_CHECK='Both';
      NO_IO_CHECK='Both';
      NO_ASSERT_CHECK='TRUE';
      NO_DIR_CHECK='TRUE';
      ALLOW_CONNECT='TRUE';
    'VSS'<682>:
      PIN_NUMBER='(0,0,0,0,0,0,0,0,0,0,0,0,0,0,0,0,0,0,0,0,0,0,0,0,0,AY15,0,0,0,~
0)';
      PINUSE='GROUND';
      NO_LOAD_CHECK='Both';
      NO_IO_CHECK='Both';
      NO_ASSERT_CHECK='TRUE';
      NO_DIR_CHECK='TRUE';
      ALLOW_CONNECT='TRUE';
    'VSS'<681>:
      PIN_NUMBER='(0,0,0,0,0,0,0,0,0,0,0,0,0,0,0,0,0,0,0,0,0,0,0,0,0,AY17,0,0,0,~
0)';
      PINUSE='GROUND';
      NO_LOAD_CHECK='Both';
      NO_IO_CHECK='Both';
      NO_ASSERT_CHECK='TRUE';
      NO_DIR_CHECK='TRUE';
      ALLOW_CONNECT='TRUE';
    'VSS'<680>:
      PIN_NUMBER='(0,0,0,0,0,0,0,0,0,0,0,0,0,0,0,0,0,0,0,0,0,0,0,0,0,AY21,0,0,0,~
0)';
      PINUSE='GROUND';
      NO_LOAD_CHECK='Both';
      NO_IO_CHECK='Both';
      NO_ASSERT_CHECK='TRUE';
      NO_DIR_CHECK='TRUE';
      ALLOW_CONNECT='TRUE';
    'VSS'<679>:
      PIN_NUMBER='(0,0,0,0,0,0,0,0,0,0,0,0,0,0,0,0,0,0,0,0,0,0,0,0,0,AY23,0,0,0,~
0)';
      PINUSE='GROUND';
      NO_LOAD_CHECK='Both';
      NO_IO_CHECK='Both';
      NO_ASSERT_CHECK='TRUE';
      NO_DIR_CHECK='TRUE';
      ALLOW_CONNECT='TRUE';
    'VSS'<678>:
      PIN_NUMBER='(0,0,0,0,0,0,0,0,0,0,0,0,0,0,0,0,0,0,0,0,0,0,0,0,0,AY25,0,0,0,~
0)';
      PINUSE='GROUND';
      NO_LOAD_CHECK='Both';
      NO_IO_CHECK='Both';
      NO_ASSERT_CHECK='TRUE';
      NO_DIR_CHECK='TRUE';
      ALLOW_CONNECT='TRUE';
    'VSS'<677>:
      PIN_NUMBER='(0,0,0,0,0,0,0,0,0,0,0,0,0,0,0,0,0,0,0,0,0,0,0,0,0,AY63,0,0,0,~
0)';
      PINUSE='GROUND';
      NO_LOAD_CHECK='Both';
      NO_IO_CHECK='Both';
      NO_ASSERT_CHECK='TRUE';
      NO_DIR_CHECK='TRUE';
      ALLOW_CONNECT='TRUE';
    'VSS'<676>:
      PIN_NUMBER='(0,0,0,0,0,0,0,0,0,0,0,0,0,0,0,0,0,0,0,0,0,0,0,0,0,AY79,0,0,0,~
0)';
      PINUSE='GROUND';
      NO_LOAD_CHECK='Both';
      NO_IO_CHECK='Both';
      NO_ASSERT_CHECK='TRUE';
      NO_DIR_CHECK='TRUE';
      ALLOW_CONNECT='TRUE';
    'VSS'<675>:
      PIN_NUMBER='(0,0,0,0,0,0,0,0,0,0,0,0,0,0,0,0,0,0,0,0,0,0,0,0,0,AY81,0,0,0,~
0)';
      PINUSE='GROUND';
      NO_LOAD_CHECK='Both';
      NO_IO_CHECK='Both';
      NO_ASSERT_CHECK='TRUE';
      NO_DIR_CHECK='TRUE';
      ALLOW_CONNECT='TRUE';
    'VSS'<674>:
      PIN_NUMBER='(0,0,0,0,0,0,0,0,0,0,0,0,0,0,0,0,0,0,0,0,0,0,0,0,0,BA2,0,0,0,0~
)';
      PINUSE='GROUND';
      NO_LOAD_CHECK='Both';
      NO_IO_CHECK='Both';
      NO_ASSERT_CHECK='TRUE';
      NO_DIR_CHECK='TRUE';
      ALLOW_CONNECT='TRUE';
    'VSS'<673>:
      PIN_NUMBER='(0,0,0,0,0,0,0,0,0,0,0,0,0,0,0,0,0,0,0,0,0,0,0,0,0,BA6,0,0,0,0~
)';
      PINUSE='GROUND';
      NO_LOAD_CHECK='Both';
      NO_IO_CHECK='Both';
      NO_ASSERT_CHECK='TRUE';
      NO_DIR_CHECK='TRUE';
      ALLOW_CONNECT='TRUE';
    'VSS'<672>:
      PIN_NUMBER='(0,0,0,0,0,0,0,0,0,0,0,0,0,0,0,0,0,0,0,0,0,0,0,0,0,BA12,0,0,0,~
0)';
      PINUSE='GROUND';
      NO_LOAD_CHECK='Both';
      NO_IO_CHECK='Both';
      NO_ASSERT_CHECK='TRUE';
      NO_DIR_CHECK='TRUE';
      ALLOW_CONNECT='TRUE';
    'VSS'<671>:
      PIN_NUMBER='(0,0,0,0,0,0,0,0,0,0,0,0,0,0,0,0,0,0,0,0,0,0,0,0,0,BA62,0,0,0,~
0)';
      PINUSE='GROUND';
      NO_LOAD_CHECK='Both';
      NO_IO_CHECK='Both';
      NO_ASSERT_CHECK='TRUE';
      NO_DIR_CHECK='TRUE';
      ALLOW_CONNECT='TRUE';
    'VSS'<670>:
      PIN_NUMBER='(0,0,0,0,0,0,0,0,0,0,0,0,0,0,0,0,0,0,0,0,0,0,0,0,0,BA68,0,0,0,~
0)';
      PINUSE='GROUND';
      NO_LOAD_CHECK='Both';
      NO_IO_CHECK='Both';
      NO_ASSERT_CHECK='TRUE';
      NO_DIR_CHECK='TRUE';
      ALLOW_CONNECT='TRUE';
    'VSS'<669>:
      PIN_NUMBER='(0,0,0,0,0,0,0,0,0,0,0,0,0,0,0,0,0,0,0,0,0,0,0,0,0,BA74,0,0,0,~
0)';
      PINUSE='GROUND';
      NO_LOAD_CHECK='Both';
      NO_IO_CHECK='Both';
      NO_ASSERT_CHECK='TRUE';
      NO_DIR_CHECK='TRUE';
      ALLOW_CONNECT='TRUE';
    'VSS'<668>:
      PIN_NUMBER='(0,0,0,0,0,0,0,0,0,0,0,0,0,0,0,0,0,0,0,0,0,0,0,0,0,BA80,0,0,0,~
0)';
      PINUSE='GROUND';
      NO_LOAD_CHECK='Both';
      NO_IO_CHECK='Both';
      NO_ASSERT_CHECK='TRUE';
      NO_DIR_CHECK='TRUE';
      ALLOW_CONNECT='TRUE';
    'VSS'<667>:
      PIN_NUMBER='(0,0,0,0,0,0,0,0,0,0,0,0,0,0,0,0,0,0,0,0,0,0,0,0,0,BA84,0,0,0,~
0)';
      PINUSE='GROUND';
      NO_LOAD_CHECK='Both';
      NO_IO_CHECK='Both';
      NO_ASSERT_CHECK='TRUE';
      NO_DIR_CHECK='TRUE';
      ALLOW_CONNECT='TRUE';
    'VSS'<666>:
      PIN_NUMBER='(0,0,0,0,0,0,0,0,0,0,0,0,0,0,0,0,0,0,0,0,0,0,0,0,0,BB19,0,0,0,~
0)';
      PINUSE='GROUND';
      NO_LOAD_CHECK='Both';
      NO_IO_CHECK='Both';
      NO_ASSERT_CHECK='TRUE';
      NO_DIR_CHECK='TRUE';
      ALLOW_CONNECT='TRUE';
    'VSS'<665>:
      PIN_NUMBER='(0,0,0,0,0,0,0,0,0,0,0,0,0,0,0,0,0,0,0,0,0,0,0,0,0,BB23,0,0,0,~
0)';
      PINUSE='GROUND';
      NO_LOAD_CHECK='Both';
      NO_IO_CHECK='Both';
      NO_ASSERT_CHECK='TRUE';
      NO_DIR_CHECK='TRUE';
      ALLOW_CONNECT='TRUE';
    'VSS'<664>:
      PIN_NUMBER='(0,0,0,0,0,0,0,0,0,0,0,0,0,0,0,0,0,0,0,0,0,0,0,0,0,BB63,0,0,0,~
0)';
      PINUSE='GROUND';
      NO_LOAD_CHECK='Both';
      NO_IO_CHECK='Both';
      NO_ASSERT_CHECK='TRUE';
      NO_DIR_CHECK='TRUE';
      ALLOW_CONNECT='TRUE';
    'VSS'<663>:
      PIN_NUMBER='(0,0,0,0,0,0,0,0,0,0,0,0,0,0,0,0,0,0,0,0,0,0,0,0,0,BB69,0,0,0,~
0)';
      PINUSE='GROUND';
      NO_LOAD_CHECK='Both';
      NO_IO_CHECK='Both';
      NO_ASSERT_CHECK='TRUE';
      NO_DIR_CHECK='TRUE';
      ALLOW_CONNECT='TRUE';
    'VSS'<662>:
      PIN_NUMBER='(0,0,0,0,0,0,0,0,0,0,0,0,0,0,0,0,0,0,0,0,0,0,0,0,0,BB73,0,0,0,~
0)';
      PINUSE='GROUND';
      NO_LOAD_CHECK='Both';
      NO_IO_CHECK='Both';
      NO_ASSERT_CHECK='TRUE';
      NO_DIR_CHECK='TRUE';
      ALLOW_CONNECT='TRUE';
    'VSS'<661>:
      PIN_NUMBER='(0,0,0,0,0,0,0,0,0,0,0,0,0,0,0,0,0,0,0,0,0,0,0,0,0,BB75,0,0,0,~
0)';
      PINUSE='GROUND';
      NO_LOAD_CHECK='Both';
      NO_IO_CHECK='Both';
      NO_ASSERT_CHECK='TRUE';
      NO_DIR_CHECK='TRUE';
      ALLOW_CONNECT='TRUE';
    'VSS'<660>:
      PIN_NUMBER='(0,0,0,0,0,0,0,0,0,0,0,0,0,0,0,0,0,0,0,0,0,0,0,0,0,BB77,0,0,0,~
0)';
      PINUSE='GROUND';
      NO_LOAD_CHECK='Both';
      NO_IO_CHECK='Both';
      NO_ASSERT_CHECK='TRUE';
      NO_DIR_CHECK='TRUE';
      ALLOW_CONNECT='TRUE';
    'VSS'<659>:
      PIN_NUMBER='(0,0,0,0,0,0,0,0,0,0,0,0,0,0,0,0,0,0,0,0,0,0,0,0,0,BB79,0,0,0,~
0)';
      PINUSE='GROUND';
      NO_LOAD_CHECK='Both';
      NO_IO_CHECK='Both';
      NO_ASSERT_CHECK='TRUE';
      NO_DIR_CHECK='TRUE';
      ALLOW_CONNECT='TRUE';
    'VSS'<658>:
      PIN_NUMBER='(0,0,0,0,0,0,0,0,0,0,0,0,0,0,0,0,0,0,0,0,0,0,0,0,0,BB81,0,0,0,~
0)';
      PINUSE='GROUND';
      NO_LOAD_CHECK='Both';
      NO_IO_CHECK='Both';
      NO_ASSERT_CHECK='TRUE';
      NO_DIR_CHECK='TRUE';
      ALLOW_CONNECT='TRUE';
    'VSS'<657>:
      PIN_NUMBER='(0,0,0,0,0,0,0,0,0,0,0,0,0,0,0,0,0,0,0,0,0,0,0,0,0,BB83,0,0,0,~
0)';
      PINUSE='GROUND';
      NO_LOAD_CHECK='Both';
      NO_IO_CHECK='Both';
      NO_ASSERT_CHECK='TRUE';
      NO_DIR_CHECK='TRUE';
      ALLOW_CONNECT='TRUE';
    'VSS'<656>:
      PIN_NUMBER='(0,0,0,0,0,0,0,0,0,0,0,0,0,0,0,0,0,0,0,0,0,0,0,0,0,BC4,0,0,0,0~
)';
      PINUSE='GROUND';
      NO_LOAD_CHECK='Both';
      NO_IO_CHECK='Both';
      NO_ASSERT_CHECK='TRUE';
      NO_DIR_CHECK='TRUE';
      ALLOW_CONNECT='TRUE';
    'VSS'<655>:
      PIN_NUMBER='(0,0,0,0,0,0,0,0,0,0,0,0,0,0,0,0,0,0,0,0,0,0,0,0,0,BC8,0,0,0,0~
)';
      PINUSE='GROUND';
      NO_LOAD_CHECK='Both';
      NO_IO_CHECK='Both';
      NO_ASSERT_CHECK='TRUE';
      NO_DIR_CHECK='TRUE';
      ALLOW_CONNECT='TRUE';
    'VSS'<654>:
      PIN_NUMBER='(0,0,0,0,0,0,0,0,0,0,0,0,0,0,0,0,0,0,0,0,0,0,0,0,0,BC12,0,0,0,~
0)';
      PINUSE='GROUND';
      NO_LOAD_CHECK='Both';
      NO_IO_CHECK='Both';
      NO_ASSERT_CHECK='TRUE';
      NO_DIR_CHECK='TRUE';
      ALLOW_CONNECT='TRUE';
    'VSS'<653>:
      PIN_NUMBER='(0,0,0,0,0,0,0,0,0,0,0,0,0,0,0,0,0,0,0,0,0,0,0,0,0,BC16,0,0,0,~
0)';
      PINUSE='GROUND';
      NO_LOAD_CHECK='Both';
      NO_IO_CHECK='Both';
      NO_ASSERT_CHECK='TRUE';
      NO_DIR_CHECK='TRUE';
      ALLOW_CONNECT='TRUE';
    'VSS'<652>:
      PIN_NUMBER='(0,0,0,0,0,0,0,0,0,0,0,0,0,0,0,0,0,0,0,0,0,0,0,0,0,BC70,0,0,0,~
0)';
      PINUSE='GROUND';
      NO_LOAD_CHECK='Both';
      NO_IO_CHECK='Both';
      NO_ASSERT_CHECK='TRUE';
      NO_DIR_CHECK='TRUE';
      ALLOW_CONNECT='TRUE';
    'VSS'<651>:
      PIN_NUMBER='(0,0,0,0,0,0,0,0,0,0,0,0,0,0,0,0,0,0,0,0,0,0,0,0,0,BC72,0,0,0,~
0)';
      PINUSE='GROUND';
      NO_LOAD_CHECK='Both';
      NO_IO_CHECK='Both';
      NO_ASSERT_CHECK='TRUE';
      NO_DIR_CHECK='TRUE';
      ALLOW_CONNECT='TRUE';
    'VSS'<650>:
      PIN_NUMBER='(0,0,0,0,0,0,0,0,0,0,0,0,0,0,0,0,0,0,0,0,0,0,0,0,0,BC74,0,0,0,~
0)';
      PINUSE='GROUND';
      NO_LOAD_CHECK='Both';
      NO_IO_CHECK='Both';
      NO_ASSERT_CHECK='TRUE';
      NO_DIR_CHECK='TRUE';
      ALLOW_CONNECT='TRUE';
    'VSS'<649>:
      PIN_NUMBER='(0,0,0,0,0,0,0,0,0,0,0,0,0,0,0,0,0,0,0,0,0,0,0,0,0,BC76,0,0,0,~
0)';
      PINUSE='GROUND';
      NO_LOAD_CHECK='Both';
      NO_IO_CHECK='Both';
      NO_ASSERT_CHECK='TRUE';
      NO_DIR_CHECK='TRUE';
      ALLOW_CONNECT='TRUE';
    'VSS'<648>:
      PIN_NUMBER='(0,0,0,0,0,0,0,0,0,0,0,0,0,0,0,0,0,0,0,0,0,0,0,0,0,BC78,0,0,0,~
0)';
      PINUSE='GROUND';
      NO_LOAD_CHECK='Both';
      NO_IO_CHECK='Both';
      NO_ASSERT_CHECK='TRUE';
      NO_DIR_CHECK='TRUE';
      ALLOW_CONNECT='TRUE';
    'VSS'<647>:
      PIN_NUMBER='(0,0,0,0,0,0,0,0,0,0,0,0,0,0,0,0,0,0,0,0,0,0,0,0,0,BC80,0,0,0,~
0)';
      PINUSE='GROUND';
      NO_LOAD_CHECK='Both';
      NO_IO_CHECK='Both';
      NO_ASSERT_CHECK='TRUE';
      NO_DIR_CHECK='TRUE';
      ALLOW_CONNECT='TRUE';
    'VSS'<646>:
      PIN_NUMBER='(0,0,0,0,0,0,0,0,0,0,0,0,0,0,0,0,0,0,0,0,0,0,0,0,0,BC82,0,0,0,~
0)';
      PINUSE='GROUND';
      NO_LOAD_CHECK='Both';
      NO_IO_CHECK='Both';
      NO_ASSERT_CHECK='TRUE';
      NO_DIR_CHECK='TRUE';
      ALLOW_CONNECT='TRUE';
    'VSS'<645>:
      PIN_NUMBER='(0,0,0,0,0,0,0,0,0,0,0,0,0,0,0,0,0,0,0,0,0,0,0,0,0,BD5,0,0,0,0~
)';
      PINUSE='GROUND';
      NO_LOAD_CHECK='Both';
      NO_IO_CHECK='Both';
      NO_ASSERT_CHECK='TRUE';
      NO_DIR_CHECK='TRUE';
      ALLOW_CONNECT='TRUE';
    'VSS'<644>:
      PIN_NUMBER='(0,0,0,0,0,0,0,0,0,0,0,0,0,0,0,0,0,0,0,0,0,0,0,0,0,BD11,0,0,0,~
0)';
      PINUSE='GROUND';
      NO_LOAD_CHECK='Both';
      NO_IO_CHECK='Both';
      NO_ASSERT_CHECK='TRUE';
      NO_DIR_CHECK='TRUE';
      ALLOW_CONNECT='TRUE';
    'VSS'<643>:
      PIN_NUMBER='(0,0,0,0,0,0,0,0,0,0,0,0,0,0,0,0,0,0,0,0,0,0,0,0,0,BD15,0,0,0,~
0)';
      PINUSE='GROUND';
      NO_LOAD_CHECK='Both';
      NO_IO_CHECK='Both';
      NO_ASSERT_CHECK='TRUE';
      NO_DIR_CHECK='TRUE';
      ALLOW_CONNECT='TRUE';
    'VSS'<642>:
      PIN_NUMBER='(0,0,0,0,0,0,0,0,0,0,0,0,0,0,0,0,0,0,0,0,0,0,0,0,0,BD21,0,0,0,~
0)';
      PINUSE='GROUND';
      NO_LOAD_CHECK='Both';
      NO_IO_CHECK='Both';
      NO_ASSERT_CHECK='TRUE';
      NO_DIR_CHECK='TRUE';
      ALLOW_CONNECT='TRUE';
    'VSS'<641>:
      PIN_NUMBER='(0,0,0,0,0,0,0,0,0,0,0,0,0,0,0,0,0,0,0,0,0,0,0,0,0,BD27,0,0,0,~
0)';
      PINUSE='GROUND';
      NO_LOAD_CHECK='Both';
      NO_IO_CHECK='Both';
      NO_ASSERT_CHECK='TRUE';
      NO_DIR_CHECK='TRUE';
      ALLOW_CONNECT='TRUE';
    'VSS'<640>:
      PIN_NUMBER='(0,0,0,0,0,0,0,0,0,0,0,0,0,0,0,0,0,0,0,0,0,0,0,0,0,BD63,0,0,0,~
0)';
      PINUSE='GROUND';
      NO_LOAD_CHECK='Both';
      NO_IO_CHECK='Both';
      NO_ASSERT_CHECK='TRUE';
      NO_DIR_CHECK='TRUE';
      ALLOW_CONNECT='TRUE';
    'VSS'<639>:
      PIN_NUMBER='(0,0,0,0,0,0,0,0,0,0,0,0,0,0,0,0,0,0,0,0,0,0,0,0,0,BD71,0,0,0,~
0)';
      PINUSE='GROUND';
      NO_LOAD_CHECK='Both';
      NO_IO_CHECK='Both';
      NO_ASSERT_CHECK='TRUE';
      NO_DIR_CHECK='TRUE';
      ALLOW_CONNECT='TRUE';
    'VSS'<638>:
      PIN_NUMBER='(0,0,0,0,0,0,0,0,0,0,0,0,0,0,0,0,0,0,0,0,0,0,0,0,0,BE4,0,0,0,0~
)';
      PINUSE='GROUND';
      NO_LOAD_CHECK='Both';
      NO_IO_CHECK='Both';
      NO_ASSERT_CHECK='TRUE';
      NO_DIR_CHECK='TRUE';
      ALLOW_CONNECT='TRUE';
    'VSS'<637>:
      PIN_NUMBER='(0,0,0,0,0,0,0,0,0,0,0,0,0,0,0,0,0,0,0,0,0,0,0,0,0,BE6,0,0,0,0~
)';
      PINUSE='GROUND';
      NO_LOAD_CHECK='Both';
      NO_IO_CHECK='Both';
      NO_ASSERT_CHECK='TRUE';
      NO_DIR_CHECK='TRUE';
      ALLOW_CONNECT='TRUE';
    'VSS'<636>:
      PIN_NUMBER='(0,0,0,0,0,0,0,0,0,0,0,0,0,0,0,0,0,0,0,0,0,0,0,0,0,BE8,0,0,0,0~
)';
      PINUSE='GROUND';
      NO_LOAD_CHECK='Both';
      NO_IO_CHECK='Both';
      NO_ASSERT_CHECK='TRUE';
      NO_DIR_CHECK='TRUE';
      ALLOW_CONNECT='TRUE';
    'VSS'<635>:
      PIN_NUMBER='(0,0,0,0,0,0,0,0,0,0,0,0,0,0,0,0,0,0,0,0,0,0,0,0,0,BE10,0,0,0,~
0)';
      PINUSE='GROUND';
      NO_LOAD_CHECK='Both';
      NO_IO_CHECK='Both';
      NO_ASSERT_CHECK='TRUE';
      NO_DIR_CHECK='TRUE';
      ALLOW_CONNECT='TRUE';
    'VSS'<634>:
      PIN_NUMBER='(0,0,0,0,0,0,0,0,0,0,0,0,0,0,0,0,0,0,0,0,0,0,0,0,0,BE26,0,0,0,~
0)';
      PINUSE='GROUND';
      NO_LOAD_CHECK='Both';
      NO_IO_CHECK='Both';
      NO_ASSERT_CHECK='TRUE';
      NO_DIR_CHECK='TRUE';
      ALLOW_CONNECT='TRUE';
    'VSS'<633>:
      PIN_NUMBER='(0,0,0,0,0,0,0,0,0,0,0,0,0,0,0,0,0,0,0,0,0,0,0,0,0,BE64,0,0,0,~
0)';
      PINUSE='GROUND';
      NO_LOAD_CHECK='Both';
      NO_IO_CHECK='Both';
      NO_ASSERT_CHECK='TRUE';
      NO_DIR_CHECK='TRUE';
      ALLOW_CONNECT='TRUE';
    'VSS'<632>:
      PIN_NUMBER='(0,0,0,0,0,0,0,0,0,0,0,0,0,0,0,0,0,0,0,0,0,0,0,0,0,BE66,0,0,0,~
0)';
      PINUSE='GROUND';
      NO_LOAD_CHECK='Both';
      NO_IO_CHECK='Both';
      NO_ASSERT_CHECK='TRUE';
      NO_DIR_CHECK='TRUE';
      ALLOW_CONNECT='TRUE';
    'VSS'<631>:
      PIN_NUMBER='(0,0,0,0,0,0,0,0,0,0,0,0,0,0,0,0,0,0,0,0,0,0,0,0,0,BE68,0,0,0,~
0)';
      PINUSE='GROUND';
      NO_LOAD_CHECK='Both';
      NO_IO_CHECK='Both';
      NO_ASSERT_CHECK='TRUE';
      NO_DIR_CHECK='TRUE';
      ALLOW_CONNECT='TRUE';
    'VSS'<630>:
      PIN_NUMBER='(0,0,0,0,0,0,0,0,0,0,0,0,0,0,0,0,0,0,0,0,0,0,0,0,0,BE70,0,0,0,~
0)';
      PINUSE='GROUND';
      NO_LOAD_CHECK='Both';
      NO_IO_CHECK='Both';
      NO_ASSERT_CHECK='TRUE';
      NO_DIR_CHECK='TRUE';
      ALLOW_CONNECT='TRUE';
    'VSS'<629>:
      PIN_NUMBER='(0,0,0,0,0,0,0,0,0,0,0,0,0,0,0,0,0,0,0,0,0,0,0,0,0,BF9,0,0,0,0~
)';
      PINUSE='GROUND';
      NO_LOAD_CHECK='Both';
      NO_IO_CHECK='Both';
      NO_ASSERT_CHECK='TRUE';
      NO_DIR_CHECK='TRUE';
      ALLOW_CONNECT='TRUE';
    'VSS'<628>:
      PIN_NUMBER='(0,0,0,0,0,0,0,0,0,0,0,0,0,0,0,0,0,0,0,0,0,0,0,0,0,BF15,0,0,0,~
0)';
      PINUSE='GROUND';
      NO_LOAD_CHECK='Both';
      NO_IO_CHECK='Both';
      NO_ASSERT_CHECK='TRUE';
      NO_DIR_CHECK='TRUE';
      ALLOW_CONNECT='TRUE';
    'VSS'<627>:
      PIN_NUMBER='(0,0,0,0,0,0,0,0,0,0,0,0,0,0,0,0,0,0,0,0,0,0,0,0,0,BF17,0,0,0,~
0)';
      PINUSE='GROUND';
      NO_LOAD_CHECK='Both';
      NO_IO_CHECK='Both';
      NO_ASSERT_CHECK='TRUE';
      NO_DIR_CHECK='TRUE';
      ALLOW_CONNECT='TRUE';
    'VSS'<626>:
      PIN_NUMBER='(0,0,0,0,0,0,0,0,0,0,0,0,0,0,0,0,0,0,0,0,0,0,0,0,0,BF19,0,0,0,~
0)';
      PINUSE='GROUND';
      NO_LOAD_CHECK='Both';
      NO_IO_CHECK='Both';
      NO_ASSERT_CHECK='TRUE';
      NO_DIR_CHECK='TRUE';
      ALLOW_CONNECT='TRUE';
    'VSS'<625>:
      PIN_NUMBER='(0,0,0,0,0,0,0,0,0,0,0,0,0,0,0,0,0,0,0,0,0,0,0,0,0,BF25,0,0,0,~
0)';
      PINUSE='GROUND';
      NO_LOAD_CHECK='Both';
      NO_IO_CHECK='Both';
      NO_ASSERT_CHECK='TRUE';
      NO_DIR_CHECK='TRUE';
      ALLOW_CONNECT='TRUE';
    'VSS'<624>:
      PIN_NUMBER='(0,0,0,0,0,0,0,0,0,0,0,0,0,0,0,0,0,0,0,0,0,0,0,0,0,BF63,0,0,0,~
0)';
      PINUSE='GROUND';
      NO_LOAD_CHECK='Both';
      NO_IO_CHECK='Both';
      NO_ASSERT_CHECK='TRUE';
      NO_DIR_CHECK='TRUE';
      ALLOW_CONNECT='TRUE';
    'VSS'<623>:
      PIN_NUMBER='(0,0,0,0,0,0,0,0,0,0,0,0,0,0,0,0,0,0,0,0,0,0,0,0,0,BF65,0,0,0,~
0)';
      PINUSE='GROUND';
      NO_LOAD_CHECK='Both';
      NO_IO_CHECK='Both';
      NO_ASSERT_CHECK='TRUE';
      NO_DIR_CHECK='TRUE';
      ALLOW_CONNECT='TRUE';
    'VSS'<622>:
      PIN_NUMBER='(0,0,0,0,0,0,0,0,0,0,0,0,0,0,0,0,0,0,0,0,0,0,0,0,0,BF67,0,0,0,~
0)';
      PINUSE='GROUND';
      NO_LOAD_CHECK='Both';
      NO_IO_CHECK='Both';
      NO_ASSERT_CHECK='TRUE';
      NO_DIR_CHECK='TRUE';
      ALLOW_CONNECT='TRUE';
    'VSS'<621>:
      PIN_NUMBER='(0,0,0,0,0,0,0,0,0,0,0,0,0,0,0,0,0,0,0,0,0,0,0,0,0,BF69,0,0,0,~
0)';
      PINUSE='GROUND';
      NO_LOAD_CHECK='Both';
      NO_IO_CHECK='Both';
      NO_ASSERT_CHECK='TRUE';
      NO_DIR_CHECK='TRUE';
      ALLOW_CONNECT='TRUE';
    'VSS'<620>:
      PIN_NUMBER='(0,0,0,0,0,0,0,0,0,0,0,0,0,0,0,0,0,0,0,0,0,0,0,0,0,BF71,0,0,0,~
0)';
      PINUSE='GROUND';
      NO_LOAD_CHECK='Both';
      NO_IO_CHECK='Both';
      NO_ASSERT_CHECK='TRUE';
      NO_DIR_CHECK='TRUE';
      ALLOW_CONNECT='TRUE';
    'VSS'<619>:
      PIN_NUMBER='(0,0,0,0,0,0,0,0,0,0,0,0,0,0,0,0,0,0,0,0,0,0,0,0,0,BG6,0,0,0,0~
)';
      PINUSE='GROUND';
      NO_LOAD_CHECK='Both';
      NO_IO_CHECK='Both';
      NO_ASSERT_CHECK='TRUE';
      NO_DIR_CHECK='TRUE';
      ALLOW_CONNECT='TRUE';
    'VSS'<618>:
      PIN_NUMBER='(0,0,0,0,0,0,0,0,0,0,0,0,0,0,0,0,0,0,0,0,0,0,0,0,0,BG8,0,0,0,0~
)';
      PINUSE='GROUND';
      NO_LOAD_CHECK='Both';
      NO_IO_CHECK='Both';
      NO_ASSERT_CHECK='TRUE';
      NO_DIR_CHECK='TRUE';
      ALLOW_CONNECT='TRUE';
    'VSS'<617>:
      PIN_NUMBER='(0,0,0,0,0,0,0,0,0,0,0,0,0,0,0,0,0,0,0,0,0,0,0,0,0,BG10,0,0,0,~
0)';
      PINUSE='GROUND';
      NO_LOAD_CHECK='Both';
      NO_IO_CHECK='Both';
      NO_ASSERT_CHECK='TRUE';
      NO_DIR_CHECK='TRUE';
      ALLOW_CONNECT='TRUE';
    'VSS'<616>:
      PIN_NUMBER='(0,0,0,0,0,0,0,0,0,0,0,0,0,0,0,0,0,0,0,0,0,0,0,0,0,BG22,0,0,0,~
0)';
      PINUSE='GROUND';
      NO_LOAD_CHECK='Both';
      NO_IO_CHECK='Both';
      NO_ASSERT_CHECK='TRUE';
      NO_DIR_CHECK='TRUE';
      ALLOW_CONNECT='TRUE';
    'VSS'<615>:
      PIN_NUMBER='(0,0,0,0,0,0,0,0,0,0,0,0,0,0,0,0,0,0,0,0,0,0,0,0,0,BG24,0,0,0,~
0)';
      PINUSE='GROUND';
      NO_LOAD_CHECK='Both';
      NO_IO_CHECK='Both';
      NO_ASSERT_CHECK='TRUE';
      NO_DIR_CHECK='TRUE';
      ALLOW_CONNECT='TRUE';
    'VSS'<614>:
      PIN_NUMBER='(0,0,0,0,0,0,0,0,0,0,0,0,0,0,0,0,0,0,0,0,0,0,0,0,0,BG72,0,0,0,~
0)';
      PINUSE='GROUND';
      NO_LOAD_CHECK='Both';
      NO_IO_CHECK='Both';
      NO_ASSERT_CHECK='TRUE';
      NO_DIR_CHECK='TRUE';
      ALLOW_CONNECT='TRUE';
    'VSS'<613>:
      PIN_NUMBER='(0,0,0,0,0,0,0,0,0,0,0,0,0,0,0,0,0,0,0,0,0,0,0,0,0,0,BG74,0,0,~
0)';
      PINUSE='GROUND';
      NO_LOAD_CHECK='Both';
      NO_IO_CHECK='Both';
      NO_ASSERT_CHECK='TRUE';
      NO_DIR_CHECK='TRUE';
      ALLOW_CONNECT='TRUE';
    'VSS'<612>:
      PIN_NUMBER='(0,0,0,0,0,0,0,0,0,0,0,0,0,0,0,0,0,0,0,0,0,0,0,0,0,0,BG76,0,0,~
0)';
      PINUSE='GROUND';
      NO_LOAD_CHECK='Both';
      NO_IO_CHECK='Both';
      NO_ASSERT_CHECK='TRUE';
      NO_DIR_CHECK='TRUE';
      ALLOW_CONNECT='TRUE';
    'VSS'<611>:
      PIN_NUMBER='(0,0,0,0,0,0,0,0,0,0,0,0,0,0,0,0,0,0,0,0,0,0,0,0,0,0,BG78,0,0,~
0)';
      PINUSE='GROUND';
      NO_LOAD_CHECK='Both';
      NO_IO_CHECK='Both';
      NO_ASSERT_CHECK='TRUE';
      NO_DIR_CHECK='TRUE';
      ALLOW_CONNECT='TRUE';
    'VSS'<610>:
      PIN_NUMBER='(0,0,0,0,0,0,0,0,0,0,0,0,0,0,0,0,0,0,0,0,0,0,0,0,0,0,BG80,0,0,~
0)';
      PINUSE='GROUND';
      NO_LOAD_CHECK='Both';
      NO_IO_CHECK='Both';
      NO_ASSERT_CHECK='TRUE';
      NO_DIR_CHECK='TRUE';
      ALLOW_CONNECT='TRUE';
    'VSS'<609>:
      PIN_NUMBER='(0,0,0,0,0,0,0,0,0,0,0,0,0,0,0,0,0,0,0,0,0,0,0,0,0,0,BG82,0,0,~
0)';
      PINUSE='GROUND';
      NO_LOAD_CHECK='Both';
      NO_IO_CHECK='Both';
      NO_ASSERT_CHECK='TRUE';
      NO_DIR_CHECK='TRUE';
      ALLOW_CONNECT='TRUE';
    'VSS'<608>:
      PIN_NUMBER='(0,0,0,0,0,0,0,0,0,0,0,0,0,0,0,0,0,0,0,0,0,0,0,0,0,0,BH7,0,0,0~
)';
      PINUSE='GROUND';
      NO_LOAD_CHECK='Both';
      NO_IO_CHECK='Both';
      NO_ASSERT_CHECK='TRUE';
      NO_DIR_CHECK='TRUE';
      ALLOW_CONNECT='TRUE';
    'VSS'<607>:
      PIN_NUMBER='(0,0,0,0,0,0,0,0,0,0,0,0,0,0,0,0,0,0,0,0,0,0,0,0,0,0,BH9,0,0,0~
)';
      PINUSE='GROUND';
      NO_LOAD_CHECK='Both';
      NO_IO_CHECK='Both';
      NO_ASSERT_CHECK='TRUE';
      NO_DIR_CHECK='TRUE';
      ALLOW_CONNECT='TRUE';
    'VSS'<606>:
      PIN_NUMBER='(0,0,0,0,0,0,0,0,0,0,0,0,0,0,0,0,0,0,0,0,0,0,0,0,0,0,BH11,0,0,~
0)';
      PINUSE='GROUND';
      NO_LOAD_CHECK='Both';
      NO_IO_CHECK='Both';
      NO_ASSERT_CHECK='TRUE';
      NO_DIR_CHECK='TRUE';
      ALLOW_CONNECT='TRUE';
    'VSS'<605>:
      PIN_NUMBER='(0,0,0,0,0,0,0,0,0,0,0,0,0,0,0,0,0,0,0,0,0,0,0,0,0,0,BH15,0,0,~
0)';
      PINUSE='GROUND';
      NO_LOAD_CHECK='Both';
      NO_IO_CHECK='Both';
      NO_ASSERT_CHECK='TRUE';
      NO_DIR_CHECK='TRUE';
      ALLOW_CONNECT='TRUE';
    'VSS'<604>:
      PIN_NUMBER='(0,0,0,0,0,0,0,0,0,0,0,0,0,0,0,0,0,0,0,0,0,0,0,0,0,0,BH21,0,0,~
0)';
      PINUSE='GROUND';
      NO_LOAD_CHECK='Both';
      NO_IO_CHECK='Both';
      NO_ASSERT_CHECK='TRUE';
      NO_DIR_CHECK='TRUE';
      ALLOW_CONNECT='TRUE';
    'VSS'<603>:
      PIN_NUMBER='(0,0,0,0,0,0,0,0,0,0,0,0,0,0,0,0,0,0,0,0,0,0,0,0,0,0,BJ4,0,0,0~
)';
      PINUSE='GROUND';
      NO_LOAD_CHECK='Both';
      NO_IO_CHECK='Both';
      NO_ASSERT_CHECK='TRUE';
      NO_DIR_CHECK='TRUE';
      ALLOW_CONNECT='TRUE';
    'VSS'<602>:
      PIN_NUMBER='(0,0,0,0,0,0,0,0,0,0,0,0,0,0,0,0,0,0,0,0,0,0,0,0,0,0,BJ6,0,0,0~
)';
      PINUSE='GROUND';
      NO_LOAD_CHECK='Both';
      NO_IO_CHECK='Both';
      NO_ASSERT_CHECK='TRUE';
      NO_DIR_CHECK='TRUE';
      ALLOW_CONNECT='TRUE';
    'VSS'<601>:
      PIN_NUMBER='(0,0,0,0,0,0,0,0,0,0,0,0,0,0,0,0,0,0,0,0,0,0,0,0,0,0,BK3,0,0,0~
)';
      PINUSE='GROUND';
      NO_LOAD_CHECK='Both';
      NO_IO_CHECK='Both';
      NO_ASSERT_CHECK='TRUE';
      NO_DIR_CHECK='TRUE';
      ALLOW_CONNECT='TRUE';
    'VSS'<600>:
      PIN_NUMBER='(0,0,0,0,0,0,0,0,0,0,0,0,0,0,0,0,0,0,0,0,0,0,0,0,0,0,BK7,0,0,0~
)';
      PINUSE='GROUND';
      NO_LOAD_CHECK='Both';
      NO_IO_CHECK='Both';
      NO_ASSERT_CHECK='TRUE';
      NO_DIR_CHECK='TRUE';
      ALLOW_CONNECT='TRUE';
    'VSS'<599>:
      PIN_NUMBER='(0,0,0,0,0,0,0,0,0,0,0,0,0,0,0,0,0,0,0,0,0,0,0,0,0,0,BK11,0,0,~
0)';
      PINUSE='GROUND';
      NO_LOAD_CHECK='Both';
      NO_IO_CHECK='Both';
      NO_ASSERT_CHECK='TRUE';
      NO_DIR_CHECK='TRUE';
      ALLOW_CONNECT='TRUE';
    'VSS'<598>:
      PIN_NUMBER='(0,0,0,0,0,0,0,0,0,0,0,0,0,0,0,0,0,0,0,0,0,0,0,0,0,0,BK19,0,0,~
0)';
      PINUSE='GROUND';
      NO_LOAD_CHECK='Both';
      NO_IO_CHECK='Both';
      NO_ASSERT_CHECK='TRUE';
      NO_DIR_CHECK='TRUE';
      ALLOW_CONNECT='TRUE';
    'VSS'<597>:
      PIN_NUMBER='(0,0,0,0,0,0,0,0,0,0,0,0,0,0,0,0,0,0,0,0,0,0,0,0,0,0,BL6,0,0,0~
)';
      PINUSE='GROUND';
      NO_LOAD_CHECK='Both';
      NO_IO_CHECK='Both';
      NO_ASSERT_CHECK='TRUE';
      NO_DIR_CHECK='TRUE';
      ALLOW_CONNECT='TRUE';
    'VSS'<596>:
      PIN_NUMBER='(0,0,0,0,0,0,0,0,0,0,0,0,0,0,0,0,0,0,0,0,0,0,0,0,0,0,BL10,0,0,~
0)';
      PINUSE='GROUND';
      NO_LOAD_CHECK='Both';
      NO_IO_CHECK='Both';
      NO_ASSERT_CHECK='TRUE';
      NO_DIR_CHECK='TRUE';
      ALLOW_CONNECT='TRUE';
    'VSS'<595>:
      PIN_NUMBER='(0,0,0,0,0,0,0,0,0,0,0,0,0,0,0,0,0,0,0,0,0,0,0,0,0,0,BL12,0,0,~
0)';
      PINUSE='GROUND';
      NO_LOAD_CHECK='Both';
      NO_IO_CHECK='Both';
      NO_ASSERT_CHECK='TRUE';
      NO_DIR_CHECK='TRUE';
      ALLOW_CONNECT='TRUE';
    'VSS'<594>:
      PIN_NUMBER='(0,0,0,0,0,0,0,0,0,0,0,0,0,0,0,0,0,0,0,0,0,0,0,0,0,0,P61,0,0,0~
)';
      PINUSE='GROUND';
      NO_LOAD_CHECK='Both';
      NO_IO_CHECK='Both';
      NO_ASSERT_CHECK='TRUE';
      NO_DIR_CHECK='TRUE';
      ALLOW_CONNECT='TRUE';
    'VSS'<593>:
      PIN_NUMBER='(0,0,0,0,0,0,0,0,0,0,0,0,0,0,0,0,0,0,0,0,0,0,0,0,0,0,BL22,0,0,~
0)';
      PINUSE='GROUND';
      NO_LOAD_CHECK='Both';
      NO_IO_CHECK='Both';
      NO_ASSERT_CHECK='TRUE';
      NO_DIR_CHECK='TRUE';
      ALLOW_CONNECT='TRUE';
    'VSS'<592>:
      PIN_NUMBER='(0,0,0,0,0,0,0,0,0,0,0,0,0,0,0,0,0,0,0,0,0,0,0,0,0,0,BL24,0,0,~
0)';
      PINUSE='GROUND';
      NO_LOAD_CHECK='Both';
      NO_IO_CHECK='Both';
      NO_ASSERT_CHECK='TRUE';
      NO_DIR_CHECK='TRUE';
      ALLOW_CONNECT='TRUE';
    'VSS'<591>:
      PIN_NUMBER='(0,0,0,0,0,0,0,0,0,0,0,0,0,0,0,0,0,0,0,0,0,0,0,0,0,0,BL64,0,0,~
0)';
      PINUSE='GROUND';
      NO_LOAD_CHECK='Both';
      NO_IO_CHECK='Both';
      NO_ASSERT_CHECK='TRUE';
      NO_DIR_CHECK='TRUE';
      ALLOW_CONNECT='TRUE';
    'VSS'<590>:
      PIN_NUMBER='(0,0,0,0,0,0,0,0,0,0,0,0,0,0,0,0,0,0,0,0,0,0,0,0,0,0,BL66,0,0,~
0)';
      PINUSE='GROUND';
      NO_LOAD_CHECK='Both';
      NO_IO_CHECK='Both';
      NO_ASSERT_CHECK='TRUE';
      NO_DIR_CHECK='TRUE';
      ALLOW_CONNECT='TRUE';
    'VSS'<589>:
      PIN_NUMBER='(0,0,0,0,0,0,0,0,0,0,0,0,0,0,0,0,0,0,0,0,0,0,0,0,0,0,BL68,0,0,~
0)';
      PINUSE='GROUND';
      NO_LOAD_CHECK='Both';
      NO_IO_CHECK='Both';
      NO_ASSERT_CHECK='TRUE';
      NO_DIR_CHECK='TRUE';
      ALLOW_CONNECT='TRUE';
    'VSS'<588>:
      PIN_NUMBER='(0,0,0,0,0,0,0,0,0,0,0,0,0,0,0,0,0,0,0,0,0,0,0,0,0,0,BL70,0,0,~
0)';
      PINUSE='GROUND';
      NO_LOAD_CHECK='Both';
      NO_IO_CHECK='Both';
      NO_ASSERT_CHECK='TRUE';
      NO_DIR_CHECK='TRUE';
      ALLOW_CONNECT='TRUE';
    'VSS'<587>:
      PIN_NUMBER='(0,0,0,0,0,0,0,0,0,0,0,0,0,0,0,0,0,0,0,0,0,0,0,0,0,0,BL72,0,0,~
0)';
      PINUSE='GROUND';
      NO_LOAD_CHECK='Both';
      NO_IO_CHECK='Both';
      NO_ASSERT_CHECK='TRUE';
      NO_DIR_CHECK='TRUE';
      ALLOW_CONNECT='TRUE';
    'VSS'<586>:
      PIN_NUMBER='(0,0,0,0,0,0,0,0,0,0,0,0,0,0,0,0,0,0,0,0,0,0,0,0,0,0,BL74,0,0,~
0)';
      PINUSE='GROUND';
      NO_LOAD_CHECK='Both';
      NO_IO_CHECK='Both';
      NO_ASSERT_CHECK='TRUE';
      NO_DIR_CHECK='TRUE';
      ALLOW_CONNECT='TRUE';
    'VSS'<585>:
      PIN_NUMBER='(0,0,0,0,0,0,0,0,0,0,0,0,0,0,0,0,0,0,0,0,0,0,0,0,0,0,BL76,0,0,~
0)';
      PINUSE='GROUND';
      NO_LOAD_CHECK='Both';
      NO_IO_CHECK='Both';
      NO_ASSERT_CHECK='TRUE';
      NO_DIR_CHECK='TRUE';
      ALLOW_CONNECT='TRUE';
    'VSS'<584>:
      PIN_NUMBER='(0,0,0,0,0,0,0,0,0,0,0,0,0,0,0,0,0,0,0,0,0,0,0,0,0,0,BL78,0,0,~
0)';
      PINUSE='GROUND';
      NO_LOAD_CHECK='Both';
      NO_IO_CHECK='Both';
      NO_ASSERT_CHECK='TRUE';
      NO_DIR_CHECK='TRUE';
      ALLOW_CONNECT='TRUE';
    'VSS'<583>:
      PIN_NUMBER='(0,0,0,0,0,0,0,0,0,0,0,0,0,0,0,0,0,0,0,0,0,0,0,0,0,0,BL80,0,0,~
0)';
      PINUSE='GROUND';
      NO_LOAD_CHECK='Both';
      NO_IO_CHECK='Both';
      NO_ASSERT_CHECK='TRUE';
      NO_DIR_CHECK='TRUE';
      ALLOW_CONNECT='TRUE';
    'VSS'<582>:
      PIN_NUMBER='(0,0,0,0,0,0,0,0,0,0,0,0,0,0,0,0,0,0,0,0,0,0,0,0,0,0,BL82,0,0,~
0)';
      PINUSE='GROUND';
      NO_LOAD_CHECK='Both';
      NO_IO_CHECK='Both';
      NO_ASSERT_CHECK='TRUE';
      NO_DIR_CHECK='TRUE';
      ALLOW_CONNECT='TRUE';
    'VSS'<581>:
      PIN_NUMBER='(0,0,0,0,0,0,0,0,0,0,0,0,0,0,0,0,0,0,0,0,0,0,0,0,0,0,BM9,0,0,0~
)';
      PINUSE='GROUND';
      NO_LOAD_CHECK='Both';
      NO_IO_CHECK='Both';
      NO_ASSERT_CHECK='TRUE';
      NO_DIR_CHECK='TRUE';
      ALLOW_CONNECT='TRUE';
    'VSS'<580>:
      PIN_NUMBER='(0,0,0,0,0,0,0,0,0,0,0,0,0,0,0,0,0,0,0,0,0,0,0,0,0,0,BM13,0,0,~
0)';
      PINUSE='GROUND';
      NO_LOAD_CHECK='Both';
      NO_IO_CHECK='Both';
      NO_ASSERT_CHECK='TRUE';
      NO_DIR_CHECK='TRUE';
      ALLOW_CONNECT='TRUE';
    'VSS'<579>:
      PIN_NUMBER='(0,0,0,0,0,0,0,0,0,0,0,0,0,0,0,0,0,0,0,0,0,0,0,0,0,0,BM15,0,0,~
0)';
      PINUSE='GROUND';
      NO_LOAD_CHECK='Both';
      NO_IO_CHECK='Both';
      NO_ASSERT_CHECK='TRUE';
      NO_DIR_CHECK='TRUE';
      ALLOW_CONNECT='TRUE';
    'VSS'<578>:
      PIN_NUMBER='(0,0,0,0,0,0,0,0,0,0,0,0,0,0,0,0,0,0,0,0,0,0,0,0,0,0,P59,0,0,0~
)';
      PINUSE='GROUND';
      NO_LOAD_CHECK='Both';
      NO_IO_CHECK='Both';
      NO_ASSERT_CHECK='TRUE';
      NO_DIR_CHECK='TRUE';
      ALLOW_CONNECT='TRUE';
    'VSS'<577>:
      PIN_NUMBER='(0,0,0,0,0,0,0,0,0,0,0,0,0,0,0,0,0,0,0,0,0,0,0,0,0,0,BM25,0,0,~
0)';
      PINUSE='GROUND';
      NO_LOAD_CHECK='Both';
      NO_IO_CHECK='Both';
      NO_ASSERT_CHECK='TRUE';
      NO_DIR_CHECK='TRUE';
      ALLOW_CONNECT='TRUE';
    'VSS'<576>:
      PIN_NUMBER='(0,0,0,0,0,0,0,0,0,0,0,0,0,0,0,0,0,0,0,0,0,0,0,0,0,0,BN6,0,0,0~
)';
      PINUSE='GROUND';
      NO_LOAD_CHECK='Both';
      NO_IO_CHECK='Both';
      NO_ASSERT_CHECK='TRUE';
      NO_DIR_CHECK='TRUE';
      ALLOW_CONNECT='TRUE';
    'VSS'<575>:
      PIN_NUMBER='(0,0,0,0,0,0,0,0,0,0,0,0,0,0,0,0,0,0,0,0,0,0,0,0,0,0,BN10,0,0,~
0)';
      PINUSE='GROUND';
      NO_LOAD_CHECK='Both';
      NO_IO_CHECK='Both';
      NO_ASSERT_CHECK='TRUE';
      NO_DIR_CHECK='TRUE';
      ALLOW_CONNECT='TRUE';
    'VSS'<574>:
      PIN_NUMBER='(0,0,0,0,0,0,0,0,0,0,0,0,0,0,0,0,0,0,0,0,0,0,0,0,0,0,BN20,0,0,~
0)';
      PINUSE='GROUND';
      NO_LOAD_CHECK='Both';
      NO_IO_CHECK='Both';
      NO_ASSERT_CHECK='TRUE';
      NO_DIR_CHECK='TRUE';
      ALLOW_CONNECT='TRUE';
    'VSS'<573>:
      PIN_NUMBER='(0,0,0,0,0,0,0,0,0,0,0,0,0,0,0,0,0,0,0,0,0,0,0,0,0,0,BN26,0,0,~
0)';
      PINUSE='GROUND';
      NO_LOAD_CHECK='Both';
      NO_IO_CHECK='Both';
      NO_ASSERT_CHECK='TRUE';
      NO_DIR_CHECK='TRUE';
      ALLOW_CONNECT='TRUE';
    'VSS'<572>:
      PIN_NUMBER='(0,0,0,0,0,0,0,0,0,0,0,0,0,0,0,0,0,0,0,0,0,0,0,0,0,0,BP3,0,0,0~
)';
      PINUSE='GROUND';
      NO_LOAD_CHECK='Both';
      NO_IO_CHECK='Both';
      NO_ASSERT_CHECK='TRUE';
      NO_DIR_CHECK='TRUE';
      ALLOW_CONNECT='TRUE';
    'VSS'<571>:
      PIN_NUMBER='(0,0,0,0,0,0,0,0,0,0,0,0,0,0,0,0,0,0,0,0,0,0,0,0,0,0,BP27,0,0,~
0)';
      PINUSE='GROUND';
      NO_LOAD_CHECK='Both';
      NO_IO_CHECK='Both';
      NO_ASSERT_CHECK='TRUE';
      NO_DIR_CHECK='TRUE';
      ALLOW_CONNECT='TRUE';
    'VSS'<570>:
      PIN_NUMBER='(0,0,0,0,0,0,0,0,0,0,0,0,0,0,0,0,0,0,0,0,0,0,0,0,0,0,BR6,0,0,0~
)';
      PINUSE='GROUND';
      NO_LOAD_CHECK='Both';
      NO_IO_CHECK='Both';
      NO_ASSERT_CHECK='TRUE';
      NO_DIR_CHECK='TRUE';
      ALLOW_CONNECT='TRUE';
    'VSS'<569>:
      PIN_NUMBER='(0,0,0,0,0,0,0,0,0,0,0,0,0,0,0,0,0,0,0,0,0,0,0,0,0,0,BR10,0,0,~
0)';
      PINUSE='GROUND';
      NO_LOAD_CHECK='Both';
      NO_IO_CHECK='Both';
      NO_ASSERT_CHECK='TRUE';
      NO_DIR_CHECK='TRUE';
      ALLOW_CONNECT='TRUE';
    'VSS'<568>:
      PIN_NUMBER='(0,0,0,0,0,0,0,0,0,0,0,0,0,0,0,0,0,0,0,0,0,0,0,0,0,0,BR16,0,0,~
0)';
      PINUSE='GROUND';
      NO_LOAD_CHECK='Both';
      NO_IO_CHECK='Both';
      NO_ASSERT_CHECK='TRUE';
      NO_DIR_CHECK='TRUE';
      ALLOW_CONNECT='TRUE';
    'VSS'<567>:
      PIN_NUMBER='(0,0,0,0,0,0,0,0,0,0,0,0,0,0,0,0,0,0,0,0,0,0,0,0,0,0,P57,0,0,0~
)';
      PINUSE='GROUND';
      NO_LOAD_CHECK='Both';
      NO_IO_CHECK='Both';
      NO_ASSERT_CHECK='TRUE';
      NO_DIR_CHECK='TRUE';
      ALLOW_CONNECT='TRUE';
    'VSS'<566>:
      PIN_NUMBER='(0,0,0,0,0,0,0,0,0,0,0,0,0,0,0,0,0,0,0,0,0,0,0,0,0,0,BR64,0,0,~
0)';
      PINUSE='GROUND';
      NO_LOAD_CHECK='Both';
      NO_IO_CHECK='Both';
      NO_ASSERT_CHECK='TRUE';
      NO_DIR_CHECK='TRUE';
      ALLOW_CONNECT='TRUE';
    'VSS'<565>:
      PIN_NUMBER='(0,0,0,0,0,0,0,0,0,0,0,0,0,0,0,0,0,0,0,0,0,0,0,0,0,0,BR66,0,0,~
0)';
      PINUSE='GROUND';
      NO_LOAD_CHECK='Both';
      NO_IO_CHECK='Both';
      NO_ASSERT_CHECK='TRUE';
      NO_DIR_CHECK='TRUE';
      ALLOW_CONNECT='TRUE';
    'VSS'<564>:
      PIN_NUMBER='(0,0,0,0,0,0,0,0,0,0,0,0,0,0,0,0,0,0,0,0,0,0,0,0,0,0,BR68,0,0,~
0)';
      PINUSE='GROUND';
      NO_LOAD_CHECK='Both';
      NO_IO_CHECK='Both';
      NO_ASSERT_CHECK='TRUE';
      NO_DIR_CHECK='TRUE';
      ALLOW_CONNECT='TRUE';
    'VSS'<563>:
      PIN_NUMBER='(0,0,0,0,0,0,0,0,0,0,0,0,0,0,0,0,0,0,0,0,0,0,0,0,0,0,BR70,0,0,~
0)';
      PINUSE='GROUND';
      NO_LOAD_CHECK='Both';
      NO_IO_CHECK='Both';
      NO_ASSERT_CHECK='TRUE';
      NO_DIR_CHECK='TRUE';
      ALLOW_CONNECT='TRUE';
    'VSS'<562>:
      PIN_NUMBER='(0,0,0,0,0,0,0,0,0,0,0,0,0,0,0,0,0,0,0,0,0,0,0,0,0,0,BR72,0,0,~
0)';
      PINUSE='GROUND';
      NO_LOAD_CHECK='Both';
      NO_IO_CHECK='Both';
      NO_ASSERT_CHECK='TRUE';
      NO_DIR_CHECK='TRUE';
      ALLOW_CONNECT='TRUE';
    'VSS'<561>:
      PIN_NUMBER='(0,0,0,0,0,0,0,0,0,0,0,0,0,0,0,0,0,0,0,0,0,0,0,0,0,0,BR74,0,0,~
0)';
      PINUSE='GROUND';
      NO_LOAD_CHECK='Both';
      NO_IO_CHECK='Both';
      NO_ASSERT_CHECK='TRUE';
      NO_DIR_CHECK='TRUE';
      ALLOW_CONNECT='TRUE';
    'VSS'<560>:
      PIN_NUMBER='(0,0,0,0,0,0,0,0,0,0,0,0,0,0,0,0,0,0,0,0,0,0,0,0,0,0,BR76,0,0,~
0)';
      PINUSE='GROUND';
      NO_LOAD_CHECK='Both';
      NO_IO_CHECK='Both';
      NO_ASSERT_CHECK='TRUE';
      NO_DIR_CHECK='TRUE';
      ALLOW_CONNECT='TRUE';
    'VSS'<559>:
      PIN_NUMBER='(0,0,0,0,0,0,0,0,0,0,0,0,0,0,0,0,0,0,0,0,0,0,0,0,0,0,BR78,0,0,~
0)';
      PINUSE='GROUND';
      NO_LOAD_CHECK='Both';
      NO_IO_CHECK='Both';
      NO_ASSERT_CHECK='TRUE';
      NO_DIR_CHECK='TRUE';
      ALLOW_CONNECT='TRUE';
    'VSS'<558>:
      PIN_NUMBER='(0,0,0,0,0,0,0,0,0,0,0,0,0,0,0,0,0,0,0,0,0,0,0,0,0,0,BR80,0,0,~
0)';
      PINUSE='GROUND';
      NO_LOAD_CHECK='Both';
      NO_IO_CHECK='Both';
      NO_ASSERT_CHECK='TRUE';
      NO_DIR_CHECK='TRUE';
      ALLOW_CONNECT='TRUE';
    'VSS'<557>:
      PIN_NUMBER='(0,0,0,0,0,0,0,0,0,0,0,0,0,0,0,0,0,0,0,0,0,0,0,0,0,0,BR82,0,0,~
0)';
      PINUSE='GROUND';
      NO_LOAD_CHECK='Both';
      NO_IO_CHECK='Both';
      NO_ASSERT_CHECK='TRUE';
      NO_DIR_CHECK='TRUE';
      ALLOW_CONNECT='TRUE';
    'VSS'<556>:
      PIN_NUMBER='(0,0,0,0,0,0,0,0,0,0,0,0,0,0,0,0,0,0,0,0,0,0,0,0,0,0,BT3,0,0,0~
)';
      PINUSE='GROUND';
      NO_LOAD_CHECK='Both';
      NO_IO_CHECK='Both';
      NO_ASSERT_CHECK='TRUE';
      NO_DIR_CHECK='TRUE';
      ALLOW_CONNECT='TRUE';
    'VSS'<555>:
      PIN_NUMBER='(0,0,0,0,0,0,0,0,0,0,0,0,0,0,0,0,0,0,0,0,0,0,0,0,0,0,BT5,0,0,0~
)';
      PINUSE='GROUND';
      NO_LOAD_CHECK='Both';
      NO_IO_CHECK='Both';
      NO_ASSERT_CHECK='TRUE';
      NO_DIR_CHECK='TRUE';
      ALLOW_CONNECT='TRUE';
    'VSS'<554>:
      PIN_NUMBER='(0,0,0,0,0,0,0,0,0,0,0,0,0,0,0,0,0,0,0,0,0,0,0,0,0,0,BT21,0,0,~
0)';
      PINUSE='GROUND';
      NO_LOAD_CHECK='Both';
      NO_IO_CHECK='Both';
      NO_ASSERT_CHECK='TRUE';
      NO_DIR_CHECK='TRUE';
      ALLOW_CONNECT='TRUE';
    'VSS'<553>:
      PIN_NUMBER='(0,0,0,0,0,0,0,0,0,0,0,0,0,0,0,0,0,0,0,0,0,0,0,0,0,0,BT23,0,0,~
0)';
      PINUSE='GROUND';
      NO_LOAD_CHECK='Both';
      NO_IO_CHECK='Both';
      NO_ASSERT_CHECK='TRUE';
      NO_DIR_CHECK='TRUE';
      ALLOW_CONNECT='TRUE';
    'VSS'<552>:
      PIN_NUMBER='(0,0,0,0,0,0,0,0,0,0,0,0,0,0,0,0,0,0,0,0,0,0,0,0,0,0,BT25,0,0,~
0)';
      PINUSE='GROUND';
      NO_LOAD_CHECK='Both';
      NO_IO_CHECK='Both';
      NO_ASSERT_CHECK='TRUE';
      NO_DIR_CHECK='TRUE';
      ALLOW_CONNECT='TRUE';
    'VSS'<551>:
      PIN_NUMBER='(0,0,0,0,0,0,0,0,0,0,0,0,0,0,0,0,0,0,0,0,0,0,0,0,0,0,BU8,0,0,0~
)';
      PINUSE='GROUND';
      NO_LOAD_CHECK='Both';
      NO_IO_CHECK='Both';
      NO_ASSERT_CHECK='TRUE';
      NO_DIR_CHECK='TRUE';
      ALLOW_CONNECT='TRUE';
    'VSS'<550>:
      PIN_NUMBER='(0,0,0,0,0,0,0,0,0,0,0,0,0,0,0,0,0,0,0,0,0,0,0,0,0,0,BV5,0,0,0~
)';
      PINUSE='GROUND';
      NO_LOAD_CHECK='Both';
      NO_IO_CHECK='Both';
      NO_ASSERT_CHECK='TRUE';
      NO_DIR_CHECK='TRUE';
      ALLOW_CONNECT='TRUE';
    'VSS'<549>:
      PIN_NUMBER='(0,0,0,0,0,0,0,0,0,0,0,0,0,0,0,0,0,0,0,0,0,0,0,0,0,0,BU10,0,0,~
0)';
      PINUSE='GROUND';
      NO_LOAD_CHECK='Both';
      NO_IO_CHECK='Both';
      NO_ASSERT_CHECK='TRUE';
      NO_DIR_CHECK='TRUE';
      ALLOW_CONNECT='TRUE';
    'VSS'<548>:
      PIN_NUMBER='(0,0,0,0,0,0,0,0,0,0,0,0,0,0,0,0,0,0,0,0,0,0,0,0,0,0,BV17,0,0,~
0)';
      PINUSE='GROUND';
      NO_LOAD_CHECK='Both';
      NO_IO_CHECK='Both';
      NO_ASSERT_CHECK='TRUE';
      NO_DIR_CHECK='TRUE';
      ALLOW_CONNECT='TRUE';
    'VSS'<547>:
      PIN_NUMBER='(0,0,0,0,0,0,0,0,0,0,0,0,0,0,0,0,0,0,0,0,0,0,0,0,0,0,BV25,0,0,~
0)';
      PINUSE='GROUND';
      NO_LOAD_CHECK='Both';
      NO_IO_CHECK='Both';
      NO_ASSERT_CHECK='TRUE';
      NO_DIR_CHECK='TRUE';
      ALLOW_CONNECT='TRUE';
    'VSS'<546>:
      PIN_NUMBER='(0,0,0,0,0,0,0,0,0,0,0,0,0,0,0,0,0,0,0,0,0,0,0,0,0,0,BW6,0,0,0~
)';
      PINUSE='GROUND';
      NO_LOAD_CHECK='Both';
      NO_IO_CHECK='Both';
      NO_ASSERT_CHECK='TRUE';
      NO_DIR_CHECK='TRUE';
      ALLOW_CONNECT='TRUE';
    'VSS'<545>:
      PIN_NUMBER='(0,0,0,0,0,0,0,0,0,0,0,0,0,0,0,0,0,0,0,0,0,0,0,0,0,0,P55,0,0,0~
)';
      PINUSE='GROUND';
      NO_LOAD_CHECK='Both';
      NO_IO_CHECK='Both';
      NO_ASSERT_CHECK='TRUE';
      NO_DIR_CHECK='TRUE';
      ALLOW_CONNECT='TRUE';
    'VSS'<544>:
      PIN_NUMBER='(0,0,0,0,0,0,0,0,0,0,0,0,0,0,0,0,0,0,0,0,0,0,0,0,0,0,BW12,0,0,~
0)';
      PINUSE='GROUND';
      NO_LOAD_CHECK='Both';
      NO_IO_CHECK='Both';
      NO_ASSERT_CHECK='TRUE';
      NO_DIR_CHECK='TRUE';
      ALLOW_CONNECT='TRUE';
    'VSS'<543>:
      PIN_NUMBER='(0,0,0,0,0,0,0,0,0,0,0,0,0,0,0,0,0,0,0,0,0,0,0,0,0,0,BW14,0,0,~
0)';
      PINUSE='GROUND';
      NO_LOAD_CHECK='Both';
      NO_IO_CHECK='Both';
      NO_ASSERT_CHECK='TRUE';
      NO_DIR_CHECK='TRUE';
      ALLOW_CONNECT='TRUE';
    'VSS'<542>:
      PIN_NUMBER='(0,0,0,0,0,0,0,0,0,0,0,0,0,0,0,0,0,0,0,0,0,0,0,0,0,0,BW16,0,0,~
0)';
      PINUSE='GROUND';
      NO_LOAD_CHECK='Both';
      NO_IO_CHECK='Both';
      NO_ASSERT_CHECK='TRUE';
      NO_DIR_CHECK='TRUE';
      ALLOW_CONNECT='TRUE';
    'VSS'<541>:
      PIN_NUMBER='(0,0,0,0,0,0,0,0,0,0,0,0,0,0,0,0,0,0,0,0,0,0,0,0,0,0,BW18,0,0,~
0)';
      PINUSE='GROUND';
      NO_LOAD_CHECK='Both';
      NO_IO_CHECK='Both';
      NO_ASSERT_CHECK='TRUE';
      NO_DIR_CHECK='TRUE';
      ALLOW_CONNECT='TRUE';
    'VSS'<540>:
      PIN_NUMBER='(0,0,0,0,0,0,0,0,0,0,0,0,0,0,0,0,0,0,0,0,0,0,0,0,0,0,BW26,0,0,~
0)';
      PINUSE='GROUND';
      NO_LOAD_CHECK='Both';
      NO_IO_CHECK='Both';
      NO_ASSERT_CHECK='TRUE';
      NO_DIR_CHECK='TRUE';
      ALLOW_CONNECT='TRUE';
    'VSS'<539>:
      PIN_NUMBER='(0,0,0,0,0,0,0,0,0,0,0,0,0,0,0,0,0,0,0,0,0,0,0,0,0,0,BW72,0,0,~
0)';
      PINUSE='GROUND';
      NO_LOAD_CHECK='Both';
      NO_IO_CHECK='Both';
      NO_ASSERT_CHECK='TRUE';
      NO_DIR_CHECK='TRUE';
      ALLOW_CONNECT='TRUE';
    'VSS'<538>:
      PIN_NUMBER='(0,0,0,0,0,0,0,0,0,0,0,0,0,0,0,0,0,0,0,0,0,0,0,0,0,0,BW74,0,0,~
0)';
      PINUSE='GROUND';
      NO_LOAD_CHECK='Both';
      NO_IO_CHECK='Both';
      NO_ASSERT_CHECK='TRUE';
      NO_DIR_CHECK='TRUE';
      ALLOW_CONNECT='TRUE';
    'VSS'<537>:
      PIN_NUMBER='(0,0,0,0,0,0,0,0,0,0,0,0,0,0,0,0,0,0,0,0,0,0,0,0,0,0,BW76,0,0,~
0)';
      PINUSE='GROUND';
      NO_LOAD_CHECK='Both';
      NO_IO_CHECK='Both';
      NO_ASSERT_CHECK='TRUE';
      NO_DIR_CHECK='TRUE';
      ALLOW_CONNECT='TRUE';
    'VSS'<536>:
      PIN_NUMBER='(0,0,0,0,0,0,0,0,0,0,0,0,0,0,0,0,0,0,0,0,0,0,0,0,0,0,BW78,0,0,~
0)';
      PINUSE='GROUND';
      NO_LOAD_CHECK='Both';
      NO_IO_CHECK='Both';
      NO_ASSERT_CHECK='TRUE';
      NO_DIR_CHECK='TRUE';
      ALLOW_CONNECT='TRUE';
    'VSS'<535>:
      PIN_NUMBER='(0,0,0,0,0,0,0,0,0,0,0,0,0,0,0,0,0,0,0,0,0,0,0,0,0,0,BW80,0,0,~
0)';
      PINUSE='GROUND';
      NO_LOAD_CHECK='Both';
      NO_IO_CHECK='Both';
      NO_ASSERT_CHECK='TRUE';
      NO_DIR_CHECK='TRUE';
      ALLOW_CONNECT='TRUE';
    'VSS'<534>:
      PIN_NUMBER='(0,0,0,0,0,0,0,0,0,0,0,0,0,0,0,0,0,0,0,0,0,0,0,0,0,0,BW82,0,0,~
0)';
      PINUSE='GROUND';
      NO_LOAD_CHECK='Both';
      NO_IO_CHECK='Both';
      NO_ASSERT_CHECK='TRUE';
      NO_DIR_CHECK='TRUE';
      ALLOW_CONNECT='TRUE';
    'VSS'<533>:
      PIN_NUMBER='(0,0,0,0,0,0,0,0,0,0,0,0,0,0,0,0,0,0,0,0,0,0,0,0,0,0,BY11,0,0,~
0)';
      PINUSE='GROUND';
      NO_LOAD_CHECK='Both';
      NO_IO_CHECK='Both';
      NO_ASSERT_CHECK='TRUE';
      NO_DIR_CHECK='TRUE';
      ALLOW_CONNECT='TRUE';
    'VSS'<532>:
      PIN_NUMBER='(0,0,0,0,0,0,0,0,0,0,0,0,0,0,0,0,0,0,0,0,0,0,0,0,0,0,BY13,0,0,~
0)';
      PINUSE='GROUND';
      NO_LOAD_CHECK='Both';
      NO_IO_CHECK='Both';
      NO_ASSERT_CHECK='TRUE';
      NO_DIR_CHECK='TRUE';
      ALLOW_CONNECT='TRUE';
    'VSS'<531>:
      PIN_NUMBER='(0,0,0,0,0,0,0,0,0,0,0,0,0,0,0,0,0,0,0,0,0,0,0,0,0,0,BY23,0,0,~
0)';
      PINUSE='GROUND';
      NO_LOAD_CHECK='Both';
      NO_IO_CHECK='Both';
      NO_ASSERT_CHECK='TRUE';
      NO_DIR_CHECK='TRUE';
      ALLOW_CONNECT='TRUE';
    'VSS'<530>:
      PIN_NUMBER='(0,0,0,0,0,0,0,0,0,0,0,0,0,0,0,0,0,0,0,0,0,0,0,0,0,0,BY63,0,0,~
0)';
      PINUSE='GROUND';
      NO_LOAD_CHECK='Both';
      NO_IO_CHECK='Both';
      NO_ASSERT_CHECK='TRUE';
      NO_DIR_CHECK='TRUE';
      ALLOW_CONNECT='TRUE';
    'VSS'<529>:
      PIN_NUMBER='(0,0,0,0,0,0,0,0,0,0,0,0,0,0,0,0,0,0,0,0,0,0,0,0,0,0,BY65,0,0,~
0)';
      PINUSE='GROUND';
      NO_LOAD_CHECK='Both';
      NO_IO_CHECK='Both';
      NO_ASSERT_CHECK='TRUE';
      NO_DIR_CHECK='TRUE';
      ALLOW_CONNECT='TRUE';
    'VSS'<528>:
      PIN_NUMBER='(0,0,0,0,0,0,0,0,0,0,0,0,0,0,0,0,0,0,0,0,0,0,0,0,0,0,BY67,0,0,~
0)';
      PINUSE='GROUND';
      NO_LOAD_CHECK='Both';
      NO_IO_CHECK='Both';
      NO_ASSERT_CHECK='TRUE';
      NO_DIR_CHECK='TRUE';
      ALLOW_CONNECT='TRUE';
    'VSS'<527>:
      PIN_NUMBER='(0,0,0,0,0,0,0,0,0,0,0,0,0,0,0,0,0,0,0,0,0,0,0,0,0,0,BY69,0,0,~
0)';
      PINUSE='GROUND';
      NO_LOAD_CHECK='Both';
      NO_IO_CHECK='Both';
      NO_ASSERT_CHECK='TRUE';
      NO_DIR_CHECK='TRUE';
      ALLOW_CONNECT='TRUE';
    'VSS'<526>:
      PIN_NUMBER='(0,0,0,0,0,0,0,0,0,0,0,0,0,0,0,0,0,0,0,0,0,0,0,0,0,0,BY71,0,0,~
0)';
      PINUSE='GROUND';
      NO_LOAD_CHECK='Both';
      NO_IO_CHECK='Both';
      NO_ASSERT_CHECK='TRUE';
      NO_DIR_CHECK='TRUE';
      ALLOW_CONNECT='TRUE';
    'VSS'<525>:
      PIN_NUMBER='(0,0,0,0,0,0,0,0,0,0,0,0,0,0,0,0,0,0,0,0,0,0,0,0,0,0,CA2,0,0,0~
)';
      PINUSE='GROUND';
      NO_LOAD_CHECK='Both';
      NO_IO_CHECK='Both';
      NO_ASSERT_CHECK='TRUE';
      NO_DIR_CHECK='TRUE';
      ALLOW_CONNECT='TRUE';
    'VSS'<524>:
      PIN_NUMBER='(0,0,0,0,0,0,0,0,0,0,0,0,0,0,0,0,0,0,0,0,0,0,0,0,0,0,CA6,0,0,0~
)';
      PINUSE='GROUND';
      NO_LOAD_CHECK='Both';
      NO_IO_CHECK='Both';
      NO_ASSERT_CHECK='TRUE';
      NO_DIR_CHECK='TRUE';
      ALLOW_CONNECT='TRUE';
    'VSS'<523>:
      PIN_NUMBER='(0,0,0,0,0,0,0,0,0,0,0,0,0,0,0,0,0,0,0,0,0,0,0,0,0,0,CA8,0,0,0~
)';
      PINUSE='GROUND';
      NO_LOAD_CHECK='Both';
      NO_IO_CHECK='Both';
      NO_ASSERT_CHECK='TRUE';
      NO_DIR_CHECK='TRUE';
      ALLOW_CONNECT='TRUE';
    'VSS'<522>:
      PIN_NUMBER='(0,0,0,0,0,0,0,0,0,0,0,0,0,0,0,0,0,0,0,0,0,0,0,0,0,0,CA10,0,0,~
0)';
      PINUSE='GROUND';
      NO_LOAD_CHECK='Both';
      NO_IO_CHECK='Both';
      NO_ASSERT_CHECK='TRUE';
      NO_DIR_CHECK='TRUE';
      ALLOW_CONNECT='TRUE';
    'VSS'<521>:
      PIN_NUMBER='(0,0,0,0,0,0,0,0,0,0,0,0,0,0,0,0,0,0,0,0,0,0,0,0,0,0,CA14,0,0,~
0)';
      PINUSE='GROUND';
      NO_LOAD_CHECK='Both';
      NO_IO_CHECK='Both';
      NO_ASSERT_CHECK='TRUE';
      NO_DIR_CHECK='TRUE';
      ALLOW_CONNECT='TRUE';
    'VSS'<520>:
      PIN_NUMBER='(0,0,0,0,0,0,0,0,0,0,0,0,0,0,0,0,0,0,0,0,0,0,0,0,0,0,CA18,0,0,~
0)';
      PINUSE='GROUND';
      NO_LOAD_CHECK='Both';
      NO_IO_CHECK='Both';
      NO_ASSERT_CHECK='TRUE';
      NO_DIR_CHECK='TRUE';
      ALLOW_CONNECT='TRUE';
    'VSS'<519>:
      PIN_NUMBER='(0,0,0,0,0,0,0,0,0,0,0,0,0,0,0,0,0,0,0,0,0,0,0,0,0,0,CA26,0,0,~
0)';
      PINUSE='GROUND';
      NO_LOAD_CHECK='Both';
      NO_IO_CHECK='Both';
      NO_ASSERT_CHECK='TRUE';
      NO_DIR_CHECK='TRUE';
      ALLOW_CONNECT='TRUE';
    'VSS'<518>:
      PIN_NUMBER='(0,0,0,0,0,0,0,0,0,0,0,0,0,0,0,0,0,0,0,0,0,0,0,0,0,0,CA64,0,0,~
0)';
      PINUSE='GROUND';
      NO_LOAD_CHECK='Both';
      NO_IO_CHECK='Both';
      NO_ASSERT_CHECK='TRUE';
      NO_DIR_CHECK='TRUE';
      ALLOW_CONNECT='TRUE';
    'VSS'<517>:
      PIN_NUMBER='(0,0,0,0,0,0,0,0,0,0,0,0,0,0,0,0,0,0,0,0,0,0,0,0,0,0,CA66,0,0,~
0)';
      PINUSE='GROUND';
      NO_LOAD_CHECK='Both';
      NO_IO_CHECK='Both';
      NO_ASSERT_CHECK='TRUE';
      NO_DIR_CHECK='TRUE';
      ALLOW_CONNECT='TRUE';
    'VSS'<516>:
      PIN_NUMBER='(0,0,0,0,0,0,0,0,0,0,0,0,0,0,0,0,0,0,0,0,0,0,0,0,0,0,CA68,0,0,~
0)';
      PINUSE='GROUND';
      NO_LOAD_CHECK='Both';
      NO_IO_CHECK='Both';
      NO_ASSERT_CHECK='TRUE';
      NO_DIR_CHECK='TRUE';
      ALLOW_CONNECT='TRUE';
    'VSS'<515>:
      PIN_NUMBER='(0,0,0,0,0,0,0,0,0,0,0,0,0,0,0,0,0,0,0,0,0,0,0,0,0,0,CA70,0,0,~
0)';
      PINUSE='GROUND';
      NO_LOAD_CHECK='Both';
      NO_IO_CHECK='Both';
      NO_ASSERT_CHECK='TRUE';
      NO_DIR_CHECK='TRUE';
      ALLOW_CONNECT='TRUE';
    'VSS'<514>:
      PIN_NUMBER='(0,0,0,0,0,0,0,0,0,0,0,0,0,0,0,0,0,0,0,0,0,0,0,0,0,0,CB7,0,0,0~
)';
      PINUSE='GROUND';
      NO_LOAD_CHECK='Both';
      NO_IO_CHECK='Both';
      NO_ASSERT_CHECK='TRUE';
      NO_DIR_CHECK='TRUE';
      ALLOW_CONNECT='TRUE';
    'VSS'<513>:
      PIN_NUMBER='(0,0,0,0,0,0,0,0,0,0,0,0,0,0,0,0,0,0,0,0,0,0,0,0,0,0,CB9,0,0,0~
)';
      PINUSE='GROUND';
      NO_LOAD_CHECK='Both';
      NO_IO_CHECK='Both';
      NO_ASSERT_CHECK='TRUE';
      NO_DIR_CHECK='TRUE';
      ALLOW_CONNECT='TRUE';
    'VSS'<512>:
      PIN_NUMBER='(0,0,0,0,0,0,0,0,0,0,0,0,0,0,0,0,0,0,0,0,0,0,0,0,0,0,CB27,0,0,~
0)';
      PINUSE='GROUND';
      NO_LOAD_CHECK='Both';
      NO_IO_CHECK='Both';
      NO_ASSERT_CHECK='TRUE';
      NO_DIR_CHECK='TRUE';
      ALLOW_CONNECT='TRUE';
    'VSS'<511>:
      PIN_NUMBER='(0,0,0,0,0,0,0,0,0,0,0,0,0,0,0,0,0,0,0,0,0,0,0,0,0,0,CB63,0,0,~
0)';
      PINUSE='GROUND';
      NO_LOAD_CHECK='Both';
      NO_IO_CHECK='Both';
      NO_ASSERT_CHECK='TRUE';
      NO_DIR_CHECK='TRUE';
      ALLOW_CONNECT='TRUE';
    'VSS'<510>:
      PIN_NUMBER='(0,0,0,0,0,0,0,0,0,0,0,0,0,0,0,0,0,0,0,0,0,0,0,0,0,0,CB71,0,0,~
0)';
      PINUSE='GROUND';
      NO_LOAD_CHECK='Both';
      NO_IO_CHECK='Both';
      NO_ASSERT_CHECK='TRUE';
      NO_DIR_CHECK='TRUE';
      ALLOW_CONNECT='TRUE';
    'VSS'<509>:
      PIN_NUMBER='(0,0,0,0,0,0,0,0,0,0,0,0,0,0,0,0,0,0,0,0,0,0,0,0,0,0,CC4,0,0,0~
)';
      PINUSE='GROUND';
      NO_LOAD_CHECK='Both';
      NO_IO_CHECK='Both';
      NO_ASSERT_CHECK='TRUE';
      NO_DIR_CHECK='TRUE';
      ALLOW_CONNECT='TRUE';
    'VSS'<508>:
      PIN_NUMBER='(0,0,0,0,0,0,0,0,0,0,0,0,0,0,0,0,0,0,0,0,0,0,0,0,0,0,CC16,0,0,~
0)';
      PINUSE='GROUND';
      NO_LOAD_CHECK='Both';
      NO_IO_CHECK='Both';
      NO_ASSERT_CHECK='TRUE';
      NO_DIR_CHECK='TRUE';
      ALLOW_CONNECT='TRUE';
    'VSS'<507>:
      PIN_NUMBER='(0,0,0,0,0,0,0,0,0,0,0,0,0,0,0,0,0,0,0,0,0,0,0,0,0,0,CC18,0,0,~
0)';
      PINUSE='GROUND';
      NO_LOAD_CHECK='Both';
      NO_IO_CHECK='Both';
      NO_ASSERT_CHECK='TRUE';
      NO_DIR_CHECK='TRUE';
      ALLOW_CONNECT='TRUE';
    'VSS'<506>:
      PIN_NUMBER='(0,0,0,0,0,0,0,0,0,0,0,0,0,0,0,0,0,0,0,0,0,0,0,0,0,0,CC24,0,0,~
0)';
      PINUSE='GROUND';
      NO_LOAD_CHECK='Both';
      NO_IO_CHECK='Both';
      NO_ASSERT_CHECK='TRUE';
      NO_DIR_CHECK='TRUE';
      ALLOW_CONNECT='TRUE';
    'VSS'<505>:
      PIN_NUMBER='(0,0,0,0,0,0,0,0,0,0,0,0,0,0,0,0,0,0,0,0,0,0,0,0,0,0,CC64,0,0,~
0)';
      PINUSE='GROUND';
      NO_LOAD_CHECK='Both';
      NO_IO_CHECK='Both';
      NO_ASSERT_CHECK='TRUE';
      NO_DIR_CHECK='TRUE';
      ALLOW_CONNECT='TRUE';
    'VSS'<504>:
      PIN_NUMBER='(0,0,0,0,0,0,0,0,0,0,0,0,0,0,0,0,0,0,0,0,0,0,0,0,0,0,CC72,0,0,~
0)';
      PINUSE='GROUND';
      NO_LOAD_CHECK='Both';
      NO_IO_CHECK='Both';
      NO_ASSERT_CHECK='TRUE';
      NO_DIR_CHECK='TRUE';
      ALLOW_CONNECT='TRUE';
    'VSS'<503>:
      PIN_NUMBER='(0,0,0,0,0,0,0,0,0,0,0,0,0,0,0,0,0,0,0,0,0,0,0,0,0,0,CC74,0,0,~
0)';
      PINUSE='GROUND';
      NO_LOAD_CHECK='Both';
      NO_IO_CHECK='Both';
      NO_ASSERT_CHECK='TRUE';
      NO_DIR_CHECK='TRUE';
      ALLOW_CONNECT='TRUE';
    'VSS'<502>:
      PIN_NUMBER='(0,0,0,0,0,0,0,0,0,0,0,0,0,0,0,0,0,0,0,0,0,0,0,0,0,0,CC76,0,0,~
0)';
      PINUSE='GROUND';
      NO_LOAD_CHECK='Both';
      NO_IO_CHECK='Both';
      NO_ASSERT_CHECK='TRUE';
      NO_DIR_CHECK='TRUE';
      ALLOW_CONNECT='TRUE';
    'VSS'<501>:
      PIN_NUMBER='(0,0,0,0,0,0,0,0,0,0,0,0,0,0,0,0,0,0,0,0,0,0,0,0,0,0,CC78,0,0,~
0)';
      PINUSE='GROUND';
      NO_LOAD_CHECK='Both';
      NO_IO_CHECK='Both';
      NO_ASSERT_CHECK='TRUE';
      NO_DIR_CHECK='TRUE';
      ALLOW_CONNECT='TRUE';
    'VSS'<500>:
      PIN_NUMBER='(0,0,0,0,0,0,0,0,0,0,0,0,0,0,0,0,0,0,0,0,0,0,0,0,0,0,CC80,0,0,~
0)';
      PINUSE='GROUND';
      NO_LOAD_CHECK='Both';
      NO_IO_CHECK='Both';
      NO_ASSERT_CHECK='TRUE';
      NO_DIR_CHECK='TRUE';
      ALLOW_CONNECT='TRUE';
    'VSS'<499>:
      PIN_NUMBER='(0,0,0,0,0,0,0,0,0,0,0,0,0,0,0,0,0,0,0,0,0,0,0,0,0,0,CC82,0,0,~
0)';
      PINUSE='GROUND';
      NO_LOAD_CHECK='Both';
      NO_IO_CHECK='Both';
      NO_ASSERT_CHECK='TRUE';
      NO_DIR_CHECK='TRUE';
      ALLOW_CONNECT='TRUE';
    'VSS'<498>:
      PIN_NUMBER='(0,0,0,0,0,0,0,0,0,0,0,0,0,0,0,0,0,0,0,0,0,0,0,0,0,0,CD5,0,0,0~
)';
      PINUSE='GROUND';
      NO_LOAD_CHECK='Both';
      NO_IO_CHECK='Both';
      NO_ASSERT_CHECK='TRUE';
      NO_DIR_CHECK='TRUE';
      ALLOW_CONNECT='TRUE';
    'VSS'<497>:
      PIN_NUMBER='(0,0,0,0,0,0,0,0,0,0,0,0,0,0,0,0,0,0,0,0,0,0,0,0,0,0,CD13,0,0,~
0)';
      PINUSE='GROUND';
      NO_LOAD_CHECK='Both';
      NO_IO_CHECK='Both';
      NO_ASSERT_CHECK='TRUE';
      NO_DIR_CHECK='TRUE';
      ALLOW_CONNECT='TRUE';
    'VSS'<496>:
      PIN_NUMBER='(0,0,0,0,0,0,0,0,0,0,0,0,0,0,0,0,0,0,0,0,0,0,0,0,0,0,CD63,0,0,~
0)';
      PINUSE='GROUND';
      NO_LOAD_CHECK='Both';
      NO_IO_CHECK='Both';
      NO_ASSERT_CHECK='TRUE';
      NO_DIR_CHECK='TRUE';
      ALLOW_CONNECT='TRUE';
    'VSS'<495>:
      PIN_NUMBER='(0,0,0,0,0,0,0,0,0,0,0,0,0,0,0,0,0,0,0,0,0,0,0,0,0,0,CD73,0,0,~
0)';
      PINUSE='GROUND';
      NO_LOAD_CHECK='Both';
      NO_IO_CHECK='Both';
      NO_ASSERT_CHECK='TRUE';
      NO_DIR_CHECK='TRUE';
      ALLOW_CONNECT='TRUE';
    'VSS'<494>:
      PIN_NUMBER='(0,0,0,0,0,0,0,0,0,0,0,0,0,0,0,0,0,0,0,0,0,0,0,0,0,0,CD75,0,0,~
0)';
      PINUSE='GROUND';
      NO_LOAD_CHECK='Both';
      NO_IO_CHECK='Both';
      NO_ASSERT_CHECK='TRUE';
      NO_DIR_CHECK='TRUE';
      ALLOW_CONNECT='TRUE';
    'VSS'<493>:
      PIN_NUMBER='(0,0,0,0,0,0,0,0,0,0,0,0,0,0,0,0,0,0,0,0,0,0,0,0,0,0,CD77,0,0,~
0)';
      PINUSE='GROUND';
      NO_LOAD_CHECK='Both';
      NO_IO_CHECK='Both';
      NO_ASSERT_CHECK='TRUE';
      NO_DIR_CHECK='TRUE';
      ALLOW_CONNECT='TRUE';
    'VSS'<492>:
      PIN_NUMBER='(0,0,0,0,0,0,0,0,0,0,0,0,0,0,0,0,0,0,0,0,0,0,0,0,0,0,CD79,0,0,~
0)';
      PINUSE='GROUND';
      NO_LOAD_CHECK='Both';
      NO_IO_CHECK='Both';
      NO_ASSERT_CHECK='TRUE';
      NO_DIR_CHECK='TRUE';
      ALLOW_CONNECT='TRUE';
    'VSS'<491>:
      PIN_NUMBER='(0,0,0,0,0,0,0,0,0,0,0,0,0,0,0,0,0,0,0,0,0,0,0,0,0,0,CD81,0,0,~
0)';
      PINUSE='GROUND';
      NO_LOAD_CHECK='Both';
      NO_IO_CHECK='Both';
      NO_ASSERT_CHECK='TRUE';
      NO_DIR_CHECK='TRUE';
      ALLOW_CONNECT='TRUE';
    'VSS'<490>:
      PIN_NUMBER='(0,0,0,0,0,0,0,0,0,0,0,0,0,0,0,0,0,0,0,0,0,0,0,0,0,0,CE10,0,0,~
0)';
      PINUSE='GROUND';
      NO_LOAD_CHECK='Both';
      NO_IO_CHECK='Both';
      NO_ASSERT_CHECK='TRUE';
      NO_DIR_CHECK='TRUE';
      ALLOW_CONNECT='TRUE';
    'VSS'<489>:
      PIN_NUMBER='(0,0,0,0,0,0,0,0,0,0,0,0,0,0,0,0,0,0,0,0,0,0,0,0,0,0,CE14,0,0,~
0)';
      PINUSE='GROUND';
      NO_LOAD_CHECK='Both';
      NO_IO_CHECK='Both';
      NO_ASSERT_CHECK='TRUE';
      NO_DIR_CHECK='TRUE';
      ALLOW_CONNECT='TRUE';
    'VSS'<488>:
      PIN_NUMBER='(0,0,0,0,0,0,0,0,0,0,0,0,0,0,0,0,0,0,0,0,0,0,0,0,0,0,CE20,0,0,~
0)';
      PINUSE='GROUND';
      NO_LOAD_CHECK='Both';
      NO_IO_CHECK='Both';
      NO_ASSERT_CHECK='TRUE';
      NO_DIR_CHECK='TRUE';
      ALLOW_CONNECT='TRUE';
    'VSS'<487>:
      PIN_NUMBER='(0,0,0,0,0,0,0,0,0,0,0,0,0,0,0,0,0,0,0,0,0,0,0,0,0,0,CE26,0,0,~
0)';
      PINUSE='GROUND';
      NO_LOAD_CHECK='Both';
      NO_IO_CHECK='Both';
      NO_ASSERT_CHECK='TRUE';
      NO_DIR_CHECK='TRUE';
      ALLOW_CONNECT='TRUE';
    'VSS'<486>:
      PIN_NUMBER='(0,0,0,0,0,0,0,0,0,0,0,0,0,0,0,0,0,0,0,0,0,0,0,0,0,0,CE62,0,0,~
0)';
      PINUSE='GROUND';
      NO_LOAD_CHECK='Both';
      NO_IO_CHECK='Both';
      NO_ASSERT_CHECK='TRUE';
      NO_DIR_CHECK='TRUE';
      ALLOW_CONNECT='TRUE';
    'VSS'<485>:
      PIN_NUMBER='(0,0,0,0,0,0,0,0,0,0,0,0,0,0,0,0,0,0,0,0,0,0,0,0,0,0,CE70,0,0,~
0)';
      PINUSE='GROUND';
      NO_LOAD_CHECK='Both';
      NO_IO_CHECK='Both';
      NO_ASSERT_CHECK='TRUE';
      NO_DIR_CHECK='TRUE';
      ALLOW_CONNECT='TRUE';
    'VSS'<484>:
      PIN_NUMBER='(0,0,0,0,0,0,0,0,0,0,0,0,0,0,0,0,0,0,0,0,0,0,0,0,0,0,CE82,0,0,~
0)';
      PINUSE='GROUND';
      NO_LOAD_CHECK='Both';
      NO_IO_CHECK='Both';
      NO_ASSERT_CHECK='TRUE';
      NO_DIR_CHECK='TRUE';
      ALLOW_CONNECT='TRUE';
    'VSS'<483>:
      PIN_NUMBER='(0,0,0,0,0,0,0,0,0,0,0,0,0,0,0,0,0,0,0,0,0,0,0,0,0,0,P53,0,0,0~
)';
      PINUSE='GROUND';
      NO_LOAD_CHECK='Both';
      NO_IO_CHECK='Both';
      NO_ASSERT_CHECK='TRUE';
      NO_DIR_CHECK='TRUE';
      ALLOW_CONNECT='TRUE';
    'VSS'<482>:
      PIN_NUMBER='(0,0,0,0,0,0,0,0,0,0,0,0,0,0,0,0,0,0,0,0,0,0,0,0,0,0,CF9,0,0,0~
)';
      PINUSE='GROUND';
      NO_LOAD_CHECK='Both';
      NO_IO_CHECK='Both';
      NO_ASSERT_CHECK='TRUE';
      NO_DIR_CHECK='TRUE';
      ALLOW_CONNECT='TRUE';
    'VSS'<481>:
      PIN_NUMBER='(0,0,0,0,0,0,0,0,0,0,0,0,0,0,0,0,0,0,0,0,0,0,0,0,0,0,CF63,0,0,~
0)';
      PINUSE='GROUND';
      NO_LOAD_CHECK='Both';
      NO_IO_CHECK='Both';
      NO_ASSERT_CHECK='TRUE';
      NO_DIR_CHECK='TRUE';
      ALLOW_CONNECT='TRUE';
    'VSS'<480>:
      PIN_NUMBER='(0,0,0,0,0,0,0,0,0,0,0,0,0,0,0,0,0,0,0,0,0,0,0,0,0,0,CF69,0,0,~
0)';
      PINUSE='GROUND';
      NO_LOAD_CHECK='Both';
      NO_IO_CHECK='Both';
      NO_ASSERT_CHECK='TRUE';
      NO_DIR_CHECK='TRUE';
      ALLOW_CONNECT='TRUE';
    'VSS'<479>:
      PIN_NUMBER='(0,0,0,0,0,0,0,0,0,0,0,0,0,0,0,0,0,0,0,0,0,0,0,0,0,0,CF71,0,0,~
0)';
      PINUSE='GROUND';
      NO_LOAD_CHECK='Both';
      NO_IO_CHECK='Both';
      NO_ASSERT_CHECK='TRUE';
      NO_DIR_CHECK='TRUE';
      ALLOW_CONNECT='TRUE';
    'VSS'<478>:
      PIN_NUMBER='(0,0,0,0,0,0,0,0,0,0,0,0,0,0,0,0,0,0,0,0,0,0,0,0,0,0,CF77,0,0,~
0)';
      PINUSE='GROUND';
      NO_LOAD_CHECK='Both';
      NO_IO_CHECK='Both';
      NO_ASSERT_CHECK='TRUE';
      NO_DIR_CHECK='TRUE';
      ALLOW_CONNECT='TRUE';
    'VSS'<477>:
      PIN_NUMBER='(0,0,0,0,0,0,0,0,0,0,0,0,0,0,0,0,0,0,0,0,0,0,0,0,0,0,CF83,0,0,~
0)';
      PINUSE='GROUND';
      NO_LOAD_CHECK='Both';
      NO_IO_CHECK='Both';
      NO_ASSERT_CHECK='TRUE';
      NO_DIR_CHECK='TRUE';
      ALLOW_CONNECT='TRUE';
    'VSS'<476>:
      PIN_NUMBER='(0,0,0,0,0,0,0,0,0,0,0,0,0,0,0,0,0,0,0,0,0,0,0,0,0,0,P51,0,0,0~
)';
      PINUSE='GROUND';
      NO_LOAD_CHECK='Both';
      NO_IO_CHECK='Both';
      NO_ASSERT_CHECK='TRUE';
      NO_DIR_CHECK='TRUE';
      ALLOW_CONNECT='TRUE';
    'VSS'<475>:
      PIN_NUMBER='(0,0,0,0,0,0,0,0,0,0,0,0,0,0,0,0,0,0,0,0,0,0,0,0,0,0,CG18,0,0,~
0)';
      PINUSE='GROUND';
      NO_LOAD_CHECK='Both';
      NO_IO_CHECK='Both';
      NO_ASSERT_CHECK='TRUE';
      NO_DIR_CHECK='TRUE';
      ALLOW_CONNECT='TRUE';
    'VSS'<474>:
      PIN_NUMBER='(0,0,0,0,0,0,0,0,0,0,0,0,0,0,0,0,0,0,0,0,0,0,0,0,0,0,CG22,0,0,~
0)';
      PINUSE='GROUND';
      NO_LOAD_CHECK='Both';
      NO_IO_CHECK='Both';
      NO_ASSERT_CHECK='TRUE';
      NO_DIR_CHECK='TRUE';
      ALLOW_CONNECT='TRUE';
    'VSS'<473>:
      PIN_NUMBER='(0,0,0,0,0,0,0,0,0,0,0,0,0,0,0,0,0,0,0,0,0,0,0,0,0,0,CG62,0,0,~
0)';
      PINUSE='GROUND';
      NO_LOAD_CHECK='Both';
      NO_IO_CHECK='Both';
      NO_ASSERT_CHECK='TRUE';
      NO_DIR_CHECK='TRUE';
      ALLOW_CONNECT='TRUE';
    'VSS'<472>:
      PIN_NUMBER='(0,0,0,0,0,0,0,0,0,0,0,0,0,0,0,0,0,0,0,0,0,0,0,0,0,0,CG68,0,0,~
0)';
      PINUSE='GROUND';
      NO_LOAD_CHECK='Both';
      NO_IO_CHECK='Both';
      NO_ASSERT_CHECK='TRUE';
      NO_DIR_CHECK='TRUE';
      ALLOW_CONNECT='TRUE';
    'VSS'<471>:
      PIN_NUMBER='(0,0,0,0,0,0,0,0,0,0,0,0,0,0,0,0,0,0,0,0,0,0,0,0,0,0,CG72,0,0,~
0)';
      PINUSE='GROUND';
      NO_LOAD_CHECK='Both';
      NO_IO_CHECK='Both';
      NO_ASSERT_CHECK='TRUE';
      NO_DIR_CHECK='TRUE';
      ALLOW_CONNECT='TRUE';
    'VSS'<470>:
      PIN_NUMBER='(0,0,0,0,0,0,0,0,0,0,0,0,0,0,0,0,0,0,0,0,0,0,0,0,0,0,CG80,0,0,~
0)';
      PINUSE='GROUND';
      NO_LOAD_CHECK='Both';
      NO_IO_CHECK='Both';
      NO_ASSERT_CHECK='TRUE';
      NO_DIR_CHECK='TRUE';
      ALLOW_CONNECT='TRUE';
    'VSS'<469>:
      PIN_NUMBER='(0,0,0,0,0,0,0,0,0,0,0,0,0,0,0,0,0,0,0,0,0,0,0,0,0,0,CH1,0,0,0~
)';
      PINUSE='GROUND';
      NO_LOAD_CHECK='Both';
      NO_IO_CHECK='Both';
      NO_ASSERT_CHECK='TRUE';
      NO_DIR_CHECK='TRUE';
      ALLOW_CONNECT='TRUE';
    'VSS'<468>:
      PIN_NUMBER='(0,0,0,0,0,0,0,0,0,0,0,0,0,0,0,0,0,0,0,0,0,0,0,0,0,0,CH3,0,0,0~
)';
      PINUSE='GROUND';
      NO_LOAD_CHECK='Both';
      NO_IO_CHECK='Both';
      NO_ASSERT_CHECK='TRUE';
      NO_DIR_CHECK='TRUE';
      ALLOW_CONNECT='TRUE';
    'VSS'<467>:
      PIN_NUMBER='(0,0,0,0,0,0,0,0,0,0,0,0,0,0,0,0,0,0,0,0,0,0,0,0,0,0,CH15,0,0,~
0)';
      PINUSE='GROUND';
      NO_LOAD_CHECK='Both';
      NO_IO_CHECK='Both';
      NO_ASSERT_CHECK='TRUE';
      NO_DIR_CHECK='TRUE';
      ALLOW_CONNECT='TRUE';
    'VSS'<466>:
      PIN_NUMBER='(0,0,0,0,0,0,0,0,0,0,0,0,0,0,0,0,0,0,0,0,0,0,0,0,0,0,CH19,0,0,~
0)';
      PINUSE='GROUND';
      NO_LOAD_CHECK='Both';
      NO_IO_CHECK='Both';
      NO_ASSERT_CHECK='TRUE';
      NO_DIR_CHECK='TRUE';
      ALLOW_CONNECT='TRUE';
    'VSS'<465>:
      PIN_NUMBER='(0,0,0,0,0,0,0,0,0,0,0,0,0,0,0,0,0,0,0,0,0,0,0,0,0,0,CH63,0,0,~
0)';
      PINUSE='GROUND';
      NO_LOAD_CHECK='Both';
      NO_IO_CHECK='Both';
      NO_ASSERT_CHECK='TRUE';
      NO_DIR_CHECK='TRUE';
      ALLOW_CONNECT='TRUE';
    'VSS'<464>:
      PIN_NUMBER='(0,0,0,0,0,0,0,0,0,0,0,0,0,0,0,0,0,0,0,0,0,0,0,0,0,0,CH67,0,0,~
0)';
      PINUSE='GROUND';
      NO_LOAD_CHECK='Both';
      NO_IO_CHECK='Both';
      NO_ASSERT_CHECK='TRUE';
      NO_DIR_CHECK='TRUE';
      ALLOW_CONNECT='TRUE';
    'VSS'<463>:
      PIN_NUMBER='(0,0,0,0,0,0,0,0,0,0,0,0,0,0,0,0,0,0,0,0,0,0,0,0,0,0,CH73,0,0,~
0)';
      PINUSE='GROUND';
      NO_LOAD_CHECK='Both';
      NO_IO_CHECK='Both';
      NO_ASSERT_CHECK='TRUE';
      NO_DIR_CHECK='TRUE';
      ALLOW_CONNECT='TRUE';
    'VSS'<462>:
      PIN_NUMBER='(0,0,0,0,0,0,0,0,0,0,0,0,0,0,0,0,0,0,0,0,0,0,0,0,0,0,CH79,0,0,~
0)';
      PINUSE='GROUND';
      NO_LOAD_CHECK='Both';
      NO_IO_CHECK='Both';
      NO_ASSERT_CHECK='TRUE';
      NO_DIR_CHECK='TRUE';
      ALLOW_CONNECT='TRUE';
    'VSS'<461>:
      PIN_NUMBER='(0,0,0,0,0,0,0,0,0,0,0,0,0,0,0,0,0,0,0,0,0,0,0,0,0,0,CH81,0,0,~
0)';
      PINUSE='GROUND';
      NO_LOAD_CHECK='Both';
      NO_IO_CHECK='Both';
      NO_ASSERT_CHECK='TRUE';
      NO_DIR_CHECK='TRUE';
      ALLOW_CONNECT='TRUE';
    'VSS'<460>:
      PIN_NUMBER='(0,0,0,0,0,0,0,0,0,0,0,0,0,0,0,0,0,0,0,0,0,0,0,0,0,0,CH83,0,0,~
0)';
      PINUSE='GROUND';
      NO_LOAD_CHECK='Both';
      NO_IO_CHECK='Both';
      NO_ASSERT_CHECK='TRUE';
      NO_DIR_CHECK='TRUE';
      ALLOW_CONNECT='TRUE';
    'VSS'<459>:
      PIN_NUMBER='(0,0,0,0,0,0,0,0,0,0,0,0,0,0,0,0,0,0,0,0,0,0,0,0,0,0,CJ2,0,0,0~
)';
      PINUSE='GROUND';
      NO_LOAD_CHECK='Both';
      NO_IO_CHECK='Both';
      NO_ASSERT_CHECK='TRUE';
      NO_DIR_CHECK='TRUE';
      ALLOW_CONNECT='TRUE';
    'VSS'<458>:
      PIN_NUMBER='(0,0,0,0,0,0,0,0,0,0,0,0,0,0,0,0,0,0,0,0,0,0,0,0,0,0,CJ6,0,0,0~
)';
      PINUSE='GROUND';
      NO_LOAD_CHECK='Both';
      NO_IO_CHECK='Both';
      NO_ASSERT_CHECK='TRUE';
      NO_DIR_CHECK='TRUE';
      ALLOW_CONNECT='TRUE';
    'VSS'<457>:
      PIN_NUMBER='(0,0,0,0,0,0,0,0,0,0,0,0,0,0,0,0,0,0,0,0,0,0,0,0,0,0,CJ8,0,0,0~
)';
      PINUSE='GROUND';
      NO_LOAD_CHECK='Both';
      NO_IO_CHECK='Both';
      NO_ASSERT_CHECK='TRUE';
      NO_DIR_CHECK='TRUE';
      ALLOW_CONNECT='TRUE';
    'VSS'<456>:
      PIN_NUMBER='(0,0,0,0,0,0,0,0,0,0,0,0,0,0,0,0,0,0,0,0,0,0,0,0,0,0,CJ10,0,0,~
0)';
      PINUSE='GROUND';
      NO_LOAD_CHECK='Both';
      NO_IO_CHECK='Both';
      NO_ASSERT_CHECK='TRUE';
      NO_DIR_CHECK='TRUE';
      ALLOW_CONNECT='TRUE';
    'VSS'<455>:
      PIN_NUMBER='(0,0,0,0,0,0,0,0,0,0,0,0,0,0,0,0,0,0,0,0,0,0,0,0,0,0,CJ12,0,0,~
0)';
      PINUSE='GROUND';
      NO_LOAD_CHECK='Both';
      NO_IO_CHECK='Both';
      NO_ASSERT_CHECK='TRUE';
      NO_DIR_CHECK='TRUE';
      ALLOW_CONNECT='TRUE';
    'VSS'<454>:
      PIN_NUMBER='(0,0,0,0,0,0,0,0,0,0,0,0,0,0,0,0,0,0,0,0,0,0,0,0,0,0,P49,0,0,0~
)';
      PINUSE='GROUND';
      NO_LOAD_CHECK='Both';
      NO_IO_CHECK='Both';
      NO_ASSERT_CHECK='TRUE';
      NO_DIR_CHECK='TRUE';
      ALLOW_CONNECT='TRUE';
    'VSS'<453>:
      PIN_NUMBER='(0,0,0,0,0,0,0,0,0,0,0,0,0,0,0,0,0,0,0,0,0,0,0,0,0,0,0,P47,0,0~
)';
      PINUSE='GROUND';
      NO_LOAD_CHECK='Both';
      NO_IO_CHECK='Both';
      NO_ASSERT_CHECK='TRUE';
      NO_DIR_CHECK='TRUE';
      ALLOW_CONNECT='TRUE';
    'VSS'<452>:
      PIN_NUMBER='(0,0,0,0,0,0,0,0,0,0,0,0,0,0,0,0,0,0,0,0,0,0,0,0,0,0,0,CJ62,0,~
0)';
      PINUSE='GROUND';
      NO_LOAD_CHECK='Both';
      NO_IO_CHECK='Both';
      NO_ASSERT_CHECK='TRUE';
      NO_DIR_CHECK='TRUE';
      ALLOW_CONNECT='TRUE';
    'VSS'<451>:
      PIN_NUMBER='(0,0,0,0,0,0,0,0,0,0,0,0,0,0,0,0,0,0,0,0,0,0,0,0,0,0,0,CJ74,0,~
0)';
      PINUSE='GROUND';
      NO_LOAD_CHECK='Both';
      NO_IO_CHECK='Both';
      NO_ASSERT_CHECK='TRUE';
      NO_DIR_CHECK='TRUE';
      ALLOW_CONNECT='TRUE';
    'VSS'<450>:
      PIN_NUMBER='(0,0,0,0,0,0,0,0,0,0,0,0,0,0,0,0,0,0,0,0,0,0,0,0,0,0,0,CJ76,0,~
0)';
      PINUSE='GROUND';
      NO_LOAD_CHECK='Both';
      NO_IO_CHECK='Both';
      NO_ASSERT_CHECK='TRUE';
      NO_DIR_CHECK='TRUE';
      ALLOW_CONNECT='TRUE';
    'VSS'<449>:
      PIN_NUMBER='(0,0,0,0,0,0,0,0,0,0,0,0,0,0,0,0,0,0,0,0,0,0,0,0,0,0,0,CJ78,0,~
0)';
      PINUSE='GROUND';
      NO_LOAD_CHECK='Both';
      NO_IO_CHECK='Both';
      NO_ASSERT_CHECK='TRUE';
      NO_DIR_CHECK='TRUE';
      ALLOW_CONNECT='TRUE';
    'VSS'<448>:
      PIN_NUMBER='(0,0,0,0,0,0,0,0,0,0,0,0,0,0,0,0,0,0,0,0,0,0,0,0,0,0,0,CJ82,0,~
0)';
      PINUSE='GROUND';
      NO_LOAD_CHECK='Both';
      NO_IO_CHECK='Both';
      NO_ASSERT_CHECK='TRUE';
      NO_DIR_CHECK='TRUE';
      ALLOW_CONNECT='TRUE';
    'VSS'<447>:
      PIN_NUMBER='(0,0,0,0,0,0,0,0,0,0,0,0,0,0,0,0,0,0,0,0,0,0,0,0,0,0,0,CJ84,0,~
0)';
      PINUSE='GROUND';
      NO_LOAD_CHECK='Both';
      NO_IO_CHECK='Both';
      NO_ASSERT_CHECK='TRUE';
      NO_DIR_CHECK='TRUE';
      ALLOW_CONNECT='TRUE';
    'VSS'<446>:
      PIN_NUMBER='(0,0,0,0,0,0,0,0,0,0,0,0,0,0,0,0,0,0,0,0,0,0,0,0,0,0,0,CJ86,0,~
0)';
      PINUSE='GROUND';
      NO_LOAD_CHECK='Both';
      NO_IO_CHECK='Both';
      NO_ASSERT_CHECK='TRUE';
      NO_DIR_CHECK='TRUE';
      ALLOW_CONNECT='TRUE';
    'VSS'<445>:
      PIN_NUMBER='(0,0,0,0,0,0,0,0,0,0,0,0,0,0,0,0,0,0,0,0,0,0,0,0,0,0,0,CK11,0,~
0)';
      PINUSE='GROUND';
      NO_LOAD_CHECK='Both';
      NO_IO_CHECK='Both';
      NO_ASSERT_CHECK='TRUE';
      NO_DIR_CHECK='TRUE';
      ALLOW_CONNECT='TRUE';
    'VSS'<444>:
      PIN_NUMBER='(0,0,0,0,0,0,0,0,0,0,0,0,0,0,0,0,0,0,0,0,0,0,0,0,0,0,0,CK15,0,~
0)';
      PINUSE='GROUND';
      NO_LOAD_CHECK='Both';
      NO_IO_CHECK='Both';
      NO_ASSERT_CHECK='TRUE';
      NO_DIR_CHECK='TRUE';
      ALLOW_CONNECT='TRUE';
    'VSS'<443>:
      PIN_NUMBER='(0,0,0,0,0,0,0,0,0,0,0,0,0,0,0,0,0,0,0,0,0,0,0,0,0,0,0,CK21,0,~
0)';
      PINUSE='GROUND';
      NO_LOAD_CHECK='Both';
      NO_IO_CHECK='Both';
      NO_ASSERT_CHECK='TRUE';
      NO_DIR_CHECK='TRUE';
      ALLOW_CONNECT='TRUE';
    'VSS'<442>:
      PIN_NUMBER='(0,0,0,0,0,0,0,0,0,0,0,0,0,0,0,0,0,0,0,0,0,0,0,0,0,0,0,CK27,0,~
0)';
      PINUSE='GROUND';
      NO_LOAD_CHECK='Both';
      NO_IO_CHECK='Both';
      NO_ASSERT_CHECK='TRUE';
      NO_DIR_CHECK='TRUE';
      ALLOW_CONNECT='TRUE';
    'VSS'<441>:
      PIN_NUMBER='(0,0,0,0,0,0,0,0,0,0,0,0,0,0,0,0,0,0,0,0,0,0,0,0,0,0,0,CK63,0,~
0)';
      PINUSE='GROUND';
      NO_LOAD_CHECK='Both';
      NO_IO_CHECK='Both';
      NO_ASSERT_CHECK='TRUE';
      NO_DIR_CHECK='TRUE';
      ALLOW_CONNECT='TRUE';
    'VSS'<440>:
      PIN_NUMBER='(0,0,0,0,0,0,0,0,0,0,0,0,0,0,0,0,0,0,0,0,0,0,0,0,0,0,0,CK65,0,~
0)';
      PINUSE='GROUND';
      NO_LOAD_CHECK='Both';
      NO_IO_CHECK='Both';
      NO_ASSERT_CHECK='TRUE';
      NO_DIR_CHECK='TRUE';
      ALLOW_CONNECT='TRUE';
    'VSS'<439>:
      PIN_NUMBER='(0,0,0,0,0,0,0,0,0,0,0,0,0,0,0,0,0,0,0,0,0,0,0,0,0,0,0,CK67,0,~
0)';
      PINUSE='GROUND';
      NO_LOAD_CHECK='Both';
      NO_IO_CHECK='Both';
      NO_ASSERT_CHECK='TRUE';
      NO_DIR_CHECK='TRUE';
      ALLOW_CONNECT='TRUE';
    'VSS'<438>:
      PIN_NUMBER='(0,0,0,0,0,0,0,0,0,0,0,0,0,0,0,0,0,0,0,0,0,0,0,0,0,0,0,CK69,0,~
0)';
      PINUSE='GROUND';
      NO_LOAD_CHECK='Both';
      NO_IO_CHECK='Both';
      NO_ASSERT_CHECK='TRUE';
      NO_DIR_CHECK='TRUE';
      ALLOW_CONNECT='TRUE';
    'VSS'<437>:
      PIN_NUMBER='(0,0,0,0,0,0,0,0,0,0,0,0,0,0,0,0,0,0,0,0,0,0,0,0,0,0,0,CK71,0,~
0)';
      PINUSE='GROUND';
      NO_LOAD_CHECK='Both';
      NO_IO_CHECK='Both';
      NO_ASSERT_CHECK='TRUE';
      NO_DIR_CHECK='TRUE';
      ALLOW_CONNECT='TRUE';
    'VSS'<436>:
      PIN_NUMBER='(0,0,0,0,0,0,0,0,0,0,0,0,0,0,0,0,0,0,0,0,0,0,0,0,0,0,0,CK73,0,~
0)';
      PINUSE='GROUND';
      NO_LOAD_CHECK='Both';
      NO_IO_CHECK='Both';
      NO_ASSERT_CHECK='TRUE';
      NO_DIR_CHECK='TRUE';
      ALLOW_CONNECT='TRUE';
    'VSS'<435>:
      PIN_NUMBER='(0,0,0,0,0,0,0,0,0,0,0,0,0,0,0,0,0,0,0,0,0,0,0,0,0,0,0,CK75,0,~
0)';
      PINUSE='GROUND';
      NO_LOAD_CHECK='Both';
      NO_IO_CHECK='Both';
      NO_ASSERT_CHECK='TRUE';
      NO_DIR_CHECK='TRUE';
      ALLOW_CONNECT='TRUE';
    'VSS'<434>:
      PIN_NUMBER='(0,0,0,0,0,0,0,0,0,0,0,0,0,0,0,0,0,0,0,0,0,0,0,0,0,0,0,CK83,0,~
0)';
      PINUSE='GROUND';
      NO_LOAD_CHECK='Both';
      NO_IO_CHECK='Both';
      NO_ASSERT_CHECK='TRUE';
      NO_DIR_CHECK='TRUE';
      ALLOW_CONNECT='TRUE';
    'VSS'<433>:
      PIN_NUMBER='(0,0,0,0,0,0,0,0,0,0,0,0,0,0,0,0,0,0,0,0,0,0,0,0,0,0,0,CK85,0,~
0)';
      PINUSE='GROUND';
      NO_LOAD_CHECK='Both';
      NO_IO_CHECK='Both';
      NO_ASSERT_CHECK='TRUE';
      NO_DIR_CHECK='TRUE';
      ALLOW_CONNECT='TRUE';
    'VSS'<432>:
      PIN_NUMBER='(0,0,0,0,0,0,0,0,0,0,0,0,0,0,0,0,0,0,0,0,0,0,0,0,0,0,0,CL8,0,0~
)';
      PINUSE='GROUND';
      NO_LOAD_CHECK='Both';
      NO_IO_CHECK='Both';
      NO_ASSERT_CHECK='TRUE';
      NO_DIR_CHECK='TRUE';
      ALLOW_CONNECT='TRUE';
    'VSS'<431>:
      PIN_NUMBER='(0,0,0,0,0,0,0,0,0,0,0,0,0,0,0,0,0,0,0,0,0,0,0,0,0,0,0,CL14,0,~
0)';
      PINUSE='GROUND';
      NO_LOAD_CHECK='Both';
      NO_IO_CHECK='Both';
      NO_ASSERT_CHECK='TRUE';
      NO_DIR_CHECK='TRUE';
      ALLOW_CONNECT='TRUE';
    'VSS'<430>:
      PIN_NUMBER='(0,0,0,0,0,0,0,0,0,0,0,0,0,0,0,0,0,0,0,0,0,0,0,0,0,0,0,CL18,0,~
0)';
      PINUSE='GROUND';
      NO_LOAD_CHECK='Both';
      NO_IO_CHECK='Both';
      NO_ASSERT_CHECK='TRUE';
      NO_DIR_CHECK='TRUE';
      ALLOW_CONNECT='TRUE';
    'VSS'<429>:
      PIN_NUMBER='(0,0,0,0,0,0,0,0,0,0,0,0,0,0,0,0,0,0,0,0,0,0,0,0,0,0,0,P45,0,0~
)';
      PINUSE='GROUND';
      NO_LOAD_CHECK='Both';
      NO_IO_CHECK='Both';
      NO_ASSERT_CHECK='TRUE';
      NO_DIR_CHECK='TRUE';
      ALLOW_CONNECT='TRUE';
    'VSS'<428>:
      PIN_NUMBER='(0,0,0,0,0,0,0,0,0,0,0,0,0,0,0,0,0,0,0,0,0,0,0,0,0,0,0,H63,0,0~
)';
      PINUSE='GROUND';
      NO_LOAD_CHECK='Both';
      NO_IO_CHECK='Both';
      NO_ASSERT_CHECK='TRUE';
      NO_DIR_CHECK='TRUE';
      ALLOW_CONNECT='TRUE';
    'VSS'<427>:
      PIN_NUMBER='(0,0,0,0,0,0,0,0,0,0,0,0,0,0,0,0,0,0,0,0,0,0,0,0,0,0,0,CL62,0,~
0)';
      PINUSE='GROUND';
      NO_LOAD_CHECK='Both';
      NO_IO_CHECK='Both';
      NO_ASSERT_CHECK='TRUE';
      NO_DIR_CHECK='TRUE';
      ALLOW_CONNECT='TRUE';
    'VSS'<426>:
      PIN_NUMBER='(0,0,0,0,0,0,0,0,0,0,0,0,0,0,0,0,0,0,0,0,0,0,0,0,0,0,0,CL64,0,~
0)';
      PINUSE='GROUND';
      NO_LOAD_CHECK='Both';
      NO_IO_CHECK='Both';
      NO_ASSERT_CHECK='TRUE';
      NO_DIR_CHECK='TRUE';
      ALLOW_CONNECT='TRUE';
    'VSS'<425>:
      PIN_NUMBER='(0,0,0,0,0,0,0,0,0,0,0,0,0,0,0,0,0,0,0,0,0,0,0,0,0,0,0,CL66,0,~
0)';
      PINUSE='GROUND';
      NO_LOAD_CHECK='Both';
      NO_IO_CHECK='Both';
      NO_ASSERT_CHECK='TRUE';
      NO_DIR_CHECK='TRUE';
      ALLOW_CONNECT='TRUE';
    'VSS'<424>:
      PIN_NUMBER='(0,0,0,0,0,0,0,0,0,0,0,0,0,0,0,0,0,0,0,0,0,0,0,0,0,0,0,CL74,0,~
0)';
      PINUSE='GROUND';
      NO_LOAD_CHECK='Both';
      NO_IO_CHECK='Both';
      NO_ASSERT_CHECK='TRUE';
      NO_DIR_CHECK='TRUE';
      ALLOW_CONNECT='TRUE';
    'VSS'<423>:
      PIN_NUMBER='(0,0,0,0,0,0,0,0,0,0,0,0,0,0,0,0,0,0,0,0,0,0,0,0,0,0,0,CL76,0,~
0)';
      PINUSE='GROUND';
      NO_LOAD_CHECK='Both';
      NO_IO_CHECK='Both';
      NO_ASSERT_CHECK='TRUE';
      NO_DIR_CHECK='TRUE';
      ALLOW_CONNECT='TRUE';
    'VSS'<422>:
      PIN_NUMBER='(0,0,0,0,0,0,0,0,0,0,0,0,0,0,0,0,0,0,0,0,0,0,0,0,0,0,0,CL78,0,~
0)';
      PINUSE='GROUND';
      NO_LOAD_CHECK='Both';
      NO_IO_CHECK='Both';
      NO_ASSERT_CHECK='TRUE';
      NO_DIR_CHECK='TRUE';
      ALLOW_CONNECT='TRUE';
    'VSS'<421>:
      PIN_NUMBER='(0,0,0,0,0,0,0,0,0,0,0,0,0,0,0,0,0,0,0,0,0,0,0,0,0,0,0,CL80,0,~
0)';
      PINUSE='GROUND';
      NO_LOAD_CHECK='Both';
      NO_IO_CHECK='Both';
      NO_ASSERT_CHECK='TRUE';
      NO_DIR_CHECK='TRUE';
      ALLOW_CONNECT='TRUE';
    'VSS'<420>:
      PIN_NUMBER='(0,0,0,0,0,0,0,0,0,0,0,0,0,0,0,0,0,0,0,0,0,0,0,0,0,0,0,CM19,0,~
0)';
      PINUSE='GROUND';
      NO_LOAD_CHECK='Both';
      NO_IO_CHECK='Both';
      NO_ASSERT_CHECK='TRUE';
      NO_DIR_CHECK='TRUE';
      ALLOW_CONNECT='TRUE';
    'VSS'<419>:
      PIN_NUMBER='(0,0,0,0,0,0,0,0,0,0,0,0,0,0,0,0,0,0,0,0,0,0,0,0,0,0,0,CM29,0,~
0)';
      PINUSE='GROUND';
      NO_LOAD_CHECK='Both';
      NO_IO_CHECK='Both';
      NO_ASSERT_CHECK='TRUE';
      NO_DIR_CHECK='TRUE';
      ALLOW_CONNECT='TRUE';
    'VSS'<418>:
      PIN_NUMBER='(0,0,0,0,0,0,0,0,0,0,0,0,0,0,0,0,0,0,0,0,0,0,0,0,0,0,0,CM5,0,0~
)';
      PINUSE='GROUND';
      NO_LOAD_CHECK='Both';
      NO_IO_CHECK='Both';
      NO_ASSERT_CHECK='TRUE';
      NO_DIR_CHECK='TRUE';
      ALLOW_CONNECT='TRUE';
    'VSS'<417>:
      PIN_NUMBER='(0,0,0,0,0,0,0,0,0,0,0,0,0,0,0,0,0,0,0,0,0,0,0,0,0,0,0,CM31,0,~
0)';
      PINUSE='GROUND';
      NO_LOAD_CHECK='Both';
      NO_IO_CHECK='Both';
      NO_ASSERT_CHECK='TRUE';
      NO_DIR_CHECK='TRUE';
      ALLOW_CONNECT='TRUE';
    'VSS'<416>:
      PIN_NUMBER='(0,0,0,0,0,0,0,0,0,0,0,0,0,0,0,0,0,0,0,0,0,0,0,0,0,0,0,CM61,0,~
0)';
      PINUSE='GROUND';
      NO_LOAD_CHECK='Both';
      NO_IO_CHECK='Both';
      NO_ASSERT_CHECK='TRUE';
      NO_DIR_CHECK='TRUE';
      ALLOW_CONNECT='TRUE';
    'VSS'<415>:
      PIN_NUMBER='(0,0,0,0,0,0,0,0,0,0,0,0,0,0,0,0,0,0,0,0,0,0,0,0,0,0,0,CM63,0,~
0)';
      PINUSE='GROUND';
      NO_LOAD_CHECK='Both';
      NO_IO_CHECK='Both';
      NO_ASSERT_CHECK='TRUE';
      NO_DIR_CHECK='TRUE';
      ALLOW_CONNECT='TRUE';
    'VSS'<414>:
      PIN_NUMBER='(0,0,0,0,0,0,0,0,0,0,0,0,0,0,0,0,0,0,0,0,0,0,0,0,0,0,0,CM67,0,~
0)';
      PINUSE='GROUND';
      NO_LOAD_CHECK='Both';
      NO_IO_CHECK='Both';
      NO_ASSERT_CHECK='TRUE';
      NO_DIR_CHECK='TRUE';
      ALLOW_CONNECT='TRUE';
    'VSS'<413>:
      PIN_NUMBER='(0,0,0,0,0,0,0,0,0,0,0,0,0,0,0,0,0,0,0,0,0,0,0,0,0,0,0,CM73,0,~
0)';
      PINUSE='GROUND';
      NO_LOAD_CHECK='Both';
      NO_IO_CHECK='Both';
      NO_ASSERT_CHECK='TRUE';
      NO_DIR_CHECK='TRUE';
      ALLOW_CONNECT='TRUE';
    'VSS'<412>:
      PIN_NUMBER='(0,0,0,0,0,0,0,0,0,0,0,0,0,0,0,0,0,0,0,0,0,0,0,0,0,0,0,CM77,0,~
0)';
      PINUSE='GROUND';
      NO_LOAD_CHECK='Both';
      NO_IO_CHECK='Both';
      NO_ASSERT_CHECK='TRUE';
      NO_DIR_CHECK='TRUE';
      ALLOW_CONNECT='TRUE';
    'VSS'<411>:
      PIN_NUMBER='(0,0,0,0,0,0,0,0,0,0,0,0,0,0,0,0,0,0,0,0,0,0,0,0,0,0,0,CM83,0,~
0)';
      PINUSE='GROUND';
      NO_LOAD_CHECK='Both';
      NO_IO_CHECK='Both';
      NO_ASSERT_CHECK='TRUE';
      NO_DIR_CHECK='TRUE';
      ALLOW_CONNECT='TRUE';
    'VSS'<410>:
      PIN_NUMBER='(0,0,0,0,0,0,0,0,0,0,0,0,0,0,0,0,0,0,0,0,0,0,0,0,0,0,0,CM85,0,~
0)';
      PINUSE='GROUND';
      NO_LOAD_CHECK='Both';
      NO_IO_CHECK='Both';
      NO_ASSERT_CHECK='TRUE';
      NO_DIR_CHECK='TRUE';
      ALLOW_CONNECT='TRUE';
    'VSS'<409>:
      PIN_NUMBER='(0,0,0,0,0,0,0,0,0,0,0,0,0,0,0,0,0,0,0,0,0,0,0,0,0,0,0,CN2,0,0~
)';
      PINUSE='GROUND';
      NO_LOAD_CHECK='Both';
      NO_IO_CHECK='Both';
      NO_ASSERT_CHECK='TRUE';
      NO_DIR_CHECK='TRUE';
      ALLOW_CONNECT='TRUE';
    'VSS'<408>:
      PIN_NUMBER='(0,0,0,0,0,0,0,0,0,0,0,0,0,0,0,0,0,0,0,0,0,0,0,0,0,0,0,CN12,0,~
0)';
      PINUSE='GROUND';
      NO_LOAD_CHECK='Both';
      NO_IO_CHECK='Both';
      NO_ASSERT_CHECK='TRUE';
      NO_DIR_CHECK='TRUE';
      ALLOW_CONNECT='TRUE';
    'VSS'<407>:
      PIN_NUMBER='(0,0,0,0,0,0,0,0,0,0,0,0,0,0,0,0,0,0,0,0,0,0,0,0,0,0,0,H61,0,0~
)';
      PINUSE='GROUND';
      NO_LOAD_CHECK='Both';
      NO_IO_CHECK='Both';
      NO_ASSERT_CHECK='TRUE';
      NO_DIR_CHECK='TRUE';
      ALLOW_CONNECT='TRUE';
    'VSS'<406>:
      PIN_NUMBER='(0,0,0,0,0,0,0,0,0,0,0,0,0,0,0,0,0,0,0,0,0,0,0,0,0,0,0,CN26,0,~
0)';
      PINUSE='GROUND';
      NO_LOAD_CHECK='Both';
      NO_IO_CHECK='Both';
      NO_ASSERT_CHECK='TRUE';
      NO_DIR_CHECK='TRUE';
      ALLOW_CONNECT='TRUE';
    'VSS'<405>:
      PIN_NUMBER='(0,0,0,0,0,0,0,0,0,0,0,0,0,0,0,0,0,0,0,0,0,0,0,0,0,0,0,CN32,0,~
0)';
      PINUSE='GROUND';
      NO_LOAD_CHECK='Both';
      NO_IO_CHECK='Both';
      NO_ASSERT_CHECK='TRUE';
      NO_DIR_CHECK='TRUE';
      ALLOW_CONNECT='TRUE';
    'VSS'<404>:
      PIN_NUMBER='(0,0,0,0,0,0,0,0,0,0,0,0,0,0,0,0,0,0,0,0,0,0,0,0,0,0,0,CN60,0,~
0)';
      PINUSE='GROUND';
      NO_LOAD_CHECK='Both';
      NO_IO_CHECK='Both';
      NO_ASSERT_CHECK='TRUE';
      NO_DIR_CHECK='TRUE';
      ALLOW_CONNECT='TRUE';
    'VSS'<403>:
      PIN_NUMBER='(0,0,0,0,0,0,0,0,0,0,0,0,0,0,0,0,0,0,0,0,0,0,0,0,0,0,0,CN62,0,~
0)';
      PINUSE='GROUND';
      NO_LOAD_CHECK='Both';
      NO_IO_CHECK='Both';
      NO_ASSERT_CHECK='TRUE';
      NO_DIR_CHECK='TRUE';
      ALLOW_CONNECT='TRUE';
    'VSS'<402>:
      PIN_NUMBER='(0,0,0,0,0,0,0,0,0,0,0,0,0,0,0,0,0,0,0,0,0,0,0,0,0,0,0,CN68,0,~
0)';
      PINUSE='GROUND';
      NO_LOAD_CHECK='Both';
      NO_IO_CHECK='Both';
      NO_ASSERT_CHECK='TRUE';
      NO_DIR_CHECK='TRUE';
      ALLOW_CONNECT='TRUE';
    'VSS'<401>:
      PIN_NUMBER='(0,0,0,0,0,0,0,0,0,0,0,0,0,0,0,0,0,0,0,0,0,0,0,0,0,0,0,CN78,0,~
0)';
      PINUSE='GROUND';
      NO_LOAD_CHECK='Both';
      NO_IO_CHECK='Both';
      NO_ASSERT_CHECK='TRUE';
      NO_DIR_CHECK='TRUE';
      ALLOW_CONNECT='TRUE';
    'VSS'<400>:
      PIN_NUMBER='(0,0,0,0,0,0,0,0,0,0,0,0,0,0,0,0,0,0,0,0,0,0,0,0,0,0,0,CP1,0,0~
)';
      PINUSE='GROUND';
      NO_LOAD_CHECK='Both';
      NO_IO_CHECK='Both';
      NO_ASSERT_CHECK='TRUE';
      NO_DIR_CHECK='TRUE';
      ALLOW_CONNECT='TRUE';
    'VSS'<399>:
      PIN_NUMBER='(0,0,0,0,0,0,0,0,0,0,0,0,0,0,0,0,0,0,0,0,0,0,0,0,0,0,0,H59,0,0~
)';
      PINUSE='GROUND';
      NO_LOAD_CHECK='Both';
      NO_IO_CHECK='Both';
      NO_ASSERT_CHECK='TRUE';
      NO_DIR_CHECK='TRUE';
      ALLOW_CONNECT='TRUE';
    'VSS'<398>:
      PIN_NUMBER='(0,0,0,0,0,0,0,0,0,0,0,0,0,0,0,0,0,0,0,0,0,0,0,0,0,0,0,CP25,0,~
0)';
      PINUSE='GROUND';
      NO_LOAD_CHECK='Both';
      NO_IO_CHECK='Both';
      NO_ASSERT_CHECK='TRUE';
      NO_DIR_CHECK='TRUE';
      ALLOW_CONNECT='TRUE';
    'VSS'<397>:
      PIN_NUMBER='(0,0,0,0,0,0,0,0,0,0,0,0,0,0,0,0,0,0,0,0,0,0,0,0,0,0,0,CP59,0,~
0)';
      PINUSE='GROUND';
      NO_LOAD_CHECK='Both';
      NO_IO_CHECK='Both';
      NO_ASSERT_CHECK='TRUE';
      NO_DIR_CHECK='TRUE';
      ALLOW_CONNECT='TRUE';
    'VSS'<396>:
      PIN_NUMBER='(0,0,0,0,0,0,0,0,0,0,0,0,0,0,0,0,0,0,0,0,0,0,0,0,0,0,0,CP69,0,~
0)';
      PINUSE='GROUND';
      NO_LOAD_CHECK='Both';
      NO_IO_CHECK='Both';
      NO_ASSERT_CHECK='TRUE';
      NO_DIR_CHECK='TRUE';
      ALLOW_CONNECT='TRUE';
    'VSS'<395>:
      PIN_NUMBER='(0,0,0,0,0,0,0,0,0,0,0,0,0,0,0,0,0,0,0,0,0,0,0,0,0,0,0,CP73,0,~
0)';
      PINUSE='GROUND';
      NO_LOAD_CHECK='Both';
      NO_IO_CHECK='Both';
      NO_ASSERT_CHECK='TRUE';
      NO_DIR_CHECK='TRUE';
      ALLOW_CONNECT='TRUE';
    'VSS'<394>:
      PIN_NUMBER='(0,0,0,0,0,0,0,0,0,0,0,0,0,0,0,0,0,0,0,0,0,0,0,0,0,0,0,CP75,0,~
0)';
      PINUSE='GROUND';
      NO_LOAD_CHECK='Both';
      NO_IO_CHECK='Both';
      NO_ASSERT_CHECK='TRUE';
      NO_DIR_CHECK='TRUE';
      ALLOW_CONNECT='TRUE';
    'VSS'<393>:
      PIN_NUMBER='(0,0,0,0,0,0,0,0,0,0,0,0,0,0,0,0,0,0,0,0,0,0,0,0,0,0,0,CP81,0,~
0)';
      PINUSE='GROUND';
      NO_LOAD_CHECK='Both';
      NO_IO_CHECK='Both';
      NO_ASSERT_CHECK='TRUE';
      NO_DIR_CHECK='TRUE';
      ALLOW_CONNECT='TRUE';
    'VSS'<392>:
      PIN_NUMBER='(0,0,0,0,0,0,0,0,0,0,0,0,0,0,0,0,0,0,0,0,0,0,0,0,0,0,0,CP83,0,~
0)';
      PINUSE='GROUND';
      NO_LOAD_CHECK='Both';
      NO_IO_CHECK='Both';
      NO_ASSERT_CHECK='TRUE';
      NO_DIR_CHECK='TRUE';
      ALLOW_CONNECT='TRUE';
    'VSS'<391>:
      PIN_NUMBER='(0,0,0,0,0,0,0,0,0,0,0,0,0,0,0,0,0,0,0,0,0,0,0,0,0,0,0,CR6,0,0~
)';
      PINUSE='GROUND';
      NO_LOAD_CHECK='Both';
      NO_IO_CHECK='Both';
      NO_ASSERT_CHECK='TRUE';
      NO_DIR_CHECK='TRUE';
      ALLOW_CONNECT='TRUE';
    'VSS'<390>:
      PIN_NUMBER='(0,0,0,0,0,0,0,0,0,0,0,0,0,0,0,0,0,0,0,0,0,0,0,0,0,0,0,CR10,0,~
0)';
      PINUSE='GROUND';
      NO_LOAD_CHECK='Both';
      NO_IO_CHECK='Both';
      NO_ASSERT_CHECK='TRUE';
      NO_DIR_CHECK='TRUE';
      ALLOW_CONNECT='TRUE';
    'VSS'<389>:
      PIN_NUMBER='(0,0,0,0,0,0,0,0,0,0,0,0,0,0,0,0,0,0,0,0,0,0,0,0,0,0,0,CR22,0,~
0)';
      PINUSE='GROUND';
      NO_LOAD_CHECK='Both';
      NO_IO_CHECK='Both';
      NO_ASSERT_CHECK='TRUE';
      NO_DIR_CHECK='TRUE';
      ALLOW_CONNECT='TRUE';
    'VSS'<388>:
      PIN_NUMBER='(0,0,0,0,0,0,0,0,0,0,0,0,0,0,0,0,0,0,0,0,0,0,0,0,0,0,0,CR24,0,~
0)';
      PINUSE='GROUND';
      NO_LOAD_CHECK='Both';
      NO_IO_CHECK='Both';
      NO_ASSERT_CHECK='TRUE';
      NO_DIR_CHECK='TRUE';
      ALLOW_CONNECT='TRUE';
    'VSS'<387>:
      PIN_NUMBER='(0,0,0,0,0,0,0,0,0,0,0,0,0,0,0,0,0,0,0,0,0,0,0,0,0,0,0,CR32,0,~
0)';
      PINUSE='GROUND';
      NO_LOAD_CHECK='Both';
      NO_IO_CHECK='Both';
      NO_ASSERT_CHECK='TRUE';
      NO_DIR_CHECK='TRUE';
      ALLOW_CONNECT='TRUE';
    'VSS'<386>:
      PIN_NUMBER='(0,0,0,0,0,0,0,0,0,0,0,0,0,0,0,0,0,0,0,0,0,0,0,0,0,0,0,CR58,0,~
0)';
      PINUSE='GROUND';
      NO_LOAD_CHECK='Both';
      NO_IO_CHECK='Both';
      NO_ASSERT_CHECK='TRUE';
      NO_DIR_CHECK='TRUE';
      ALLOW_CONNECT='TRUE';
    'VSS'<385>:
      PIN_NUMBER='(0,0,0,0,0,0,0,0,0,0,0,0,0,0,0,0,0,0,0,0,0,0,0,0,0,0,0,CR62,0,~
0)';
      PINUSE='GROUND';
      NO_LOAD_CHECK='Both';
      NO_IO_CHECK='Both';
      NO_ASSERT_CHECK='TRUE';
      NO_DIR_CHECK='TRUE';
      ALLOW_CONNECT='TRUE';
    'VSS'<384>:
      PIN_NUMBER='(0,0,0,0,0,0,0,0,0,0,0,0,0,0,0,0,0,0,0,0,0,0,0,0,0,0,0,CR64,0,~
0)';
      PINUSE='GROUND';
      NO_LOAD_CHECK='Both';
      NO_IO_CHECK='Both';
      NO_ASSERT_CHECK='TRUE';
      NO_DIR_CHECK='TRUE';
      ALLOW_CONNECT='TRUE';
    'VSS'<383>:
      PIN_NUMBER='(0,0,0,0,0,0,0,0,0,0,0,0,0,0,0,0,0,0,0,0,0,0,0,0,0,0,0,CR66,0,~
0)';
      PINUSE='GROUND';
      NO_LOAD_CHECK='Both';
      NO_IO_CHECK='Both';
      NO_ASSERT_CHECK='TRUE';
      NO_DIR_CHECK='TRUE';
      ALLOW_CONNECT='TRUE';
    'VSS'<382>:
      PIN_NUMBER='(0,0,0,0,0,0,0,0,0,0,0,0,0,0,0,0,0,0,0,0,0,0,0,0,0,0,0,CR68,0,~
0)';
      PINUSE='GROUND';
      NO_LOAD_CHECK='Both';
      NO_IO_CHECK='Both';
      NO_ASSERT_CHECK='TRUE';
      NO_DIR_CHECK='TRUE';
      ALLOW_CONNECT='TRUE';
    'VSS'<381>:
      PIN_NUMBER='(0,0,0,0,0,0,0,0,0,0,0,0,0,0,0,0,0,0,0,0,0,0,0,0,0,0,0,CR78,0,~
0)';
      PINUSE='GROUND';
      NO_LOAD_CHECK='Both';
      NO_IO_CHECK='Both';
      NO_ASSERT_CHECK='TRUE';
      NO_DIR_CHECK='TRUE';
      ALLOW_CONNECT='TRUE';
    'VSS'<380>:
      PIN_NUMBER='(0,0,0,0,0,0,0,0,0,0,0,0,0,0,0,0,0,0,0,0,0,0,0,0,0,0,0,CR86,0,~
0)';
      PINUSE='GROUND';
      NO_LOAD_CHECK='Both';
      NO_IO_CHECK='Both';
      NO_ASSERT_CHECK='TRUE';
      NO_DIR_CHECK='TRUE';
      ALLOW_CONNECT='TRUE';
    'VSS'<379>:
      PIN_NUMBER='(0,0,0,0,0,0,0,0,0,0,0,0,0,0,0,0,0,0,0,0,0,0,0,0,0,0,0,H57,0,0~
)';
      PINUSE='GROUND';
      NO_LOAD_CHECK='Both';
      NO_IO_CHECK='Both';
      NO_ASSERT_CHECK='TRUE';
      NO_DIR_CHECK='TRUE';
      ALLOW_CONNECT='TRUE';
    'VSS'<378>:
      PIN_NUMBER='(0,0,0,0,0,0,0,0,0,0,0,0,0,0,0,0,0,0,0,0,0,0,0,0,0,0,0,CT13,0,~
0)';
      PINUSE='GROUND';
      NO_LOAD_CHECK='Both';
      NO_IO_CHECK='Both';
      NO_ASSERT_CHECK='TRUE';
      NO_DIR_CHECK='TRUE';
      ALLOW_CONNECT='TRUE';
    'VSS'<377>:
      PIN_NUMBER='(0,0,0,0,0,0,0,0,0,0,0,0,0,0,0,0,0,0,0,0,0,0,0,0,0,0,0,CT19,0,~
0)';
      PINUSE='GROUND';
      NO_LOAD_CHECK='Both';
      NO_IO_CHECK='Both';
      NO_ASSERT_CHECK='TRUE';
      NO_DIR_CHECK='TRUE';
      ALLOW_CONNECT='TRUE';
    'VSS'<376>:
      PIN_NUMBER='(0,0,0,0,0,0,0,0,0,0,0,0,0,0,0,0,0,0,0,0,0,0,0,0,0,0,0,CT27,0,~
0)';
      PINUSE='GROUND';
      NO_LOAD_CHECK='Both';
      NO_IO_CHECK='Both';
      NO_ASSERT_CHECK='TRUE';
      NO_DIR_CHECK='TRUE';
      ALLOW_CONNECT='TRUE';
    'VSS'<375>:
      PIN_NUMBER='(0,0,0,0,0,0,0,0,0,0,0,0,0,0,0,0,0,0,0,0,0,0,0,0,0,0,0,CT29,0,~
0)';
      PINUSE='GROUND';
      NO_LOAD_CHECK='Both';
      NO_IO_CHECK='Both';
      NO_ASSERT_CHECK='TRUE';
      NO_DIR_CHECK='TRUE';
      ALLOW_CONNECT='TRUE';
    'VSS'<374>:
      PIN_NUMBER='(0,0,0,0,0,0,0,0,0,0,0,0,0,0,0,0,0,0,0,0,0,0,0,0,0,0,0,CT33,0,~
0)';
      PINUSE='GROUND';
      NO_LOAD_CHECK='Both';
      NO_IO_CHECK='Both';
      NO_ASSERT_CHECK='TRUE';
      NO_DIR_CHECK='TRUE';
      ALLOW_CONNECT='TRUE';
    'VSS'<373>:
      PIN_NUMBER='(0,0,0,0,0,0,0,0,0,0,0,0,0,0,0,0,0,0,0,0,0,0,0,0,0,0,0,CT35,0,~
0)';
      PINUSE='GROUND';
      NO_LOAD_CHECK='Both';
      NO_IO_CHECK='Both';
      NO_ASSERT_CHECK='TRUE';
      NO_DIR_CHECK='TRUE';
      ALLOW_CONNECT='TRUE';
    'VSS'<372>:
      PIN_NUMBER='(0,0,0,0,0,0,0,0,0,0,0,0,0,0,0,0,0,0,0,0,0,0,0,0,0,0,0,CT57,0,~
0)';
      PINUSE='GROUND';
      NO_LOAD_CHECK='Both';
      NO_IO_CHECK='Both';
      NO_ASSERT_CHECK='TRUE';
      NO_DIR_CHECK='TRUE';
      ALLOW_CONNECT='TRUE';
    'VSS'<371>:
      PIN_NUMBER='(0,0,0,0,0,0,0,0,0,0,0,0,0,0,0,0,0,0,0,0,0,0,0,0,0,0,0,CT73,0,~
0)';
      PINUSE='GROUND';
      NO_LOAD_CHECK='Both';
      NO_IO_CHECK='Both';
      NO_ASSERT_CHECK='TRUE';
      NO_DIR_CHECK='TRUE';
      ALLOW_CONNECT='TRUE';
    'VSS'<370>:
      PIN_NUMBER='(0,0,0,0,0,0,0,0,0,0,0,0,0,0,0,0,0,0,0,0,0,0,0,0,0,0,0,CT79,0,~
0)';
      PINUSE='GROUND';
      NO_LOAD_CHECK='Both';
      NO_IO_CHECK='Both';
      NO_ASSERT_CHECK='TRUE';
      NO_DIR_CHECK='TRUE';
      ALLOW_CONNECT='TRUE';
    'VSS'<369>:
      PIN_NUMBER='(0,0,0,0,0,0,0,0,0,0,0,0,0,0,0,0,0,0,0,0,0,0,0,0,0,0,0,CT83,0,~
0)';
      PINUSE='GROUND';
      NO_LOAD_CHECK='Both';
      NO_IO_CHECK='Both';
      NO_ASSERT_CHECK='TRUE';
      NO_DIR_CHECK='TRUE';
      ALLOW_CONNECT='TRUE';
    'VSS'<368>:
      PIN_NUMBER='(0,0,0,0,0,0,0,0,0,0,0,0,0,0,0,0,0,0,0,0,0,0,0,0,0,0,0,CT85,0,~
0)';
      PINUSE='GROUND';
      NO_LOAD_CHECK='Both';
      NO_IO_CHECK='Both';
      NO_ASSERT_CHECK='TRUE';
      NO_DIR_CHECK='TRUE';
      ALLOW_CONNECT='TRUE';
    'VSS'<367>:
      PIN_NUMBER='(0,0,0,0,0,0,0,0,0,0,0,0,0,0,0,0,0,0,0,0,0,0,0,0,0,0,0,CU4,0,0~
)';
      PINUSE='GROUND';
      NO_LOAD_CHECK='Both';
      NO_IO_CHECK='Both';
      NO_ASSERT_CHECK='TRUE';
      NO_DIR_CHECK='TRUE';
      ALLOW_CONNECT='TRUE';
    'VSS'<366>:
      PIN_NUMBER='(0,0,0,0,0,0,0,0,0,0,0,0,0,0,0,0,0,0,0,0,0,0,0,0,0,0,0,CU22,0,~
0)';
      PINUSE='GROUND';
      NO_LOAD_CHECK='Both';
      NO_IO_CHECK='Both';
      NO_ASSERT_CHECK='TRUE';
      NO_DIR_CHECK='TRUE';
      ALLOW_CONNECT='TRUE';
    'VSS'<365>:
      PIN_NUMBER='(0,0,0,0,0,0,0,0,0,0,0,0,0,0,0,0,0,0,0,0,0,0,0,0,0,0,0,CU28,0,~
0)';
      PINUSE='GROUND';
      NO_LOAD_CHECK='Both';
      NO_IO_CHECK='Both';
      NO_ASSERT_CHECK='TRUE';
      NO_DIR_CHECK='TRUE';
      ALLOW_CONNECT='TRUE';
    'VSS'<364>:
      PIN_NUMBER='(0,0,0,0,0,0,0,0,0,0,0,0,0,0,0,0,0,0,0,0,0,0,0,0,0,0,0,CU30,0,~
0)';
      PINUSE='GROUND';
      NO_LOAD_CHECK='Both';
      NO_IO_CHECK='Both';
      NO_ASSERT_CHECK='TRUE';
      NO_DIR_CHECK='TRUE';
      ALLOW_CONNECT='TRUE';
    'VSS'<363>:
      PIN_NUMBER='(0,0,0,0,0,0,0,0,0,0,0,0,0,0,0,0,0,0,0,0,0,0,0,0,0,0,0,CU34,0,~
0)';
      PINUSE='GROUND';
      NO_LOAD_CHECK='Both';
      NO_IO_CHECK='Both';
      NO_ASSERT_CHECK='TRUE';
      NO_DIR_CHECK='TRUE';
      ALLOW_CONNECT='TRUE';
    'VSS'<362>:
      PIN_NUMBER='(0,0,0,0,0,0,0,0,0,0,0,0,0,0,0,0,0,0,0,0,0,0,0,0,0,0,0,CU36,0,~
0)';
      PINUSE='GROUND';
      NO_LOAD_CHECK='Both';
      NO_IO_CHECK='Both';
      NO_ASSERT_CHECK='TRUE';
      NO_DIR_CHECK='TRUE';
      ALLOW_CONNECT='TRUE';
    'VSS'<361>:
      PIN_NUMBER='(0,0,0,0,0,0,0,0,0,0,0,0,0,0,0,0,0,0,0,0,0,0,0,0,0,0,0,CU56,0,~
0)';
      PINUSE='GROUND';
      NO_LOAD_CHECK='Both';
      NO_IO_CHECK='Both';
      NO_ASSERT_CHECK='TRUE';
      NO_DIR_CHECK='TRUE';
      ALLOW_CONNECT='TRUE';
    'VSS'<360>:
      PIN_NUMBER='(0,0,0,0,0,0,0,0,0,0,0,0,0,0,0,0,0,0,0,0,0,0,0,0,0,0,0,CU62,0,~
0)';
      PINUSE='GROUND';
      NO_LOAD_CHECK='Both';
      NO_IO_CHECK='Both';
      NO_ASSERT_CHECK='TRUE';
      NO_DIR_CHECK='TRUE';
      ALLOW_CONNECT='TRUE';
    'VSS'<359>:
      PIN_NUMBER='(0,0,0,0,0,0,0,0,0,0,0,0,0,0,0,0,0,0,0,0,0,0,0,0,0,0,0,CU68,0,~
0)';
      PINUSE='GROUND';
      NO_LOAD_CHECK='Both';
      NO_IO_CHECK='Both';
      NO_ASSERT_CHECK='TRUE';
      NO_DIR_CHECK='TRUE';
      ALLOW_CONNECT='TRUE';
    'VSS'<358>:
      PIN_NUMBER='(0,0,0,0,0,0,0,0,0,0,0,0,0,0,0,0,0,0,0,0,0,0,0,0,0,0,0,CU76,0,~
0)';
      PINUSE='GROUND';
      NO_LOAD_CHECK='Both';
      NO_IO_CHECK='Both';
      NO_ASSERT_CHECK='TRUE';
      NO_DIR_CHECK='TRUE';
      ALLOW_CONNECT='TRUE';
    'VSS'<357>:
      PIN_NUMBER='(0,0,0,0,0,0,0,0,0,0,0,0,0,0,0,0,0,0,0,0,0,0,0,0,0,0,0,CU78,0,~
0)';
      PINUSE='GROUND';
      NO_LOAD_CHECK='Both';
      NO_IO_CHECK='Both';
      NO_ASSERT_CHECK='TRUE';
      NO_DIR_CHECK='TRUE';
      ALLOW_CONNECT='TRUE';
    'VSS'<356>:
      PIN_NUMBER='(0,0,0,0,0,0,0,0,0,0,0,0,0,0,0,0,0,0,0,0,0,0,0,0,0,0,0,CU80,0,~
0)';
      PINUSE='GROUND';
      NO_LOAD_CHECK='Both';
      NO_IO_CHECK='Both';
      NO_ASSERT_CHECK='TRUE';
      NO_DIR_CHECK='TRUE';
      ALLOW_CONNECT='TRUE';
    'VSS'<355>:
      PIN_NUMBER='(0,0,0,0,0,0,0,0,0,0,0,0,0,0,0,0,0,0,0,0,0,0,0,0,0,0,0,CU82,0,~
0)';
      PINUSE='GROUND';
      NO_LOAD_CHECK='Both';
      NO_IO_CHECK='Both';
      NO_ASSERT_CHECK='TRUE';
      NO_DIR_CHECK='TRUE';
      ALLOW_CONNECT='TRUE';
    'VSS'<354>:
      PIN_NUMBER='(0,0,0,0,0,0,0,0,0,0,0,0,0,0,0,0,0,0,0,0,0,0,0,0,0,0,0,CU86,0,~
0)';
      PINUSE='GROUND';
      NO_LOAD_CHECK='Both';
      NO_IO_CHECK='Both';
      NO_ASSERT_CHECK='TRUE';
      NO_DIR_CHECK='TRUE';
      ALLOW_CONNECT='TRUE';
    'VSS'<353>:
      PIN_NUMBER='(0,0,0,0,0,0,0,0,0,0,0,0,0,0,0,0,0,0,0,0,0,0,0,0,0,0,0,CV1,0,0~
)';
      PINUSE='GROUND';
      NO_LOAD_CHECK='Both';
      NO_IO_CHECK='Both';
      NO_ASSERT_CHECK='TRUE';
      NO_DIR_CHECK='TRUE';
      ALLOW_CONNECT='TRUE';
    'VSS'<352>:
      PIN_NUMBER='(0,0,0,0,0,0,0,0,0,0,0,0,0,0,0,0,0,0,0,0,0,0,0,0,0,0,0,H55,0,0~
)';
      PINUSE='GROUND';
      NO_LOAD_CHECK='Both';
      NO_IO_CHECK='Both';
      NO_ASSERT_CHECK='TRUE';
      NO_DIR_CHECK='TRUE';
      ALLOW_CONNECT='TRUE';
    'VSS'<351>:
      PIN_NUMBER='(0,0,0,0,0,0,0,0,0,0,0,0,0,0,0,0,0,0,0,0,0,0,0,0,0,0,0,CV17,0,~
0)';
      PINUSE='GROUND';
      NO_LOAD_CHECK='Both';
      NO_IO_CHECK='Both';
      NO_ASSERT_CHECK='TRUE';
      NO_DIR_CHECK='TRUE';
      ALLOW_CONNECT='TRUE';
    'VSS'<350>:
      PIN_NUMBER='(0,0,0,0,0,0,0,0,0,0,0,0,0,0,0,0,0,0,0,0,0,0,0,0,0,0,0,CV25,0,~
0)';
      PINUSE='GROUND';
      NO_LOAD_CHECK='Both';
      NO_IO_CHECK='Both';
      NO_ASSERT_CHECK='TRUE';
      NO_DIR_CHECK='TRUE';
      ALLOW_CONNECT='TRUE';
    'VSS'<349>:
      PIN_NUMBER='(0,0,0,0,0,0,0,0,0,0,0,0,0,0,0,0,0,0,0,0,0,0,0,0,0,0,0,CV27,0,~
0)';
      PINUSE='GROUND';
      NO_LOAD_CHECK='Both';
      NO_IO_CHECK='Both';
      NO_ASSERT_CHECK='TRUE';
      NO_DIR_CHECK='TRUE';
      ALLOW_CONNECT='TRUE';
    'VSS'<348>:
      PIN_NUMBER='(0,0,0,0,0,0,0,0,0,0,0,0,0,0,0,0,0,0,0,0,0,0,0,0,0,0,0,CV31,0,~
0)';
      PINUSE='GROUND';
      NO_LOAD_CHECK='Both';
      NO_IO_CHECK='Both';
      NO_ASSERT_CHECK='TRUE';
      NO_DIR_CHECK='TRUE';
      ALLOW_CONNECT='TRUE';
    'VSS'<347>:
      PIN_NUMBER='(0,0,0,0,0,0,0,0,0,0,0,0,0,0,0,0,0,0,0,0,0,0,0,0,0,0,0,CV33,0,~
0)';
      PINUSE='GROUND';
      NO_LOAD_CHECK='Both';
      NO_IO_CHECK='Both';
      NO_ASSERT_CHECK='TRUE';
      NO_DIR_CHECK='TRUE';
      ALLOW_CONNECT='TRUE';
    'VSS'<346>:
      PIN_NUMBER='(0,0,0,0,0,0,0,0,0,0,0,0,0,0,0,0,0,0,0,0,0,0,0,0,0,0,0,CV37,0,~
0)';
      PINUSE='GROUND';
      NO_LOAD_CHECK='Both';
      NO_IO_CHECK='Both';
      NO_ASSERT_CHECK='TRUE';
      NO_DIR_CHECK='TRUE';
      ALLOW_CONNECT='TRUE';
    'VSS'<345>:
      PIN_NUMBER='(0,0,0,0,0,0,0,0,0,0,0,0,0,0,0,0,0,0,0,0,0,0,0,0,0,0,0,CV39,0,~
0)';
      PINUSE='GROUND';
      NO_LOAD_CHECK='Both';
      NO_IO_CHECK='Both';
      NO_ASSERT_CHECK='TRUE';
      NO_DIR_CHECK='TRUE';
      ALLOW_CONNECT='TRUE';
    'VSS'<344>:
      PIN_NUMBER='(0,0,0,0,0,0,0,0,0,0,0,0,0,0,0,0,0,0,0,0,0,0,0,0,0,0,0,CV41,0,~
0)';
      PINUSE='GROUND';
      NO_LOAD_CHECK='Both';
      NO_IO_CHECK='Both';
      NO_ASSERT_CHECK='TRUE';
      NO_DIR_CHECK='TRUE';
      ALLOW_CONNECT='TRUE';
    'VSS'<343>:
      PIN_NUMBER='(0,0,0,0,0,0,0,0,0,0,0,0,0,0,0,0,0,0,0,0,0,0,0,0,0,0,0,CV53,0,~
0)';
      PINUSE='GROUND';
      NO_LOAD_CHECK='Both';
      NO_IO_CHECK='Both';
      NO_ASSERT_CHECK='TRUE';
      NO_DIR_CHECK='TRUE';
      ALLOW_CONNECT='TRUE';
    'VSS'<342>:
      PIN_NUMBER='(0,0,0,0,0,0,0,0,0,0,0,0,0,0,0,0,0,0,0,0,0,0,0,0,0,0,0,CV55,0,~
0)';
      PINUSE='GROUND';
      NO_LOAD_CHECK='Both';
      NO_IO_CHECK='Both';
      NO_ASSERT_CHECK='TRUE';
      NO_DIR_CHECK='TRUE';
      ALLOW_CONNECT='TRUE';
    'VSS'<341>:
      PIN_NUMBER='(0,0,0,0,0,0,0,0,0,0,0,0,0,0,0,0,0,0,0,0,0,0,0,0,0,0,0,CV63,0,~
0)';
      PINUSE='GROUND';
      NO_LOAD_CHECK='Both';
      NO_IO_CHECK='Both';
      NO_ASSERT_CHECK='TRUE';
      NO_DIR_CHECK='TRUE';
      ALLOW_CONNECT='TRUE';
    'VSS'<340>:
      PIN_NUMBER='(0,0,0,0,0,0,0,0,0,0,0,0,0,0,0,0,0,0,0,0,0,0,0,0,0,0,0,CV67,0,~
0)';
      PINUSE='GROUND';
      NO_LOAD_CHECK='Both';
      NO_IO_CHECK='Both';
      NO_ASSERT_CHECK='TRUE';
      NO_DIR_CHECK='TRUE';
      ALLOW_CONNECT='TRUE';
    'VSS'<339>:
      PIN_NUMBER='(0,0,0,0,0,0,0,0,0,0,0,0,0,0,0,0,0,0,0,0,0,0,0,0,0,0,0,CV73,0,~
0)';
      PINUSE='GROUND';
      NO_LOAD_CHECK='Both';
      NO_IO_CHECK='Both';
      NO_ASSERT_CHECK='TRUE';
      NO_DIR_CHECK='TRUE';
      ALLOW_CONNECT='TRUE';
    'VSS'<338>:
      PIN_NUMBER='(0,0,0,0,0,0,0,0,0,0,0,0,0,0,0,0,0,0,0,0,0,0,0,0,0,0,0,CV79,0,~
0)';
      PINUSE='GROUND';
      NO_LOAD_CHECK='Both';
      NO_IO_CHECK='Both';
      NO_ASSERT_CHECK='TRUE';
      NO_DIR_CHECK='TRUE';
      ALLOW_CONNECT='TRUE';
    'VSS'<337>:
      PIN_NUMBER='(0,0,0,0,0,0,0,0,0,0,0,0,0,0,0,0,0,0,0,0,0,0,0,0,0,0,0,CV81,0,~
0)';
      PINUSE='GROUND';
      NO_LOAD_CHECK='Both';
      NO_IO_CHECK='Both';
      NO_ASSERT_CHECK='TRUE';
      NO_DIR_CHECK='TRUE';
      ALLOW_CONNECT='TRUE';
    'VSS'<336>:
      PIN_NUMBER='(0,0,0,0,0,0,0,0,0,0,0,0,0,0,0,0,0,0,0,0,0,0,0,0,0,0,0,CV83,0,~
0)';
      PINUSE='GROUND';
      NO_LOAD_CHECK='Both';
      NO_IO_CHECK='Both';
      NO_ASSERT_CHECK='TRUE';
      NO_DIR_CHECK='TRUE';
      ALLOW_CONNECT='TRUE';
    'VSS'<335>:
      PIN_NUMBER='(0,0,0,0,0,0,0,0,0,0,0,0,0,0,0,0,0,0,0,0,0,0,0,0,0,0,0,CW12,0,~
0)';
      PINUSE='GROUND';
      NO_LOAD_CHECK='Both';
      NO_IO_CHECK='Both';
      NO_ASSERT_CHECK='TRUE';
      NO_DIR_CHECK='TRUE';
      ALLOW_CONNECT='TRUE';
    'VSS'<334>:
      PIN_NUMBER='(0,0,0,0,0,0,0,0,0,0,0,0,0,0,0,0,0,0,0,0,0,0,0,0,0,0,0,CW26,0,~
0)';
      PINUSE='GROUND';
      NO_LOAD_CHECK='Both';
      NO_IO_CHECK='Both';
      NO_ASSERT_CHECK='TRUE';
      NO_DIR_CHECK='TRUE';
      ALLOW_CONNECT='TRUE';
    'VSS'<333>:
      PIN_NUMBER='(0,0,0,0,0,0,0,0,0,0,0,0,0,0,0,0,0,0,0,0,0,0,0,0,0,0,0,CW32,0,~
0)';
      PINUSE='GROUND';
      NO_LOAD_CHECK='Both';
      NO_IO_CHECK='Both';
      NO_ASSERT_CHECK='TRUE';
      NO_DIR_CHECK='TRUE';
      ALLOW_CONNECT='TRUE';
    'VSS'<332>:
      PIN_NUMBER='(0,0,0,0,0,0,0,0,0,0,0,0,0,0,0,0,0,0,0,0,0,0,0,0,0,0,0,CW38,0,~
0)';
      PINUSE='GROUND';
      NO_LOAD_CHECK='Both';
      NO_IO_CHECK='Both';
      NO_ASSERT_CHECK='TRUE';
      NO_DIR_CHECK='TRUE';
      ALLOW_CONNECT='TRUE';
    'VSS'<331>:
      PIN_NUMBER='(0,0,0,0,0,0,0,0,0,0,0,0,0,0,0,0,0,0,0,0,0,0,0,0,0,0,0,CW40,0,~
0)';
      PINUSE='GROUND';
      NO_LOAD_CHECK='Both';
      NO_IO_CHECK='Both';
      NO_ASSERT_CHECK='TRUE';
      NO_DIR_CHECK='TRUE';
      ALLOW_CONNECT='TRUE';
    'VSS'<330>:
      PIN_NUMBER='(0,0,0,0,0,0,0,0,0,0,0,0,0,0,0,0,0,0,0,0,0,0,0,0,0,0,0,CW42,0,~
0)';
      PINUSE='GROUND';
      NO_LOAD_CHECK='Both';
      NO_IO_CHECK='Both';
      NO_ASSERT_CHECK='TRUE';
      NO_DIR_CHECK='TRUE';
      ALLOW_CONNECT='TRUE';
    'VSS'<329>:
      PIN_NUMBER='(0,0,0,0,0,0,0,0,0,0,0,0,0,0,0,0,0,0,0,0,0,0,0,0,0,0,0,CW52,0,~
0)';
      PINUSE='GROUND';
      NO_LOAD_CHECK='Both';
      NO_IO_CHECK='Both';
      NO_ASSERT_CHECK='TRUE';
      NO_DIR_CHECK='TRUE';
      ALLOW_CONNECT='TRUE';
    'VSS'<328>:
      PIN_NUMBER='(0,0,0,0,0,0,0,0,0,0,0,0,0,0,0,0,0,0,0,0,0,0,0,0,0,0,0,CW54,0,~
0)';
      PINUSE='GROUND';
      NO_LOAD_CHECK='Both';
      NO_IO_CHECK='Both';
      NO_ASSERT_CHECK='TRUE';
      NO_DIR_CHECK='TRUE';
      ALLOW_CONNECT='TRUE';
    'VSS'<327>:
      PIN_NUMBER='(0,0,0,0,0,0,0,0,0,0,0,0,0,0,0,0,0,0,0,0,0,0,0,0,0,0,0,CW64,0,~
0)';
      PINUSE='GROUND';
      NO_LOAD_CHECK='Both';
      NO_IO_CHECK='Both';
      NO_ASSERT_CHECK='TRUE';
      NO_DIR_CHECK='TRUE';
      ALLOW_CONNECT='TRUE';
    'VSS'<326>:
      PIN_NUMBER='(0,0,0,0,0,0,0,0,0,0,0,0,0,0,0,0,0,0,0,0,0,0,0,0,0,0,0,CW66,0,~
0)';
      PINUSE='GROUND';
      NO_LOAD_CHECK='Both';
      NO_IO_CHECK='Both';
      NO_ASSERT_CHECK='TRUE';
      NO_DIR_CHECK='TRUE';
      ALLOW_CONNECT='TRUE';
    'VSS'<325>:
      PIN_NUMBER='(0,0,0,0,0,0,0,0,0,0,0,0,0,0,0,0,0,0,0,0,0,0,0,0,0,0,0,CW68,0,~
0)';
      PINUSE='GROUND';
      NO_LOAD_CHECK='Both';
      NO_IO_CHECK='Both';
      NO_ASSERT_CHECK='TRUE';
      NO_DIR_CHECK='TRUE';
      ALLOW_CONNECT='TRUE';
    'VSS'<324>:
      PIN_NUMBER='(0,0,0,0,0,0,0,0,0,0,0,0,0,0,0,0,0,0,0,0,0,0,0,0,0,0,0,CW74,0,~
0)';
      PINUSE='GROUND';
      NO_LOAD_CHECK='Both';
      NO_IO_CHECK='Both';
      NO_ASSERT_CHECK='TRUE';
      NO_DIR_CHECK='TRUE';
      ALLOW_CONNECT='TRUE';
    'VSS'<323>:
      PIN_NUMBER='(0,0,0,0,0,0,0,0,0,0,0,0,0,0,0,0,0,0,0,0,0,0,0,0,0,0,0,CW78,0,~
0)';
      PINUSE='GROUND';
      NO_LOAD_CHECK='Both';
      NO_IO_CHECK='Both';
      NO_ASSERT_CHECK='TRUE';
      NO_DIR_CHECK='TRUE';
      ALLOW_CONNECT='TRUE';
    'VSS'<322>:
      PIN_NUMBER='(0,0,0,0,0,0,0,0,0,0,0,0,0,0,0,0,0,0,0,0,0,0,0,0,0,0,0,CW82,0,~
0)';
      PINUSE='GROUND';
      NO_LOAD_CHECK='Both';
      NO_IO_CHECK='Both';
      NO_ASSERT_CHECK='TRUE';
      NO_DIR_CHECK='TRUE';
      ALLOW_CONNECT='TRUE';
    'VSS'<321>:
      PIN_NUMBER='(0,0,0,0,0,0,0,0,0,0,0,0,0,0,0,0,0,0,0,0,0,0,0,0,0,0,0,CY1,0,0~
)';
      PINUSE='GROUND';
      NO_LOAD_CHECK='Both';
      NO_IO_CHECK='Both';
      NO_ASSERT_CHECK='TRUE';
      NO_DIR_CHECK='TRUE';
      ALLOW_CONNECT='TRUE';
    'VSS'<320>:
      PIN_NUMBER='(0,0,0,0,0,0,0,0,0,0,0,0,0,0,0,0,0,0,0,0,0,0,0,0,0,0,0,CY9,0,0~
)';
      PINUSE='GROUND';
      NO_LOAD_CHECK='Both';
      NO_IO_CHECK='Both';
      NO_ASSERT_CHECK='TRUE';
      NO_DIR_CHECK='TRUE';
      ALLOW_CONNECT='TRUE';
    'VSS'<319>:
      PIN_NUMBER='(0,0,0,0,0,0,0,0,0,0,0,0,0,0,0,0,0,0,0,0,0,0,0,0,0,0,0,CY13,0,~
0)';
      PINUSE='GROUND';
      NO_LOAD_CHECK='Both';
      NO_IO_CHECK='Both';
      NO_ASSERT_CHECK='TRUE';
      NO_DIR_CHECK='TRUE';
      ALLOW_CONNECT='TRUE';
    'VSS'<318>:
      PIN_NUMBER='(0,0,0,0,0,0,0,0,0,0,0,0,0,0,0,0,0,0,0,0,0,0,0,0,0,0,0,CY15,0,~
0)';
      PINUSE='GROUND';
      NO_LOAD_CHECK='Both';
      NO_IO_CHECK='Both';
      NO_ASSERT_CHECK='TRUE';
      NO_DIR_CHECK='TRUE';
      ALLOW_CONNECT='TRUE';
    'VSS'<317>:
      PIN_NUMBER='(0,0,0,0,0,0,0,0,0,0,0,0,0,0,0,0,0,0,0,0,0,0,0,0,0,0,0,CY21,0,~
0)';
      PINUSE='GROUND';
      NO_LOAD_CHECK='Both';
      NO_IO_CHECK='Both';
      NO_ASSERT_CHECK='TRUE';
      NO_DIR_CHECK='TRUE';
      ALLOW_CONNECT='TRUE';
    'VSS'<316>:
      PIN_NUMBER='(0,0,0,0,0,0,0,0,0,0,0,0,0,0,0,0,0,0,0,0,0,0,0,0,0,0,0,CY41,0,~
0)';
      PINUSE='GROUND';
      NO_LOAD_CHECK='Both';
      NO_IO_CHECK='Both';
      NO_ASSERT_CHECK='TRUE';
      NO_DIR_CHECK='TRUE';
      ALLOW_CONNECT='TRUE';
    'VSS'<315>:
      PIN_NUMBER='(0,0,0,0,0,0,0,0,0,0,0,0,0,0,0,0,0,0,0,0,0,0,0,0,0,0,0,CY45,0,~
0)';
      PINUSE='GROUND';
      NO_LOAD_CHECK='Both';
      NO_IO_CHECK='Both';
      NO_ASSERT_CHECK='TRUE';
      NO_DIR_CHECK='TRUE';
      ALLOW_CONNECT='TRUE';
    'VSS'<314>:
      PIN_NUMBER='(0,0,0,0,0,0,0,0,0,0,0,0,0,0,0,0,0,0,0,0,0,0,0,0,0,0,0,CY51,0,~
0)';
      PINUSE='GROUND';
      NO_LOAD_CHECK='Both';
      NO_IO_CHECK='Both';
      NO_ASSERT_CHECK='TRUE';
      NO_DIR_CHECK='TRUE';
      ALLOW_CONNECT='TRUE';
    'VSS'<313>:
      PIN_NUMBER='(0,0,0,0,0,0,0,0,0,0,0,0,0,0,0,0,0,0,0,0,0,0,0,0,0,0,0,CY59,0,~
0)';
      PINUSE='GROUND';
      NO_LOAD_CHECK='Both';
      NO_IO_CHECK='Both';
      NO_ASSERT_CHECK='TRUE';
      NO_DIR_CHECK='TRUE';
      ALLOW_CONNECT='TRUE';
    'VSS'<312>:
      PIN_NUMBER='(0,0,0,0,0,0,0,0,0,0,0,0,0,0,0,0,0,0,0,0,0,0,0,0,0,0,0,CY61,0,~
0)';
      PINUSE='GROUND';
      NO_LOAD_CHECK='Both';
      NO_IO_CHECK='Both';
      NO_ASSERT_CHECK='TRUE';
      NO_DIR_CHECK='TRUE';
      ALLOW_CONNECT='TRUE';
    'VSS'<311>:
      PIN_NUMBER='(0,0,0,0,0,0,0,0,0,0,0,0,0,0,0,0,0,0,0,0,0,0,0,0,0,0,0,CY65,0,~
0)';
      PINUSE='GROUND';
      NO_LOAD_CHECK='Both';
      NO_IO_CHECK='Both';
      NO_ASSERT_CHECK='TRUE';
      NO_DIR_CHECK='TRUE';
      ALLOW_CONNECT='TRUE';
    'VSS'<310>:
      PIN_NUMBER='(0,0,0,0,0,0,0,0,0,0,0,0,0,0,0,0,0,0,0,0,0,0,0,0,0,0,0,CY69,0,~
0)';
      PINUSE='GROUND';
      NO_LOAD_CHECK='Both';
      NO_IO_CHECK='Both';
      NO_ASSERT_CHECK='TRUE';
      NO_DIR_CHECK='TRUE';
      ALLOW_CONNECT='TRUE';
    'VSS'<309>:
      PIN_NUMBER='(0,0,0,0,0,0,0,0,0,0,0,0,0,0,0,0,0,0,0,0,0,0,0,0,0,0,0,CY75,0,~
0)';
      PINUSE='GROUND';
      NO_LOAD_CHECK='Both';
      NO_IO_CHECK='Both';
      NO_ASSERT_CHECK='TRUE';
      NO_DIR_CHECK='TRUE';
      ALLOW_CONNECT='TRUE';
    'VSS'<308>:
      PIN_NUMBER='(0,0,0,0,0,0,0,0,0,0,0,0,0,0,0,0,0,0,0,0,0,0,0,0,0,0,0,CY77,0,~
0)';
      PINUSE='GROUND';
      NO_LOAD_CHECK='Both';
      NO_IO_CHECK='Both';
      NO_ASSERT_CHECK='TRUE';
      NO_DIR_CHECK='TRUE';
      ALLOW_CONNECT='TRUE';
    'VSS'<307>:
      PIN_NUMBER='(0,0,0,0,0,0,0,0,0,0,0,0,0,0,0,0,0,0,0,0,0,0,0,0,0,0,0,CY83,0,~
0)';
      PINUSE='GROUND';
      NO_LOAD_CHECK='Both';
      NO_IO_CHECK='Both';
      NO_ASSERT_CHECK='TRUE';
      NO_DIR_CHECK='TRUE';
      ALLOW_CONNECT='TRUE';
    'VSS'<306>:
      PIN_NUMBER='(0,0,0,0,0,0,0,0,0,0,0,0,0,0,0,0,0,0,0,0,0,0,0,0,0,0,0,CY85,0,~
0)';
      PINUSE='GROUND';
      NO_LOAD_CHECK='Both';
      NO_IO_CHECK='Both';
      NO_ASSERT_CHECK='TRUE';
      NO_DIR_CHECK='TRUE';
      ALLOW_CONNECT='TRUE';
    'VSS'<305>:
      PIN_NUMBER='(0,0,0,0,0,0,0,0,0,0,0,0,0,0,0,0,0,0,0,0,0,0,0,0,0,0,0,DA6,0,0~
)';
      PINUSE='GROUND';
      NO_LOAD_CHECK='Both';
      NO_IO_CHECK='Both';
      NO_ASSERT_CHECK='TRUE';
      NO_DIR_CHECK='TRUE';
      ALLOW_CONNECT='TRUE';
    'VSS'<304>:
      PIN_NUMBER='(0,0,0,0,0,0,0,0,0,0,0,0,0,0,0,0,0,0,0,0,0,0,0,0,0,0,0,H53,0,0~
)';
      PINUSE='GROUND';
      NO_LOAD_CHECK='Both';
      NO_IO_CHECK='Both';
      NO_ASSERT_CHECK='TRUE';
      NO_DIR_CHECK='TRUE';
      ALLOW_CONNECT='TRUE';
    'VSS'<303>:
      PIN_NUMBER='(0,0,0,0,0,0,0,0,0,0,0,0,0,0,0,0,0,0,0,0,0,0,0,0,0,0,0,DA18,0,~
0)';
      PINUSE='GROUND';
      NO_LOAD_CHECK='Both';
      NO_IO_CHECK='Both';
      NO_ASSERT_CHECK='TRUE';
      NO_DIR_CHECK='TRUE';
      ALLOW_CONNECT='TRUE';
    'VSS'<302>:
      PIN_NUMBER='(0,0,0,0,0,0,0,0,0,0,0,0,0,0,0,0,0,0,0,0,0,0,0,0,0,0,0,DA26,0,~
0)';
      PINUSE='GROUND';
      NO_LOAD_CHECK='Both';
      NO_IO_CHECK='Both';
      NO_ASSERT_CHECK='TRUE';
      NO_DIR_CHECK='TRUE';
      ALLOW_CONNECT='TRUE';
    'VSS'<301>:
      PIN_NUMBER='(0,0,0,0,0,0,0,0,0,0,0,0,0,0,0,0,0,0,0,0,0,0,0,0,0,0,0,DA28,0,~
0)';
      PINUSE='GROUND';
      NO_LOAD_CHECK='Both';
      NO_IO_CHECK='Both';
      NO_ASSERT_CHECK='TRUE';
      NO_DIR_CHECK='TRUE';
      ALLOW_CONNECT='TRUE';
    'VSS'<300>:
      PIN_NUMBER='(0,0,0,0,0,0,0,0,0,0,0,0,0,0,0,0,0,0,0,0,0,0,0,0,0,0,0,DA30,0,~
0)';
      PINUSE='GROUND';
      NO_LOAD_CHECK='Both';
      NO_IO_CHECK='Both';
      NO_ASSERT_CHECK='TRUE';
      NO_DIR_CHECK='TRUE';
      ALLOW_CONNECT='TRUE';
    'VSS'<299>:
      PIN_NUMBER='(0,0,0,0,0,0,0,0,0,0,0,0,0,0,0,0,0,0,0,0,0,0,0,0,0,0,0,DA32,0,~
0)';
      PINUSE='GROUND';
      NO_LOAD_CHECK='Both';
      NO_IO_CHECK='Both';
      NO_ASSERT_CHECK='TRUE';
      NO_DIR_CHECK='TRUE';
      ALLOW_CONNECT='TRUE';
    'VSS'<298>:
      PIN_NUMBER='(0,0,0,0,0,0,0,0,0,0,0,0,0,0,0,0,0,0,0,0,0,0,0,0,0,0,0,DA34,0,~
0)';
      PINUSE='GROUND';
      NO_LOAD_CHECK='Both';
      NO_IO_CHECK='Both';
      NO_ASSERT_CHECK='TRUE';
      NO_DIR_CHECK='TRUE';
      ALLOW_CONNECT='TRUE';
    'VSS'<297>:
      PIN_NUMBER='(0,0,0,0,0,0,0,0,0,0,0,0,0,0,0,0,0,0,0,0,0,0,0,0,0,0,0,DA36,0,~
0)';
      PINUSE='GROUND';
      NO_LOAD_CHECK='Both';
      NO_IO_CHECK='Both';
      NO_ASSERT_CHECK='TRUE';
      NO_DIR_CHECK='TRUE';
      ALLOW_CONNECT='TRUE';
    'VSS'<296>:
      PIN_NUMBER='(0,0,0,0,0,0,0,0,0,0,0,0,0,0,0,0,0,0,0,0,0,0,0,0,0,0,0,DA38,0,~
0)';
      PINUSE='GROUND';
      NO_LOAD_CHECK='Both';
      NO_IO_CHECK='Both';
      NO_ASSERT_CHECK='TRUE';
      NO_DIR_CHECK='TRUE';
      ALLOW_CONNECT='TRUE';
    'VSS'<295>:
      PIN_NUMBER='(0,0,0,0,0,0,0,0,0,0,0,0,0,0,0,0,0,0,0,0,0,0,0,0,0,0,0,DA44,0,~
0)';
      PINUSE='GROUND';
      NO_LOAD_CHECK='Both';
      NO_IO_CHECK='Both';
      NO_ASSERT_CHECK='TRUE';
      NO_DIR_CHECK='TRUE';
      ALLOW_CONNECT='TRUE';
    'VSS'<294>:
      PIN_NUMBER='(0,0,0,0,0,0,0,0,0,0,0,0,0,0,0,0,0,0,0,0,0,0,0,0,0,0,0,DA46,0,~
0)';
      PINUSE='GROUND';
      NO_LOAD_CHECK='Both';
      NO_IO_CHECK='Both';
      NO_ASSERT_CHECK='TRUE';
      NO_DIR_CHECK='TRUE';
      ALLOW_CONNECT='TRUE';
    'VSS'<293>:
      PIN_NUMBER='(0,0,0,0,0,0,0,0,0,0,0,0,0,0,0,0,0,0,0,0,0,0,0,0,0,0,0,0,DA48,~
0)';
      PINUSE='GROUND';
      NO_LOAD_CHECK='Both';
      NO_IO_CHECK='Both';
      NO_ASSERT_CHECK='TRUE';
      NO_DIR_CHECK='TRUE';
      ALLOW_CONNECT='TRUE';
    'VSS'<292>:
      PIN_NUMBER='(0,0,0,0,0,0,0,0,0,0,0,0,0,0,0,0,0,0,0,0,0,0,0,0,0,0,0,0,DA50,~
0)';
      PINUSE='GROUND';
      NO_LOAD_CHECK='Both';
      NO_IO_CHECK='Both';
      NO_ASSERT_CHECK='TRUE';
      NO_DIR_CHECK='TRUE';
      ALLOW_CONNECT='TRUE';
    'VSS'<291>:
      PIN_NUMBER='(0,0,0,0,0,0,0,0,0,0,0,0,0,0,0,0,0,0,0,0,0,0,0,0,0,0,0,0,DA64,~
0)';
      PINUSE='GROUND';
      NO_LOAD_CHECK='Both';
      NO_IO_CHECK='Both';
      NO_ASSERT_CHECK='TRUE';
      NO_DIR_CHECK='TRUE';
      ALLOW_CONNECT='TRUE';
    'VSS'<290>:
      PIN_NUMBER='(0,0,0,0,0,0,0,0,0,0,0,0,0,0,0,0,0,0,0,0,0,0,0,0,0,0,0,0,DA70,~
0)';
      PINUSE='GROUND';
      NO_LOAD_CHECK='Both';
      NO_IO_CHECK='Both';
      NO_ASSERT_CHECK='TRUE';
      NO_DIR_CHECK='TRUE';
      ALLOW_CONNECT='TRUE';
    'VSS'<289>:
      PIN_NUMBER='(0,0,0,0,0,0,0,0,0,0,0,0,0,0,0,0,0,0,0,0,0,0,0,0,0,0,0,0,DA74,~
0)';
      PINUSE='GROUND';
      NO_LOAD_CHECK='Both';
      NO_IO_CHECK='Both';
      NO_ASSERT_CHECK='TRUE';
      NO_DIR_CHECK='TRUE';
      ALLOW_CONNECT='TRUE';
    'VSS'<288>:
      PIN_NUMBER='(0,0,0,0,0,0,0,0,0,0,0,0,0,0,0,0,0,0,0,0,0,0,0,0,0,0,0,0,DA76,~
0)';
      PINUSE='GROUND';
      NO_LOAD_CHECK='Both';
      NO_IO_CHECK='Both';
      NO_ASSERT_CHECK='TRUE';
      NO_DIR_CHECK='TRUE';
      ALLOW_CONNECT='TRUE';
    'VSS'<287>:
      PIN_NUMBER='(0,0,0,0,0,0,0,0,0,0,0,0,0,0,0,0,0,0,0,0,0,0,0,0,0,0,0,0,DA78,~
0)';
      PINUSE='GROUND';
      NO_LOAD_CHECK='Both';
      NO_IO_CHECK='Both';
      NO_ASSERT_CHECK='TRUE';
      NO_DIR_CHECK='TRUE';
      ALLOW_CONNECT='TRUE';
    'VSS'<286>:
      PIN_NUMBER='(0,0,0,0,0,0,0,0,0,0,0,0,0,0,0,0,0,0,0,0,0,0,0,0,0,0,0,0,DA80,~
0)';
      PINUSE='GROUND';
      NO_LOAD_CHECK='Both';
      NO_IO_CHECK='Both';
      NO_ASSERT_CHECK='TRUE';
      NO_DIR_CHECK='TRUE';
      ALLOW_CONNECT='TRUE';
    'VSS'<285>:
      PIN_NUMBER='(0,0,0,0,0,0,0,0,0,0,0,0,0,0,0,0,0,0,0,0,0,0,0,0,0,0,0,0,DB3,0~
)';
      PINUSE='GROUND';
      NO_LOAD_CHECK='Both';
      NO_IO_CHECK='Both';
      NO_ASSERT_CHECK='TRUE';
      NO_DIR_CHECK='TRUE';
      ALLOW_CONNECT='TRUE';
    'VSS'<284>:
      PIN_NUMBER='(0,0,0,0,0,0,0,0,0,0,0,0,0,0,0,0,0,0,0,0,0,0,0,0,0,0,0,0,DB13,~
0)';
      PINUSE='GROUND';
      NO_LOAD_CHECK='Both';
      NO_IO_CHECK='Both';
      NO_ASSERT_CHECK='TRUE';
      NO_DIR_CHECK='TRUE';
      ALLOW_CONNECT='TRUE';
    'VSS'<283>:
      PIN_NUMBER='(0,0,0,0,0,0,0,0,0,0,0,0,0,0,0,0,0,0,0,0,0,0,0,0,0,0,0,0,DB17,~
0)';
      PINUSE='GROUND';
      NO_LOAD_CHECK='Both';
      NO_IO_CHECK='Both';
      NO_ASSERT_CHECK='TRUE';
      NO_DIR_CHECK='TRUE';
      ALLOW_CONNECT='TRUE';
    'VSS'<282>:
      PIN_NUMBER='(0,0,0,0,0,0,0,0,0,0,0,0,0,0,0,0,0,0,0,0,0,0,0,0,0,0,0,0,DB23,~
0)';
      PINUSE='GROUND';
      NO_LOAD_CHECK='Both';
      NO_IO_CHECK='Both';
      NO_ASSERT_CHECK='TRUE';
      NO_DIR_CHECK='TRUE';
      ALLOW_CONNECT='TRUE';
    'VSS'<281>:
      PIN_NUMBER='(0,0,0,0,0,0,0,0,0,0,0,0,0,0,0,0,0,0,0,0,0,0,0,0,0,0,0,0,DB25,~
0)';
      PINUSE='GROUND';
      NO_LOAD_CHECK='Both';
      NO_IO_CHECK='Both';
      NO_ASSERT_CHECK='TRUE';
      NO_DIR_CHECK='TRUE';
      ALLOW_CONNECT='TRUE';
    'VSS'<280>:
      PIN_NUMBER='(0,0,0,0,0,0,0,0,0,0,0,0,0,0,0,0,0,0,0,0,0,0,0,0,0,0,0,0,DB39,~
0)';
      PINUSE='GROUND';
      NO_LOAD_CHECK='Both';
      NO_IO_CHECK='Both';
      NO_ASSERT_CHECK='TRUE';
      NO_DIR_CHECK='TRUE';
      ALLOW_CONNECT='TRUE';
    'VSS'<279>:
      PIN_NUMBER='(0,0,0,0,0,0,0,0,0,0,0,0,0,0,0,0,0,0,0,0,0,0,0,0,0,0,0,0,DB41,~
0)';
      PINUSE='GROUND';
      NO_LOAD_CHECK='Both';
      NO_IO_CHECK='Both';
      NO_ASSERT_CHECK='TRUE';
      NO_DIR_CHECK='TRUE';
      ALLOW_CONNECT='TRUE';
    'VSS'<278>:
      PIN_NUMBER='(0,0,0,0,0,0,0,0,0,0,0,0,0,0,0,0,0,0,0,0,0,0,0,0,0,0,0,0,DB47,~
0)';
      PINUSE='GROUND';
      NO_LOAD_CHECK='Both';
      NO_IO_CHECK='Both';
      NO_ASSERT_CHECK='TRUE';
      NO_DIR_CHECK='TRUE';
      ALLOW_CONNECT='TRUE';
    'VSS'<277>:
      PIN_NUMBER='(0,0,0,0,0,0,0,0,0,0,0,0,0,0,0,0,0,0,0,0,0,0,0,0,0,0,0,0,DB49,~
0)';
      PINUSE='GROUND';
      NO_LOAD_CHECK='Both';
      NO_IO_CHECK='Both';
      NO_ASSERT_CHECK='TRUE';
      NO_DIR_CHECK='TRUE';
      ALLOW_CONNECT='TRUE';
    'VSS'<276>:
      PIN_NUMBER='(0,0,0,0,0,0,0,0,0,0,0,0,0,0,0,0,0,0,0,0,0,0,0,0,0,0,0,0,DB73,~
0)';
      PINUSE='GROUND';
      NO_LOAD_CHECK='Both';
      NO_IO_CHECK='Both';
      NO_ASSERT_CHECK='TRUE';
      NO_DIR_CHECK='TRUE';
      ALLOW_CONNECT='TRUE';
    'VSS'<275>:
      PIN_NUMBER='(0,0,0,0,0,0,0,0,0,0,0,0,0,0,0,0,0,0,0,0,0,0,0,0,0,0,0,0,DB77,~
0)';
      PINUSE='GROUND';
      NO_LOAD_CHECK='Both';
      NO_IO_CHECK='Both';
      NO_ASSERT_CHECK='TRUE';
      NO_DIR_CHECK='TRUE';
      ALLOW_CONNECT='TRUE';
    'VSS'<274>:
      PIN_NUMBER='(0,0,0,0,0,0,0,0,0,0,0,0,0,0,0,0,0,0,0,0,0,0,0,0,0,0,0,0,DB83,~
0)';
      PINUSE='GROUND';
      NO_LOAD_CHECK='Both';
      NO_IO_CHECK='Both';
      NO_ASSERT_CHECK='TRUE';
      NO_DIR_CHECK='TRUE';
      ALLOW_CONNECT='TRUE';
    'VSS'<273>:
      PIN_NUMBER='(0,0,0,0,0,0,0,0,0,0,0,0,0,0,0,0,0,0,0,0,0,0,0,0,0,0,0,0,DB85,~
0)';
      PINUSE='GROUND';
      NO_LOAD_CHECK='Both';
      NO_IO_CHECK='Both';
      NO_ASSERT_CHECK='TRUE';
      NO_DIR_CHECK='TRUE';
      ALLOW_CONNECT='TRUE';
    'VSS'<272>:
      PIN_NUMBER='(0,0,0,0,0,0,0,0,0,0,0,0,0,0,0,0,0,0,0,0,0,0,0,0,0,0,0,0,DC14,~
0)';
      PINUSE='GROUND';
      NO_LOAD_CHECK='Both';
      NO_IO_CHECK='Both';
      NO_ASSERT_CHECK='TRUE';
      NO_DIR_CHECK='TRUE';
      ALLOW_CONNECT='TRUE';
    'VSS'<271>:
      PIN_NUMBER='(0,0,0,0,0,0,0,0,0,0,0,0,0,0,0,0,0,0,0,0,0,0,0,0,0,0,0,0,DC24,~
0)';
      PINUSE='GROUND';
      NO_LOAD_CHECK='Both';
      NO_IO_CHECK='Both';
      NO_ASSERT_CHECK='TRUE';
      NO_DIR_CHECK='TRUE';
      ALLOW_CONNECT='TRUE';
    'VSS'<270>:
      PIN_NUMBER='(0,0,0,0,0,0,0,0,0,0,0,0,0,0,0,0,0,0,0,0,0,0,0,0,0,0,0,0,DC26,~
0)';
      PINUSE='GROUND';
      NO_LOAD_CHECK='Both';
      NO_IO_CHECK='Both';
      NO_ASSERT_CHECK='TRUE';
      NO_DIR_CHECK='TRUE';
      ALLOW_CONNECT='TRUE';
    'VSS'<269>:
      PIN_NUMBER='(0,0,0,0,0,0,0,0,0,0,0,0,0,0,0,0,0,0,0,0,0,0,0,0,0,0,0,0,DC32,~
0)';
      PINUSE='GROUND';
      NO_LOAD_CHECK='Both';
      NO_IO_CHECK='Both';
      NO_ASSERT_CHECK='TRUE';
      NO_DIR_CHECK='TRUE';
      ALLOW_CONNECT='TRUE';
    'VSS'<268>:
      PIN_NUMBER='(0,0,0,0,0,0,0,0,0,0,0,0,0,0,0,0,0,0,0,0,0,0,0,0,0,0,0,0,DC38,~
0)';
      PINUSE='GROUND';
      NO_LOAD_CHECK='Both';
      NO_IO_CHECK='Both';
      NO_ASSERT_CHECK='TRUE';
      NO_DIR_CHECK='TRUE';
      ALLOW_CONNECT='TRUE';
    'VSS'<267>:
      PIN_NUMBER='(0,0,0,0,0,0,0,0,0,0,0,0,0,0,0,0,0,0,0,0,0,0,0,0,0,0,0,0,DC42,~
0)';
      PINUSE='GROUND';
      NO_LOAD_CHECK='Both';
      NO_IO_CHECK='Both';
      NO_ASSERT_CHECK='TRUE';
      NO_DIR_CHECK='TRUE';
      ALLOW_CONNECT='TRUE';
    'VSS'<266>:
      PIN_NUMBER='(0,0,0,0,0,0,0,0,0,0,0,0,0,0,0,0,0,0,0,0,0,0,0,0,0,0,0,0,DC64,~
0)';
      PINUSE='GROUND';
      NO_LOAD_CHECK='Both';
      NO_IO_CHECK='Both';
      NO_ASSERT_CHECK='TRUE';
      NO_DIR_CHECK='TRUE';
      ALLOW_CONNECT='TRUE';
    'VSS'<265>:
      PIN_NUMBER='(0,0,0,0,0,0,0,0,0,0,0,0,0,0,0,0,0,0,0,0,0,0,0,0,0,0,0,0,DC66,~
0)';
      PINUSE='GROUND';
      NO_LOAD_CHECK='Both';
      NO_IO_CHECK='Both';
      NO_ASSERT_CHECK='TRUE';
      NO_DIR_CHECK='TRUE';
      ALLOW_CONNECT='TRUE';
    'VSS'<264>:
      PIN_NUMBER='(0,0,0,0,0,0,0,0,0,0,0,0,0,0,0,0,0,0,0,0,0,0,0,0,0,0,0,0,DC68,~
0)';
      PINUSE='GROUND';
      NO_LOAD_CHECK='Both';
      NO_IO_CHECK='Both';
      NO_ASSERT_CHECK='TRUE';
      NO_DIR_CHECK='TRUE';
      ALLOW_CONNECT='TRUE';
    'VSS'<263>:
      PIN_NUMBER='(0,0,0,0,0,0,0,0,0,0,0,0,0,0,0,0,0,0,0,0,0,0,0,0,0,0,0,0,DC70,~
0)';
      PINUSE='GROUND';
      NO_LOAD_CHECK='Both';
      NO_IO_CHECK='Both';
      NO_ASSERT_CHECK='TRUE';
      NO_DIR_CHECK='TRUE';
      ALLOW_CONNECT='TRUE';
    'VSS'<262>:
      PIN_NUMBER='(0,0,0,0,0,0,0,0,0,0,0,0,0,0,0,0,0,0,0,0,0,0,0,0,0,0,0,0,DC78,~
0)';
      PINUSE='GROUND';
      NO_LOAD_CHECK='Both';
      NO_IO_CHECK='Both';
      NO_ASSERT_CHECK='TRUE';
      NO_DIR_CHECK='TRUE';
      ALLOW_CONNECT='TRUE';
    'VSS'<261>:
      PIN_NUMBER='(0,0,0,0,0,0,0,0,0,0,0,0,0,0,0,0,0,0,0,0,0,0,0,0,0,0,0,0,DC84,~
0)';
      PINUSE='GROUND';
      NO_LOAD_CHECK='Both';
      NO_IO_CHECK='Both';
      NO_ASSERT_CHECK='TRUE';
      NO_DIR_CHECK='TRUE';
      ALLOW_CONNECT='TRUE';
    'VSS'<260>:
      PIN_NUMBER='(0,0,0,0,0,0,0,0,0,0,0,0,0,0,0,0,0,0,0,0,0,0,0,0,0,0,0,0,DC86,~
0)';
      PINUSE='GROUND';
      NO_LOAD_CHECK='Both';
      NO_IO_CHECK='Both';
      NO_ASSERT_CHECK='TRUE';
      NO_DIR_CHECK='TRUE';
      ALLOW_CONNECT='TRUE';
    'VSS'<259>:
      PIN_NUMBER='(0,0,0,0,0,0,0,0,0,0,0,0,0,0,0,0,0,0,0,0,0,0,0,0,0,0,0,0,DD11,~
0)';
      PINUSE='GROUND';
      NO_LOAD_CHECK='Both';
      NO_IO_CHECK='Both';
      NO_ASSERT_CHECK='TRUE';
      NO_DIR_CHECK='TRUE';
      ALLOW_CONNECT='TRUE';
    'VSS'<258>:
      PIN_NUMBER='(0,0,0,0,0,0,0,0,0,0,0,0,0,0,0,0,0,0,0,0,0,0,0,0,0,0,0,0,DD23,~
0)';
      PINUSE='GROUND';
      NO_LOAD_CHECK='Both';
      NO_IO_CHECK='Both';
      NO_ASSERT_CHECK='TRUE';
      NO_DIR_CHECK='TRUE';
      ALLOW_CONNECT='TRUE';
    'VSS'<257>:
      PIN_NUMBER='(0,0,0,0,0,0,0,0,0,0,0,0,0,0,0,0,0,0,0,0,0,0,0,0,0,0,0,0,DD27,~
0)';
      PINUSE='GROUND';
      NO_LOAD_CHECK='Both';
      NO_IO_CHECK='Both';
      NO_ASSERT_CHECK='TRUE';
      NO_DIR_CHECK='TRUE';
      ALLOW_CONNECT='TRUE';
    'VSS'<256>:
      PIN_NUMBER='(0,0,0,0,0,0,0,0,0,0,0,0,0,0,0,0,0,0,0,0,0,0,0,0,0,0,0,0,DD31,~
0)';
      PINUSE='GROUND';
      NO_LOAD_CHECK='Both';
      NO_IO_CHECK='Both';
      NO_ASSERT_CHECK='TRUE';
      NO_DIR_CHECK='TRUE';
      ALLOW_CONNECT='TRUE';
    'VSS'<255>:
      PIN_NUMBER='(0,0,0,0,0,0,0,0,0,0,0,0,0,0,0,0,0,0,0,0,0,0,0,0,0,0,0,0,DD33,~
0)';
      PINUSE='GROUND';
      NO_LOAD_CHECK='Both';
      NO_IO_CHECK='Both';
      NO_ASSERT_CHECK='TRUE';
      NO_DIR_CHECK='TRUE';
      ALLOW_CONNECT='TRUE';
    'VSS'<254>:
      PIN_NUMBER='(0,0,0,0,0,0,0,0,0,0,0,0,0,0,0,0,0,0,0,0,0,0,0,0,0,0,0,0,DD37,~
0)';
      PINUSE='GROUND';
      NO_LOAD_CHECK='Both';
      NO_IO_CHECK='Both';
      NO_ASSERT_CHECK='TRUE';
      NO_DIR_CHECK='TRUE';
      ALLOW_CONNECT='TRUE';
    'VSS'<253>:
      PIN_NUMBER='(0,0,0,0,0,0,0,0,0,0,0,0,0,0,0,0,0,0,0,0,0,0,0,0,0,0,0,0,DD71,~
0)';
      PINUSE='GROUND';
      NO_LOAD_CHECK='Both';
      NO_IO_CHECK='Both';
      NO_ASSERT_CHECK='TRUE';
      NO_DIR_CHECK='TRUE';
      ALLOW_CONNECT='TRUE';
    'VSS'<252>:
      PIN_NUMBER='(0,0,0,0,0,0,0,0,0,0,0,0,0,0,0,0,0,0,0,0,0,0,0,0,0,0,0,0,DD73,~
0)';
      PINUSE='GROUND';
      NO_LOAD_CHECK='Both';
      NO_IO_CHECK='Both';
      NO_ASSERT_CHECK='TRUE';
      NO_DIR_CHECK='TRUE';
      ALLOW_CONNECT='TRUE';
    'VSS'<251>:
      PIN_NUMBER='(0,0,0,0,0,0,0,0,0,0,0,0,0,0,0,0,0,0,0,0,0,0,0,0,0,0,0,0,DD75,~
0)';
      PINUSE='GROUND';
      NO_LOAD_CHECK='Both';
      NO_IO_CHECK='Both';
      NO_ASSERT_CHECK='TRUE';
      NO_DIR_CHECK='TRUE';
      ALLOW_CONNECT='TRUE';
    'VSS'<250>:
      PIN_NUMBER='(0,0,0,0,0,0,0,0,0,0,0,0,0,0,0,0,0,0,0,0,0,0,0,0,0,0,0,0,DD81,~
0)';
      PINUSE='GROUND';
      NO_LOAD_CHECK='Both';
      NO_IO_CHECK='Both';
      NO_ASSERT_CHECK='TRUE';
      NO_DIR_CHECK='TRUE';
      ALLOW_CONNECT='TRUE';
    'VSS'<249>:
      PIN_NUMBER='(0,0,0,0,0,0,0,0,0,0,0,0,0,0,0,0,0,0,0,0,0,0,0,0,0,0,0,0,DD83,~
0)';
      PINUSE='GROUND';
      NO_LOAD_CHECK='Both';
      NO_IO_CHECK='Both';
      NO_ASSERT_CHECK='TRUE';
      NO_DIR_CHECK='TRUE';
      ALLOW_CONNECT='TRUE';
    'VSS'<248>:
      PIN_NUMBER='(0,0,0,0,0,0,0,0,0,0,0,0,0,0,0,0,0,0,0,0,0,0,0,0,0,0,0,0,DE6,0~
)';
      PINUSE='GROUND';
      NO_LOAD_CHECK='Both';
      NO_IO_CHECK='Both';
      NO_ASSERT_CHECK='TRUE';
      NO_DIR_CHECK='TRUE';
      ALLOW_CONNECT='TRUE';
    'VSS'<247>:
      PIN_NUMBER='(0,0,0,0,0,0,0,0,0,0,0,0,0,0,0,0,0,0,0,0,0,0,0,0,0,0,0,0,DE8,0~
)';
      PINUSE='GROUND';
      NO_LOAD_CHECK='Both';
      NO_IO_CHECK='Both';
      NO_ASSERT_CHECK='TRUE';
      NO_DIR_CHECK='TRUE';
      ALLOW_CONNECT='TRUE';
    'VSS'<246>:
      PIN_NUMBER='(0,0,0,0,0,0,0,0,0,0,0,0,0,0,0,0,0,0,0,0,0,0,0,0,0,0,0,0,DE18,~
0)';
      PINUSE='GROUND';
      NO_LOAD_CHECK='Both';
      NO_IO_CHECK='Both';
      NO_ASSERT_CHECK='TRUE';
      NO_DIR_CHECK='TRUE';
      ALLOW_CONNECT='TRUE';
    'VSS'<245>:
      PIN_NUMBER='(0,0,0,0,0,0,0,0,0,0,0,0,0,0,0,0,0,0,0,0,0,0,0,0,0,0,0,0,DE20,~
0)';
      PINUSE='GROUND';
      NO_LOAD_CHECK='Both';
      NO_IO_CHECK='Both';
      NO_ASSERT_CHECK='TRUE';
      NO_DIR_CHECK='TRUE';
      ALLOW_CONNECT='TRUE';
    'VSS'<244>:
      PIN_NUMBER='(0,0,0,0,0,0,0,0,0,0,0,0,0,0,0,0,0,0,0,0,0,0,0,0,0,0,0,0,DE24,~
0)';
      PINUSE='GROUND';
      NO_LOAD_CHECK='Both';
      NO_IO_CHECK='Both';
      NO_ASSERT_CHECK='TRUE';
      NO_DIR_CHECK='TRUE';
      ALLOW_CONNECT='TRUE';
    'VSS'<243>:
      PIN_NUMBER='(0,0,0,0,0,0,0,0,0,0,0,0,0,0,0,0,0,0,0,0,0,0,0,0,0,0,0,0,DE28,~
0)';
      PINUSE='GROUND';
      NO_LOAD_CHECK='Both';
      NO_IO_CHECK='Both';
      NO_ASSERT_CHECK='TRUE';
      NO_DIR_CHECK='TRUE';
      ALLOW_CONNECT='TRUE';
    'VSS'<242>:
      PIN_NUMBER='(0,0,0,0,0,0,0,0,0,0,0,0,0,0,0,0,0,0,0,0,0,0,0,0,0,0,0,0,DE30,~
0)';
      PINUSE='GROUND';
      NO_LOAD_CHECK='Both';
      NO_IO_CHECK='Both';
      NO_ASSERT_CHECK='TRUE';
      NO_DIR_CHECK='TRUE';
      ALLOW_CONNECT='TRUE';
    'VSS'<241>:
      PIN_NUMBER='(0,0,0,0,0,0,0,0,0,0,0,0,0,0,0,0,0,0,0,0,0,0,0,0,0,0,0,0,DE34,~
0)';
      PINUSE='GROUND';
      NO_LOAD_CHECK='Both';
      NO_IO_CHECK='Both';
      NO_ASSERT_CHECK='TRUE';
      NO_DIR_CHECK='TRUE';
      ALLOW_CONNECT='TRUE';
    'VSS'<240>:
      PIN_NUMBER='(0,0,0,0,0,0,0,0,0,0,0,0,0,0,0,0,0,0,0,0,0,0,0,0,0,0,0,0,DE36,~
0)';
      PINUSE='GROUND';
      NO_LOAD_CHECK='Both';
      NO_IO_CHECK='Both';
      NO_ASSERT_CHECK='TRUE';
      NO_DIR_CHECK='TRUE';
      ALLOW_CONNECT='TRUE';
    'VSS'<239>:
      PIN_NUMBER='(0,0,0,0,0,0,0,0,0,0,0,0,0,0,0,0,0,0,0,0,0,0,0,0,0,0,0,0,DE64,~
0)';
      PINUSE='GROUND';
      NO_LOAD_CHECK='Both';
      NO_IO_CHECK='Both';
      NO_ASSERT_CHECK='TRUE';
      NO_DIR_CHECK='TRUE';
      ALLOW_CONNECT='TRUE';
    'VSS'<238>:
      PIN_NUMBER='(0,0,0,0,0,0,0,0,0,0,0,0,0,0,0,0,0,0,0,0,0,0,0,0,0,0,0,0,DE70,~
0)';
      PINUSE='GROUND';
      NO_LOAD_CHECK='Both';
      NO_IO_CHECK='Both';
      NO_ASSERT_CHECK='TRUE';
      NO_DIR_CHECK='TRUE';
      ALLOW_CONNECT='TRUE';
    'VSS'<237>:
      PIN_NUMBER='(0,0,0,0,0,0,0,0,0,0,0,0,0,0,0,0,0,0,0,0,0,0,0,0,0,0,0,0,DE72,~
0)';
      PINUSE='GROUND';
      NO_LOAD_CHECK='Both';
      NO_IO_CHECK='Both';
      NO_ASSERT_CHECK='TRUE';
      NO_DIR_CHECK='TRUE';
      ALLOW_CONNECT='TRUE';
    'VSS'<236>:
      PIN_NUMBER='(0,0,0,0,0,0,0,0,0,0,0,0,0,0,0,0,0,0,0,0,0,0,0,0,0,0,0,0,DE78,~
0)';
      PINUSE='GROUND';
      NO_LOAD_CHECK='Both';
      NO_IO_CHECK='Both';
      NO_ASSERT_CHECK='TRUE';
      NO_DIR_CHECK='TRUE';
      ALLOW_CONNECT='TRUE';
    'VSS'<235>:
      PIN_NUMBER='(0,0,0,0,0,0,0,0,0,0,0,0,0,0,0,0,0,0,0,0,0,0,0,0,0,0,0,0,DF5,0~
)';
      PINUSE='GROUND';
      NO_LOAD_CHECK='Both';
      NO_IO_CHECK='Both';
      NO_ASSERT_CHECK='TRUE';
      NO_DIR_CHECK='TRUE';
      ALLOW_CONNECT='TRUE';
    'VSS'<234>:
      PIN_NUMBER='(0,0,0,0,0,0,0,0,0,0,0,0,0,0,0,0,0,0,0,0,0,0,0,0,0,0,0,0,DF7,0~
)';
      PINUSE='GROUND';
      NO_LOAD_CHECK='Both';
      NO_IO_CHECK='Both';
      NO_ASSERT_CHECK='TRUE';
      NO_DIR_CHECK='TRUE';
      ALLOW_CONNECT='TRUE';
    'VSS'<233>:
      PIN_NUMBER='(0,0,0,0,0,0,0,0,0,0,0,0,0,0,0,0,0,0,0,0,0,0,0,0,0,0,0,0,H51,0~
)';
      PINUSE='GROUND';
      NO_LOAD_CHECK='Both';
      NO_IO_CHECK='Both';
      NO_ASSERT_CHECK='TRUE';
      NO_DIR_CHECK='TRUE';
      ALLOW_CONNECT='TRUE';
    'VSS'<232>:
      PIN_NUMBER='(0,0,0,0,0,0,0,0,0,0,0,0,0,0,0,0,0,0,0,0,0,0,0,0,0,0,0,0,DF19,~
0)';
      PINUSE='GROUND';
      NO_LOAD_CHECK='Both';
      NO_IO_CHECK='Both';
      NO_ASSERT_CHECK='TRUE';
      NO_DIR_CHECK='TRUE';
      ALLOW_CONNECT='TRUE';
    'VSS'<231>:
      PIN_NUMBER='(0,0,0,0,0,0,0,0,0,0,0,0,0,0,0,0,0,0,0,0,0,0,0,0,0,0,0,0,DF29,~
0)';
      PINUSE='GROUND';
      NO_LOAD_CHECK='Both';
      NO_IO_CHECK='Both';
      NO_ASSERT_CHECK='TRUE';
      NO_DIR_CHECK='TRUE';
      ALLOW_CONNECT='TRUE';
    'VSS'<230>:
      PIN_NUMBER='(0,0,0,0,0,0,0,0,0,0,0,0,0,0,0,0,0,0,0,0,0,0,0,0,0,0,0,0,DF35,~
0)';
      PINUSE='GROUND';
      NO_LOAD_CHECK='Both';
      NO_IO_CHECK='Both';
      NO_ASSERT_CHECK='TRUE';
      NO_DIR_CHECK='TRUE';
      ALLOW_CONNECT='TRUE';
    'VSS'<229>:
      PIN_NUMBER='(0,0,0,0,0,0,0,0,0,0,0,0,0,0,0,0,0,0,0,0,0,0,0,0,0,0,0,0,DF37,~
0)';
      PINUSE='GROUND';
      NO_LOAD_CHECK='Both';
      NO_IO_CHECK='Both';
      NO_ASSERT_CHECK='TRUE';
      NO_DIR_CHECK='TRUE';
      ALLOW_CONNECT='TRUE';
    'VSS'<228>:
      PIN_NUMBER='(0,0,0,0,0,0,0,0,0,0,0,0,0,0,0,0,0,0,0,0,0,0,0,0,0,0,0,0,DF39,~
0)';
      PINUSE='GROUND';
      NO_LOAD_CHECK='Both';
      NO_IO_CHECK='Both';
      NO_ASSERT_CHECK='TRUE';
      NO_DIR_CHECK='TRUE';
      ALLOW_CONNECT='TRUE';
    'VSS'<227>:
      PIN_NUMBER='(0,0,0,0,0,0,0,0,0,0,0,0,0,0,0,0,0,0,0,0,0,0,0,0,0,0,0,0,DF41,~
0)';
      PINUSE='GROUND';
      NO_LOAD_CHECK='Both';
      NO_IO_CHECK='Both';
      NO_ASSERT_CHECK='TRUE';
      NO_DIR_CHECK='TRUE';
      ALLOW_CONNECT='TRUE';
    'VSS'<226>:
      PIN_NUMBER='(0,0,0,0,0,0,0,0,0,0,0,0,0,0,0,0,0,0,0,0,0,0,0,0,0,0,0,0,DF65,~
0)';
      PINUSE='GROUND';
      NO_LOAD_CHECK='Both';
      NO_IO_CHECK='Both';
      NO_ASSERT_CHECK='TRUE';
      NO_DIR_CHECK='TRUE';
      ALLOW_CONNECT='TRUE';
    'VSS'<225>:
      PIN_NUMBER='(0,0,0,0,0,0,0,0,0,0,0,0,0,0,0,0,0,0,0,0,0,0,0,0,0,0,0,0,DF69,~
0)';
      PINUSE='GROUND';
      NO_LOAD_CHECK='Both';
      NO_IO_CHECK='Both';
      NO_ASSERT_CHECK='TRUE';
      NO_DIR_CHECK='TRUE';
      ALLOW_CONNECT='TRUE';
    'VSS'<224>:
      PIN_NUMBER='(0,0,0,0,0,0,0,0,0,0,0,0,0,0,0,0,0,0,0,0,0,0,0,0,0,0,0,0,DF73,~
0)';
      PINUSE='GROUND';
      NO_LOAD_CHECK='Both';
      NO_IO_CHECK='Both';
      NO_ASSERT_CHECK='TRUE';
      NO_DIR_CHECK='TRUE';
      ALLOW_CONNECT='TRUE';
    'VSS'<223>:
      PIN_NUMBER='(0,0,0,0,0,0,0,0,0,0,0,0,0,0,0,0,0,0,0,0,0,0,0,0,0,0,0,0,DF79,~
0)';
      PINUSE='GROUND';
      NO_LOAD_CHECK='Both';
      NO_IO_CHECK='Both';
      NO_ASSERT_CHECK='TRUE';
      NO_DIR_CHECK='TRUE';
      ALLOW_CONNECT='TRUE';
    'VSS'<222>:
      PIN_NUMBER='(0,0,0,0,0,0,0,0,0,0,0,0,0,0,0,0,0,0,0,0,0,0,0,0,0,0,0,0,DF83,~
0)';
      PINUSE='GROUND';
      NO_LOAD_CHECK='Both';
      NO_IO_CHECK='Both';
      NO_ASSERT_CHECK='TRUE';
      NO_DIR_CHECK='TRUE';
      ALLOW_CONNECT='TRUE';
    'VSS'<221>:
      PIN_NUMBER='(0,0,0,0,0,0,0,0,0,0,0,0,0,0,0,0,0,0,0,0,0,0,0,0,0,0,0,0,DF85,~
0)';
      PINUSE='GROUND';
      NO_LOAD_CHECK='Both';
      NO_IO_CHECK='Both';
      NO_ASSERT_CHECK='TRUE';
      NO_DIR_CHECK='TRUE';
      ALLOW_CONNECT='TRUE';
    'VSS'<220>:
      PIN_NUMBER='(0,0,0,0,0,0,0,0,0,0,0,0,0,0,0,0,0,0,0,0,0,0,0,0,0,0,0,0,DG2,0~
)';
      PINUSE='GROUND';
      NO_LOAD_CHECK='Both';
      NO_IO_CHECK='Both';
      NO_ASSERT_CHECK='TRUE';
      NO_DIR_CHECK='TRUE';
      ALLOW_CONNECT='TRUE';
    'VSS'<219>:
      PIN_NUMBER='(0,0,0,0,0,0,0,0,0,0,0,0,0,0,0,0,0,0,0,0,0,0,0,0,0,0,0,0,H49,0~
)';
      PINUSE='GROUND';
      NO_LOAD_CHECK='Both';
      NO_IO_CHECK='Both';
      NO_ASSERT_CHECK='TRUE';
      NO_DIR_CHECK='TRUE';
      ALLOW_CONNECT='TRUE';
    'VSS'<218>:
      PIN_NUMBER='(0,0,0,0,0,0,0,0,0,0,0,0,0,0,0,0,0,0,0,0,0,0,0,0,0,0,0,0,DG14,~
0)';
      PINUSE='GROUND';
      NO_LOAD_CHECK='Both';
      NO_IO_CHECK='Both';
      NO_ASSERT_CHECK='TRUE';
      NO_DIR_CHECK='TRUE';
      ALLOW_CONNECT='TRUE';
    'VSS'<217>:
      PIN_NUMBER='(0,0,0,0,0,0,0,0,0,0,0,0,0,0,0,0,0,0,0,0,0,0,0,0,0,0,0,0,DG16,~
0)';
      PINUSE='GROUND';
      NO_LOAD_CHECK='Both';
      NO_IO_CHECK='Both';
      NO_ASSERT_CHECK='TRUE';
      NO_DIR_CHECK='TRUE';
      ALLOW_CONNECT='TRUE';
    'VSS'<216>:
      PIN_NUMBER='(0,0,0,0,0,0,0,0,0,0,0,0,0,0,0,0,0,0,0,0,0,0,0,0,0,0,0,0,DG24,~
0)';
      PINUSE='GROUND';
      NO_LOAD_CHECK='Both';
      NO_IO_CHECK='Both';
      NO_ASSERT_CHECK='TRUE';
      NO_DIR_CHECK='TRUE';
      ALLOW_CONNECT='TRUE';
    'VSS'<215>:
      PIN_NUMBER='(0,0,0,0,0,0,0,0,0,0,0,0,0,0,0,0,0,0,0,0,0,0,0,0,0,0,0,0,DG66,~
0)';
      PINUSE='GROUND';
      NO_LOAD_CHECK='Both';
      NO_IO_CHECK='Both';
      NO_ASSERT_CHECK='TRUE';
      NO_DIR_CHECK='TRUE';
      ALLOW_CONNECT='TRUE';
    'VSS'<214>:
      PIN_NUMBER='(0,0,0,0,0,0,0,0,0,0,0,0,0,0,0,0,0,0,0,0,0,0,0,0,0,0,0,0,DG68,~
0)';
      PINUSE='GROUND';
      NO_LOAD_CHECK='Both';
      NO_IO_CHECK='Both';
      NO_ASSERT_CHECK='TRUE';
      NO_DIR_CHECK='TRUE';
      ALLOW_CONNECT='TRUE';
    'VSS'<213>:
      PIN_NUMBER='(0,0,0,0,0,0,0,0,0,0,0,0,0,0,0,0,0,0,0,0,0,0,0,0,0,0,0,0,DG76,~
0)';
      PINUSE='GROUND';
      NO_LOAD_CHECK='Both';
      NO_IO_CHECK='Both';
      NO_ASSERT_CHECK='TRUE';
      NO_DIR_CHECK='TRUE';
      ALLOW_CONNECT='TRUE';
    'VSS'<212>:
      PIN_NUMBER='(0,0,0,0,0,0,0,0,0,0,0,0,0,0,0,0,0,0,0,0,0,0,0,0,0,0,0,0,DG78,~
0)';
      PINUSE='GROUND';
      NO_LOAD_CHECK='Both';
      NO_IO_CHECK='Both';
      NO_ASSERT_CHECK='TRUE';
      NO_DIR_CHECK='TRUE';
      ALLOW_CONNECT='TRUE';
    'VSS'<211>:
      PIN_NUMBER='(0,0,0,0,0,0,0,0,0,0,0,0,0,0,0,0,0,0,0,0,0,0,0,0,0,0,0,0,DG80,~
0)';
      PINUSE='GROUND';
      NO_LOAD_CHECK='Both';
      NO_IO_CHECK='Both';
      NO_ASSERT_CHECK='TRUE';
      NO_DIR_CHECK='TRUE';
      ALLOW_CONNECT='TRUE';
    'VSS'<210>:
      PIN_NUMBER='(0,0,0,0,0,0,0,0,0,0,0,0,0,0,0,0,0,0,0,0,0,0,0,0,0,0,0,0,DG82,~
0)';
      PINUSE='GROUND';
      NO_LOAD_CHECK='Both';
      NO_IO_CHECK='Both';
      NO_ASSERT_CHECK='TRUE';
      NO_DIR_CHECK='TRUE';
      ALLOW_CONNECT='TRUE';
    'VSS'<209>:
      PIN_NUMBER='(0,0,0,0,0,0,0,0,0,0,0,0,0,0,0,0,0,0,0,0,0,0,0,0,0,0,0,0,DH13,~
0)';
      PINUSE='GROUND';
      NO_LOAD_CHECK='Both';
      NO_IO_CHECK='Both';
      NO_ASSERT_CHECK='TRUE';
      NO_DIR_CHECK='TRUE';
      ALLOW_CONNECT='TRUE';
    'VSS'<208>:
      PIN_NUMBER='(0,0,0,0,0,0,0,0,0,0,0,0,0,0,0,0,0,0,0,0,0,0,0,0,0,0,0,0,DH15,~
0)';
      PINUSE='GROUND';
      NO_LOAD_CHECK='Both';
      NO_IO_CHECK='Both';
      NO_ASSERT_CHECK='TRUE';
      NO_DIR_CHECK='TRUE';
      ALLOW_CONNECT='TRUE';
    'VSS'<207>:
      PIN_NUMBER='(0,0,0,0,0,0,0,0,0,0,0,0,0,0,0,0,0,0,0,0,0,0,0,0,0,0,0,0,DH23,~
0)';
      PINUSE='GROUND';
      NO_LOAD_CHECK='Both';
      NO_IO_CHECK='Both';
      NO_ASSERT_CHECK='TRUE';
      NO_DIR_CHECK='TRUE';
      ALLOW_CONNECT='TRUE';
    'VSS'<206>:
      PIN_NUMBER='(0,0,0,0,0,0,0,0,0,0,0,0,0,0,0,0,0,0,0,0,0,0,0,0,0,0,0,0,DH25,~
0)';
      PINUSE='GROUND';
      NO_LOAD_CHECK='Both';
      NO_IO_CHECK='Both';
      NO_ASSERT_CHECK='TRUE';
      NO_DIR_CHECK='TRUE';
      ALLOW_CONNECT='TRUE';
    'VSS'<205>:
      PIN_NUMBER='(0,0,0,0,0,0,0,0,0,0,0,0,0,0,0,0,0,0,0,0,0,0,0,0,0,0,0,0,DH27,~
0)';
      PINUSE='GROUND';
      NO_LOAD_CHECK='Both';
      NO_IO_CHECK='Both';
      NO_ASSERT_CHECK='TRUE';
      NO_DIR_CHECK='TRUE';
      ALLOW_CONNECT='TRUE';
    'VSS'<204>:
      PIN_NUMBER='(0,0,0,0,0,0,0,0,0,0,0,0,0,0,0,0,0,0,0,0,0,0,0,0,0,0,0,0,DH29,~
0)';
      PINUSE='GROUND';
      NO_LOAD_CHECK='Both';
      NO_IO_CHECK='Both';
      NO_ASSERT_CHECK='TRUE';
      NO_DIR_CHECK='TRUE';
      ALLOW_CONNECT='TRUE';
    'VSS'<203>:
      PIN_NUMBER='(0,0,0,0,0,0,0,0,0,0,0,0,0,0,0,0,0,0,0,0,0,0,0,0,0,0,0,0,DH31,~
0)';
      PINUSE='GROUND';
      NO_LOAD_CHECK='Both';
      NO_IO_CHECK='Both';
      NO_ASSERT_CHECK='TRUE';
      NO_DIR_CHECK='TRUE';
      ALLOW_CONNECT='TRUE';
    'VSS'<202>:
      PIN_NUMBER='(0,0,0,0,0,0,0,0,0,0,0,0,0,0,0,0,0,0,0,0,0,0,0,0,0,0,0,0,DH33,~
0)';
      PINUSE='GROUND';
      NO_LOAD_CHECK='Both';
      NO_IO_CHECK='Both';
      NO_ASSERT_CHECK='TRUE';
      NO_DIR_CHECK='TRUE';
      ALLOW_CONNECT='TRUE';
    'VSS'<201>:
      PIN_NUMBER='(0,0,0,0,0,0,0,0,0,0,0,0,0,0,0,0,0,0,0,0,0,0,0,0,0,0,0,0,DH35,~
0)';
      PINUSE='GROUND';
      NO_LOAD_CHECK='Both';
      NO_IO_CHECK='Both';
      NO_ASSERT_CHECK='TRUE';
      NO_DIR_CHECK='TRUE';
      ALLOW_CONNECT='TRUE';
    'VSS'<200>:
      PIN_NUMBER='(0,0,0,0,0,0,0,0,0,0,0,0,0,0,0,0,0,0,0,0,0,0,0,0,0,0,0,0,DH37,~
0)';
      PINUSE='GROUND';
      NO_LOAD_CHECK='Both';
      NO_IO_CHECK='Both';
      NO_ASSERT_CHECK='TRUE';
      NO_DIR_CHECK='TRUE';
      ALLOW_CONNECT='TRUE';
    'VSS'<199>:
      PIN_NUMBER='(0,0,0,0,0,0,0,0,0,0,0,0,0,0,0,0,0,0,0,0,0,0,0,0,0,0,0,0,DH41,~
0)';
      PINUSE='GROUND';
      NO_LOAD_CHECK='Both';
      NO_IO_CHECK='Both';
      NO_ASSERT_CHECK='TRUE';
      NO_DIR_CHECK='TRUE';
      ALLOW_CONNECT='TRUE';
    'VSS'<198>:
      PIN_NUMBER='(0,0,0,0,0,0,0,0,0,0,0,0,0,0,0,0,0,0,0,0,0,0,0,0,0,0,0,0,DH67,~
0)';
      PINUSE='GROUND';
      NO_LOAD_CHECK='Both';
      NO_IO_CHECK='Both';
      NO_ASSERT_CHECK='TRUE';
      NO_DIR_CHECK='TRUE';
      ALLOW_CONNECT='TRUE';
    'VSS'<197>:
      PIN_NUMBER='(0,0,0,0,0,0,0,0,0,0,0,0,0,0,0,0,0,0,0,0,0,0,0,0,0,0,0,0,DH71,~
0)';
      PINUSE='GROUND';
      NO_LOAD_CHECK='Both';
      NO_IO_CHECK='Both';
      NO_ASSERT_CHECK='TRUE';
      NO_DIR_CHECK='TRUE';
      ALLOW_CONNECT='TRUE';
    'VSS'<196>:
      PIN_NUMBER='(0,0,0,0,0,0,0,0,0,0,0,0,0,0,0,0,0,0,0,0,0,0,0,0,0,0,0,0,DH73,~
0)';
      PINUSE='GROUND';
      NO_LOAD_CHECK='Both';
      NO_IO_CHECK='Both';
      NO_ASSERT_CHECK='TRUE';
      NO_DIR_CHECK='TRUE';
      ALLOW_CONNECT='TRUE';
    'VSS'<195>:
      PIN_NUMBER='(0,0,0,0,0,0,0,0,0,0,0,0,0,0,0,0,0,0,0,0,0,0,0,0,0,0,0,0,DH79,~
0)';
      PINUSE='GROUND';
      NO_LOAD_CHECK='Both';
      NO_IO_CHECK='Both';
      NO_ASSERT_CHECK='TRUE';
      NO_DIR_CHECK='TRUE';
      ALLOW_CONNECT='TRUE';
    'VSS'<194>:
      PIN_NUMBER='(0,0,0,0,0,0,0,0,0,0,0,0,0,0,0,0,0,0,0,0,0,0,0,0,0,0,0,0,DH81,~
0)';
      PINUSE='GROUND';
      NO_LOAD_CHECK='Both';
      NO_IO_CHECK='Both';
      NO_ASSERT_CHECK='TRUE';
      NO_DIR_CHECK='TRUE';
      ALLOW_CONNECT='TRUE';
    'VSS'<193>:
      PIN_NUMBER='(0,0,0,0,0,0,0,0,0,0,0,0,0,0,0,0,0,0,0,0,0,0,0,0,0,0,0,0,DH83,~
0)';
      PINUSE='GROUND';
      NO_LOAD_CHECK='Both';
      NO_IO_CHECK='Both';
      NO_ASSERT_CHECK='TRUE';
      NO_DIR_CHECK='TRUE';
      ALLOW_CONNECT='TRUE';
    'VSS'<192>:
      PIN_NUMBER='(0,0,0,0,0,0,0,0,0,0,0,0,0,0,0,0,0,0,0,0,0,0,0,0,0,0,0,0,DJ2,0~
)';
      PINUSE='GROUND';
      NO_LOAD_CHECK='Both';
      NO_IO_CHECK='Both';
      NO_ASSERT_CHECK='TRUE';
      NO_DIR_CHECK='TRUE';
      ALLOW_CONNECT='TRUE';
    'VSS'<191>:
      PIN_NUMBER='(0,0,0,0,0,0,0,0,0,0,0,0,0,0,0,0,0,0,0,0,0,0,0,0,0,0,0,0,DJ10,~
0)';
      PINUSE='GROUND';
      NO_LOAD_CHECK='Both';
      NO_IO_CHECK='Both';
      NO_ASSERT_CHECK='TRUE';
      NO_DIR_CHECK='TRUE';
      ALLOW_CONNECT='TRUE';
    'VSS'<190>:
      PIN_NUMBER='(0,0,0,0,0,0,0,0,0,0,0,0,0,0,0,0,0,0,0,0,0,0,0,0,0,0,0,0,H47,0~
)';
      PINUSE='GROUND';
      NO_LOAD_CHECK='Both';
      NO_IO_CHECK='Both';
      NO_ASSERT_CHECK='TRUE';
      NO_DIR_CHECK='TRUE';
      ALLOW_CONNECT='TRUE';
    'VSS'<189>:
      PIN_NUMBER='(0,0,0,0,0,0,0,0,0,0,0,0,0,0,0,0,0,0,0,0,0,0,0,0,0,0,0,0,DJ22,~
0)';
      PINUSE='GROUND';
      NO_LOAD_CHECK='Both';
      NO_IO_CHECK='Both';
      NO_ASSERT_CHECK='TRUE';
      NO_DIR_CHECK='TRUE';
      ALLOW_CONNECT='TRUE';
    'VSS'<188>:
      PIN_NUMBER='(0,0,0,0,0,0,0,0,0,0,0,0,0,0,0,0,0,0,0,0,0,0,0,0,0,0,0,0,DJ38,~
0)';
      PINUSE='GROUND';
      NO_LOAD_CHECK='Both';
      NO_IO_CHECK='Both';
      NO_ASSERT_CHECK='TRUE';
      NO_DIR_CHECK='TRUE';
      ALLOW_CONNECT='TRUE';
    'VSS'<187>:
      PIN_NUMBER='(0,0,0,0,0,0,0,0,0,0,0,0,0,0,0,0,0,0,0,0,0,0,0,0,0,0,0,0,DJ42,~
0)';
      PINUSE='GROUND';
      NO_LOAD_CHECK='Both';
      NO_IO_CHECK='Both';
      NO_ASSERT_CHECK='TRUE';
      NO_DIR_CHECK='TRUE';
      ALLOW_CONNECT='TRUE';
    'VSS'<186>:
      PIN_NUMBER='(0,0,0,0,0,0,0,0,0,0,0,0,0,0,0,0,0,0,0,0,0,0,0,0,0,0,0,0,DJ68,~
0)';
      PINUSE='GROUND';
      NO_LOAD_CHECK='Both';
      NO_IO_CHECK='Both';
      NO_ASSERT_CHECK='TRUE';
      NO_DIR_CHECK='TRUE';
      ALLOW_CONNECT='TRUE';
    'VSS'<185>:
      PIN_NUMBER='(0,0,0,0,0,0,0,0,0,0,0,0,0,0,0,0,0,0,0,0,0,0,0,0,0,0,0,0,DJ74,~
0)';
      PINUSE='GROUND';
      NO_LOAD_CHECK='Both';
      NO_IO_CHECK='Both';
      NO_ASSERT_CHECK='TRUE';
      NO_DIR_CHECK='TRUE';
      ALLOW_CONNECT='TRUE';
    'VSS'<184>:
      PIN_NUMBER='(0,0,0,0,0,0,0,0,0,0,0,0,0,0,0,0,0,0,0,0,0,0,0,0,0,0,0,0,DJ78,~
0)';
      PINUSE='GROUND';
      NO_LOAD_CHECK='Both';
      NO_IO_CHECK='Both';
      NO_ASSERT_CHECK='TRUE';
      NO_DIR_CHECK='TRUE';
      ALLOW_CONNECT='TRUE';
    'VSS'<183>:
      PIN_NUMBER='(0,0,0,0,0,0,0,0,0,0,0,0,0,0,0,0,0,0,0,0,0,0,0,0,0,0,0,0,DJ82,~
0)';
      PINUSE='GROUND';
      NO_LOAD_CHECK='Both';
      NO_IO_CHECK='Both';
      NO_ASSERT_CHECK='TRUE';
      NO_DIR_CHECK='TRUE';
      ALLOW_CONNECT='TRUE';
    'VSS'<182>:
      PIN_NUMBER='(0,0,0,0,0,0,0,0,0,0,0,0,0,0,0,0,0,0,0,0,0,0,0,0,0,0,0,0,DJ84,~
0)';
      PINUSE='GROUND';
      NO_LOAD_CHECK='Both';
      NO_IO_CHECK='Both';
      NO_ASSERT_CHECK='TRUE';
      NO_DIR_CHECK='TRUE';
      ALLOW_CONNECT='TRUE';
    'VSS'<181>:
      PIN_NUMBER='(0,0,0,0,0,0,0,0,0,0,0,0,0,0,0,0,0,0,0,0,0,0,0,0,0,0,0,0,DK7,0~
)';
      PINUSE='GROUND';
      NO_LOAD_CHECK='Both';
      NO_IO_CHECK='Both';
      NO_ASSERT_CHECK='TRUE';
      NO_DIR_CHECK='TRUE';
      ALLOW_CONNECT='TRUE';
    'VSS'<180>:
      PIN_NUMBER='(0,0,0,0,0,0,0,0,0,0,0,0,0,0,0,0,0,0,0,0,0,0,0,0,0,0,0,0,DK23,~
0)';
      PINUSE='GROUND';
      NO_LOAD_CHECK='Both';
      NO_IO_CHECK='Both';
      NO_ASSERT_CHECK='TRUE';
      NO_DIR_CHECK='TRUE';
      ALLOW_CONNECT='TRUE';
    'VSS'<179>:
      PIN_NUMBER='(0,0,0,0,0,0,0,0,0,0,0,0,0,0,0,0,0,0,0,0,0,0,0,0,0,0,0,0,DK29,~
0)';
      PINUSE='GROUND';
      NO_LOAD_CHECK='Both';
      NO_IO_CHECK='Both';
      NO_ASSERT_CHECK='TRUE';
      NO_DIR_CHECK='TRUE';
      ALLOW_CONNECT='TRUE';
    'VSS'<178>:
      PIN_NUMBER='(0,0,0,0,0,0,0,0,0,0,0,0,0,0,0,0,0,0,0,0,0,0,0,0,0,0,0,0,DK35,~
0)';
      PINUSE='GROUND';
      NO_LOAD_CHECK='Both';
      NO_IO_CHECK='Both';
      NO_ASSERT_CHECK='TRUE';
      NO_DIR_CHECK='TRUE';
      ALLOW_CONNECT='TRUE';
    'VSS'<177>:
      PIN_NUMBER='(0,0,0,0,0,0,0,0,0,0,0,0,0,0,0,0,0,0,0,0,0,0,0,0,0,0,0,0,DK39,~
0)';
      PINUSE='GROUND';
      NO_LOAD_CHECK='Both';
      NO_IO_CHECK='Both';
      NO_ASSERT_CHECK='TRUE';
      NO_DIR_CHECK='TRUE';
      ALLOW_CONNECT='TRUE';
    'VSS'<176>:
      PIN_NUMBER='(0,0,0,0,0,0,0,0,0,0,0,0,0,0,0,0,0,0,0,0,0,0,0,0,0,0,0,0,DK41,~
0)';
      PINUSE='GROUND';
      NO_LOAD_CHECK='Both';
      NO_IO_CHECK='Both';
      NO_ASSERT_CHECK='TRUE';
      NO_DIR_CHECK='TRUE';
      ALLOW_CONNECT='TRUE';
    'VSS'<175>:
      PIN_NUMBER='(0,0,0,0,0,0,0,0,0,0,0,0,0,0,0,0,0,0,0,0,0,0,0,0,0,0,0,0,DK73,~
0)';
      PINUSE='GROUND';
      NO_LOAD_CHECK='Both';
      NO_IO_CHECK='Both';
      NO_ASSERT_CHECK='TRUE';
      NO_DIR_CHECK='TRUE';
      ALLOW_CONNECT='TRUE';
    'VSS'<174>:
      PIN_NUMBER='(0,0,0,0,0,0,0,0,0,0,0,0,0,0,0,0,0,0,0,0,0,0,0,0,0,0,0,0,DK75,~
0)';
      PINUSE='GROUND';
      NO_LOAD_CHECK='Both';
      NO_IO_CHECK='Both';
      NO_ASSERT_CHECK='TRUE';
      NO_DIR_CHECK='TRUE';
      ALLOW_CONNECT='TRUE';
    'VSS'<173>:
      PIN_NUMBER='(0,0,0,0,0,0,0,0,0,0,0,0,0,0,0,0,0,0,0,0,0,0,0,0,0,0,0,0,DK77,~
0)';
      PINUSE='GROUND';
      NO_LOAD_CHECK='Both';
      NO_IO_CHECK='Both';
      NO_ASSERT_CHECK='TRUE';
      NO_DIR_CHECK='TRUE';
      ALLOW_CONNECT='TRUE';
    'VSS'<172>:
      PIN_NUMBER='(0,0,0,0,0,0,0,0,0,0,0,0,0,0,0,0,0,0,0,0,0,0,0,0,0,0,0,0,DK83,~
0)';
      PINUSE='GROUND';
      NO_LOAD_CHECK='Both';
      NO_IO_CHECK='Both';
      NO_ASSERT_CHECK='TRUE';
      NO_DIR_CHECK='TRUE';
      ALLOW_CONNECT='TRUE';
    'VSS'<171>:
      PIN_NUMBER='(0,0,0,0,0,0,0,0,0,0,0,0,0,0,0,0,0,0,0,0,0,0,0,0,0,0,0,0,DK85,~
0)';
      PINUSE='GROUND';
      NO_LOAD_CHECK='Both';
      NO_IO_CHECK='Both';
      NO_ASSERT_CHECK='TRUE';
      NO_DIR_CHECK='TRUE';
      ALLOW_CONNECT='TRUE';
    'VSS'<170>:
      PIN_NUMBER='(0,0,0,0,0,0,0,0,0,0,0,0,0,0,0,0,0,0,0,0,0,0,0,0,0,0,0,0,DL16,~
0)';
      PINUSE='GROUND';
      NO_LOAD_CHECK='Both';
      NO_IO_CHECK='Both';
      NO_ASSERT_CHECK='TRUE';
      NO_DIR_CHECK='TRUE';
      ALLOW_CONNECT='TRUE';
    'VSS'<169>:
      PIN_NUMBER='(0,0,0,0,0,0,0,0,0,0,0,0,0,0,0,0,0,0,0,0,0,0,0,0,0,0,0,0,DL18,~
0)';
      PINUSE='GROUND';
      NO_LOAD_CHECK='Both';
      NO_IO_CHECK='Both';
      NO_ASSERT_CHECK='TRUE';
      NO_DIR_CHECK='TRUE';
      ALLOW_CONNECT='TRUE';
    'VSS'<168>:
      PIN_NUMBER='(0,0,0,0,0,0,0,0,0,0,0,0,0,0,0,0,0,0,0,0,0,0,0,0,0,0,0,0,DL4,0~
)';
      PINUSE='GROUND';
      NO_LOAD_CHECK='Both';
      NO_IO_CHECK='Both';
      NO_ASSERT_CHECK='TRUE';
      NO_DIR_CHECK='TRUE';
      ALLOW_CONNECT='TRUE';
    'VSS'<167>:
      PIN_NUMBER='(0,0,0,0,0,0,0,0,0,0,0,0,0,0,0,0,0,0,0,0,0,0,0,0,0,0,0,0,DL22,~
0)';
      PINUSE='GROUND';
      NO_LOAD_CHECK='Both';
      NO_IO_CHECK='Both';
      NO_ASSERT_CHECK='TRUE';
      NO_DIR_CHECK='TRUE';
      ALLOW_CONNECT='TRUE';
    'VSS'<166>:
      PIN_NUMBER='(0,0,0,0,0,0,0,0,0,0,0,0,0,0,0,0,0,0,0,0,0,0,0,0,0,0,0,0,DL24,~
0)';
      PINUSE='GROUND';
      NO_LOAD_CHECK='Both';
      NO_IO_CHECK='Both';
      NO_ASSERT_CHECK='TRUE';
      NO_DIR_CHECK='TRUE';
      ALLOW_CONNECT='TRUE';
    'VSS'<165>:
      PIN_NUMBER='(0,0,0,0,0,0,0,0,0,0,0,0,0,0,0,0,0,0,0,0,0,0,0,0,0,0,0,0,DL28,~
0)';
      PINUSE='GROUND';
      NO_LOAD_CHECK='Both';
      NO_IO_CHECK='Both';
      NO_ASSERT_CHECK='TRUE';
      NO_DIR_CHECK='TRUE';
      ALLOW_CONNECT='TRUE';
    'VSS'<164>:
      PIN_NUMBER='(0,0,0,0,0,0,0,0,0,0,0,0,0,0,0,0,0,0,0,0,0,0,0,0,0,0,0,0,DL30,~
0)';
      PINUSE='GROUND';
      NO_LOAD_CHECK='Both';
      NO_IO_CHECK='Both';
      NO_ASSERT_CHECK='TRUE';
      NO_DIR_CHECK='TRUE';
      ALLOW_CONNECT='TRUE';
    'VSS'<163>:
      PIN_NUMBER='(0,0,0,0,0,0,0,0,0,0,0,0,0,0,0,0,0,0,0,0,0,0,0,0,0,0,0,0,DL34,~
0)';
      PINUSE='GROUND';
      NO_LOAD_CHECK='Both';
      NO_IO_CHECK='Both';
      NO_ASSERT_CHECK='TRUE';
      NO_DIR_CHECK='TRUE';
      ALLOW_CONNECT='TRUE';
    'VSS'<162>:
      PIN_NUMBER='(0,0,0,0,0,0,0,0,0,0,0,0,0,0,0,0,0,0,0,0,0,0,0,0,0,0,0,0,DL36,~
0)';
      PINUSE='GROUND';
      NO_LOAD_CHECK='Both';
      NO_IO_CHECK='Both';
      NO_ASSERT_CHECK='TRUE';
      NO_DIR_CHECK='TRUE';
      ALLOW_CONNECT='TRUE';
    'VSS'<161>:
      PIN_NUMBER='(0,0,0,0,0,0,0,0,0,0,0,0,0,0,0,0,0,0,0,0,0,0,0,0,0,0,0,0,DL40,~
0)';
      PINUSE='GROUND';
      NO_LOAD_CHECK='Both';
      NO_IO_CHECK='Both';
      NO_ASSERT_CHECK='TRUE';
      NO_DIR_CHECK='TRUE';
      ALLOW_CONNECT='TRUE';
    'VSS'<160>:
      PIN_NUMBER='(0,0,0,0,0,0,0,0,0,0,0,0,0,0,0,0,0,0,0,0,0,0,0,0,0,0,0,0,DL68,~
0)';
      PINUSE='GROUND';
      NO_LOAD_CHECK='Both';
      NO_IO_CHECK='Both';
      NO_ASSERT_CHECK='TRUE';
      NO_DIR_CHECK='TRUE';
      ALLOW_CONNECT='TRUE';
    'VSS'<159>:
      PIN_NUMBER='(0,0,0,0,0,0,0,0,0,0,0,0,0,0,0,0,0,0,0,0,0,0,0,0,0,0,0,0,DL70,~
0)';
      PINUSE='GROUND';
      NO_LOAD_CHECK='Both';
      NO_IO_CHECK='Both';
      NO_ASSERT_CHECK='TRUE';
      NO_DIR_CHECK='TRUE';
      ALLOW_CONNECT='TRUE';
    'VSS'<158>:
      PIN_NUMBER='(0,0,0,0,0,0,0,0,0,0,0,0,0,0,0,0,0,0,0,0,0,0,0,0,0,0,0,0,DL74,~
0)';
      PINUSE='GROUND';
      NO_LOAD_CHECK='Both';
      NO_IO_CHECK='Both';
      NO_ASSERT_CHECK='TRUE';
      NO_DIR_CHECK='TRUE';
      ALLOW_CONNECT='TRUE';
    'VSS'<157>:
      PIN_NUMBER='(0,0,0,0,0,0,0,0,0,0,0,0,0,0,0,0,0,0,0,0,0,0,0,0,0,0,0,0,DL76,~
0)';
      PINUSE='GROUND';
      NO_LOAD_CHECK='Both';
      NO_IO_CHECK='Both';
      NO_ASSERT_CHECK='TRUE';
      NO_DIR_CHECK='TRUE';
      ALLOW_CONNECT='TRUE';
    'VSS'<156>:
      PIN_NUMBER='(0,0,0,0,0,0,0,0,0,0,0,0,0,0,0,0,0,0,0,0,0,0,0,0,0,0,0,0,DL78,~
0)';
      PINUSE='GROUND';
      NO_LOAD_CHECK='Both';
      NO_IO_CHECK='Both';
      NO_ASSERT_CHECK='TRUE';
      NO_DIR_CHECK='TRUE';
      ALLOW_CONNECT='TRUE';
    'VSS'<155>:
      PIN_NUMBER='(0,0,0,0,0,0,0,0,0,0,0,0,0,0,0,0,0,0,0,0,0,0,0,0,0,0,0,0,DL80,~
0)';
      PINUSE='GROUND';
      NO_LOAD_CHECK='Both';
      NO_IO_CHECK='Both';
      NO_ASSERT_CHECK='TRUE';
      NO_DIR_CHECK='TRUE';
      ALLOW_CONNECT='TRUE';
    'VSS'<154>:
      PIN_NUMBER='(0,0,0,0,0,0,0,0,0,0,0,0,0,0,0,0,0,0,0,0,0,0,0,0,0,0,0,0,DM15,~
0)';
      PINUSE='GROUND';
      NO_LOAD_CHECK='Both';
      NO_IO_CHECK='Both';
      NO_ASSERT_CHECK='TRUE';
      NO_DIR_CHECK='TRUE';
      ALLOW_CONNECT='TRUE';
    'VSS'<153>:
      PIN_NUMBER='(0,0,0,0,0,0,0,0,0,0,0,0,0,0,0,0,0,0,0,0,0,0,0,0,0,0,0,0,H45,0~
)';
      PINUSE='GROUND';
      NO_LOAD_CHECK='Both';
      NO_IO_CHECK='Both';
      NO_ASSERT_CHECK='TRUE';
      NO_DIR_CHECK='TRUE';
      ALLOW_CONNECT='TRUE';
    'VSS'<152>:
      PIN_NUMBER='(0,0,0,0,0,0,0,0,0,0,0,0,0,0,0,0,0,0,0,0,0,0,0,0,0,0,0,0,DM25,~
0)';
      PINUSE='GROUND';
      NO_LOAD_CHECK='Both';
      NO_IO_CHECK='Both';
      NO_ASSERT_CHECK='TRUE';
      NO_DIR_CHECK='TRUE';
      ALLOW_CONNECT='TRUE';
    'VSS'<151>:
      PIN_NUMBER='(0,0,0,0,0,0,0,0,0,0,0,0,0,0,0,0,0,0,0,0,0,0,0,0,0,0,0,0,DM27,~
0)';
      PINUSE='GROUND';
      NO_LOAD_CHECK='Both';
      NO_IO_CHECK='Both';
      NO_ASSERT_CHECK='TRUE';
      NO_DIR_CHECK='TRUE';
      ALLOW_CONNECT='TRUE';
    'VSS'<150>:
      PIN_NUMBER='(0,0,0,0,0,0,0,0,0,0,0,0,0,0,0,0,0,0,0,0,0,0,0,0,0,0,0,0,DM31,~
0)';
      PINUSE='GROUND';
      NO_LOAD_CHECK='Both';
      NO_IO_CHECK='Both';
      NO_ASSERT_CHECK='TRUE';
      NO_DIR_CHECK='TRUE';
      ALLOW_CONNECT='TRUE';
    'VSS'<149>:
      PIN_NUMBER='(0,0,0,0,0,0,0,0,0,0,0,0,0,0,0,0,0,0,0,0,0,0,0,0,0,0,0,0,DM33,~
0)';
      PINUSE='GROUND';
      NO_LOAD_CHECK='Both';
      NO_IO_CHECK='Both';
      NO_ASSERT_CHECK='TRUE';
      NO_DIR_CHECK='TRUE';
      ALLOW_CONNECT='TRUE';
    'VSS'<148>:
      PIN_NUMBER='(0,0,0,0,0,0,0,0,0,0,0,0,0,0,0,0,0,0,0,0,0,0,0,0,0,0,0,0,DM37,~
0)';
      PINUSE='GROUND';
      NO_LOAD_CHECK='Both';
      NO_IO_CHECK='Both';
      NO_ASSERT_CHECK='TRUE';
      NO_DIR_CHECK='TRUE';
      ALLOW_CONNECT='TRUE';
    'VSS'<147>:
      PIN_NUMBER='(0,0,0,0,0,0,0,0,0,0,0,0,0,0,0,0,0,0,0,0,0,0,0,0,0,0,0,0,DM39,~
0)';
      PINUSE='GROUND';
      NO_LOAD_CHECK='Both';
      NO_IO_CHECK='Both';
      NO_ASSERT_CHECK='TRUE';
      NO_DIR_CHECK='TRUE';
      ALLOW_CONNECT='TRUE';
    'VSS'<146>:
      PIN_NUMBER='(0,0,0,0,0,0,0,0,0,0,0,0,0,0,0,0,0,0,0,0,0,0,0,0,0,0,0,0,DM65,~
0)';
      PINUSE='GROUND';
      NO_LOAD_CHECK='Both';
      NO_IO_CHECK='Both';
      NO_ASSERT_CHECK='TRUE';
      NO_DIR_CHECK='TRUE';
      ALLOW_CONNECT='TRUE';
    'VSS'<145>:
      PIN_NUMBER='(0,0,0,0,0,0,0,0,0,0,0,0,0,0,0,0,0,0,0,0,0,0,0,0,0,0,0,0,DM73,~
0)';
      PINUSE='GROUND';
      NO_LOAD_CHECK='Both';
      NO_IO_CHECK='Both';
      NO_ASSERT_CHECK='TRUE';
      NO_DIR_CHECK='TRUE';
      ALLOW_CONNECT='TRUE';
    'VSS'<144>:
      PIN_NUMBER='(0,0,0,0,0,0,0,0,0,0,0,0,0,0,0,0,0,0,0,0,0,0,0,0,0,0,0,0,DM77,~
0)';
      PINUSE='GROUND';
      NO_LOAD_CHECK='Both';
      NO_IO_CHECK='Both';
      NO_ASSERT_CHECK='TRUE';
      NO_DIR_CHECK='TRUE';
      ALLOW_CONNECT='TRUE';
    'VSS'<143>:
      PIN_NUMBER='(0,0,0,0,0,0,0,0,0,0,0,0,0,0,0,0,0,0,0,0,0,0,0,0,0,0,0,0,DM83,~
0)';
      PINUSE='GROUND';
      NO_LOAD_CHECK='Both';
      NO_IO_CHECK='Both';
      NO_ASSERT_CHECK='TRUE';
      NO_DIR_CHECK='TRUE';
      ALLOW_CONNECT='TRUE';
    'VSS'<142>:
      PIN_NUMBER='(0,0,0,0,0,0,0,0,0,0,0,0,0,0,0,0,0,0,0,0,0,0,0,0,0,0,0,0,DN2,0~
)';
      PINUSE='GROUND';
      NO_LOAD_CHECK='Both';
      NO_IO_CHECK='Both';
      NO_ASSERT_CHECK='TRUE';
      NO_DIR_CHECK='TRUE';
      ALLOW_CONNECT='TRUE';
    'VSS'<141>:
      PIN_NUMBER='(0,0,0,0,0,0,0,0,0,0,0,0,0,0,0,0,0,0,0,0,0,0,0,0,0,0,0,0,BH17,~
0)';
      PINUSE='GROUND';
      NO_LOAD_CHECK='Both';
      NO_IO_CHECK='Both';
      NO_ASSERT_CHECK='TRUE';
      NO_DIR_CHECK='TRUE';
      ALLOW_CONNECT='TRUE';
    'VSS'<140>:
      PIN_NUMBER='(0,0,0,0,0,0,0,0,0,0,0,0,0,0,0,0,0,0,0,0,0,0,0,0,0,0,0,0,DN12,~
0)';
      PINUSE='GROUND';
      NO_LOAD_CHECK='Both';
      NO_IO_CHECK='Both';
      NO_ASSERT_CHECK='TRUE';
      NO_DIR_CHECK='TRUE';
      ALLOW_CONNECT='TRUE';
    'VSS'<139>:
      PIN_NUMBER='(0,0,0,0,0,0,0,0,0,0,0,0,0,0,0,0,0,0,0,0,0,0,0,0,0,0,0,0,DN22,~
0)';
      PINUSE='GROUND';
      NO_LOAD_CHECK='Both';
      NO_IO_CHECK='Both';
      NO_ASSERT_CHECK='TRUE';
      NO_DIR_CHECK='TRUE';
      ALLOW_CONNECT='TRUE';
    'VSS'<138>:
      PIN_NUMBER='(0,0,0,0,0,0,0,0,0,0,0,0,0,0,0,0,0,0,0,0,0,0,0,0,0,0,0,0,DN26,~
0)';
      PINUSE='GROUND';
      NO_LOAD_CHECK='Both';
      NO_IO_CHECK='Both';
      NO_ASSERT_CHECK='TRUE';
      NO_DIR_CHECK='TRUE';
      ALLOW_CONNECT='TRUE';
    'VSS'<137>:
      PIN_NUMBER='(0,0,0,0,0,0,0,0,0,0,0,0,0,0,0,0,0,0,0,0,0,0,0,0,0,0,0,0,DN32,~
0)';
      PINUSE='GROUND';
      NO_LOAD_CHECK='Both';
      NO_IO_CHECK='Both';
      NO_ASSERT_CHECK='TRUE';
      NO_DIR_CHECK='TRUE';
      ALLOW_CONNECT='TRUE';
    'VSS'<136>:
      PIN_NUMBER='(0,0,0,0,0,0,0,0,0,0,0,0,0,0,0,0,0,0,0,0,0,0,0,0,0,0,0,0,DN38,~
0)';
      PINUSE='GROUND';
      NO_LOAD_CHECK='Both';
      NO_IO_CHECK='Both';
      NO_ASSERT_CHECK='TRUE';
      NO_DIR_CHECK='TRUE';
      ALLOW_CONNECT='TRUE';
    'VSS'<135>:
      PIN_NUMBER='(0,0,0,0,0,0,0,0,0,0,0,0,0,0,0,0,0,0,0,0,0,0,0,0,0,0,0,0,DN68,~
0)';
      PINUSE='GROUND';
      NO_LOAD_CHECK='Both';
      NO_IO_CHECK='Both';
      NO_ASSERT_CHECK='TRUE';
      NO_DIR_CHECK='TRUE';
      ALLOW_CONNECT='TRUE';
    'VSS'<134>:
      PIN_NUMBER='(0,0,0,0,0,0,0,0,0,0,0,0,0,0,0,0,0,0,0,0,0,0,0,0,0,0,0,0,DN72,~
0)';
      PINUSE='GROUND';
      NO_LOAD_CHECK='Both';
      NO_IO_CHECK='Both';
      NO_ASSERT_CHECK='TRUE';
      NO_DIR_CHECK='TRUE';
      ALLOW_CONNECT='TRUE';
    'VSS'<133>:
      PIN_NUMBER='(0,0,0,0,0,0,0,0,0,0,0,0,0,0,0,0,0,0,0,0,0,0,0,0,0,0,0,0,0,DN7~
8)';
      PINUSE='GROUND';
      NO_LOAD_CHECK='Both';
      NO_IO_CHECK='Both';
      NO_ASSERT_CHECK='TRUE';
      NO_DIR_CHECK='TRUE';
      ALLOW_CONNECT='TRUE';
    'VSS'<132>:
      PIN_NUMBER='(0,0,0,0,0,0,0,0,0,0,0,0,0,0,0,0,0,0,0,0,0,0,0,0,0,0,0,0,0,DP6~
7)';
      PINUSE='GROUND';
      NO_LOAD_CHECK='Both';
      NO_IO_CHECK='Both';
      NO_ASSERT_CHECK='TRUE';
      NO_DIR_CHECK='TRUE';
      ALLOW_CONNECT='TRUE';
    'VSS'<131>:
      PIN_NUMBER='(0,0,0,0,0,0,0,0,0,0,0,0,0,0,0,0,0,0,0,0,0,0,0,0,0,0,0,0,0,DP6~
9)';
      PINUSE='GROUND';
      NO_LOAD_CHECK='Both';
      NO_IO_CHECK='Both';
      NO_ASSERT_CHECK='TRUE';
      NO_DIR_CHECK='TRUE';
      ALLOW_CONNECT='TRUE';
    'VSS'<130>:
      PIN_NUMBER='(0,0,0,0,0,0,0,0,0,0,0,0,0,0,0,0,0,0,0,0,0,0,0,0,0,0,0,0,0,DP7~
1)';
      PINUSE='GROUND';
      NO_LOAD_CHECK='Both';
      NO_IO_CHECK='Both';
      NO_ASSERT_CHECK='TRUE';
      NO_DIR_CHECK='TRUE';
      ALLOW_CONNECT='TRUE';
    'VSS'<129>:
      PIN_NUMBER='(0,0,0,0,0,0,0,0,0,0,0,0,0,0,0,0,0,0,0,0,0,0,0,0,0,0,0,0,0,DP8~
1)';
      PINUSE='GROUND';
      NO_LOAD_CHECK='Both';
      NO_IO_CHECK='Both';
      NO_ASSERT_CHECK='TRUE';
      NO_DIR_CHECK='TRUE';
      ALLOW_CONNECT='TRUE';
    'VSS'<128>:
      PIN_NUMBER='(0,0,0,0,0,0,0,0,0,0,0,0,0,0,0,0,0,0,0,0,0,0,0,0,0,0,0,0,0,DP8~
3)';
      PINUSE='GROUND';
      NO_LOAD_CHECK='Both';
      NO_IO_CHECK='Both';
      NO_ASSERT_CHECK='TRUE';
      NO_DIR_CHECK='TRUE';
      ALLOW_CONNECT='TRUE';
    'VSS'<127>:
      PIN_NUMBER='(0,0,0,0,0,0,0,0,0,0,0,0,0,0,0,0,0,0,0,0,0,0,0,0,0,0,0,0,0,BR2~
6)';
      PINUSE='GROUND';
      NO_LOAD_CHECK='Both';
      NO_IO_CHECK='Both';
      NO_ASSERT_CHECK='TRUE';
      NO_DIR_CHECK='TRUE';
      ALLOW_CONNECT='TRUE';
    'VSS'<126>:
      PIN_NUMBER='(0,0,0,0,0,0,0,0,0,0,0,0,0,0,0,0,0,0,0,0,0,0,0,0,0,0,0,0,0,DR6~
)';
      PINUSE='GROUND';
      NO_LOAD_CHECK='Both';
      NO_IO_CHECK='Both';
      NO_ASSERT_CHECK='TRUE';
      NO_DIR_CHECK='TRUE';
      ALLOW_CONNECT='TRUE';
    'VSS'<125>:
      PIN_NUMBER='(0,0,0,0,0,0,0,0,0,0,0,0,0,0,0,0,0,0,0,0,0,0,0,0,0,0,0,0,0,CA2~
0)';
      PINUSE='GROUND';
      NO_LOAD_CHECK='Both';
      NO_IO_CHECK='Both';
      NO_ASSERT_CHECK='TRUE';
      NO_DIR_CHECK='TRUE';
      ALLOW_CONNECT='TRUE';
    'VSS'<124>:
      PIN_NUMBER='(0,0,0,0,0,0,0,0,0,0,0,0,0,0,0,0,0,0,0,0,0,0,0,0,0,0,0,0,0,CL2~
2)';
      PINUSE='GROUND';
      NO_LOAD_CHECK='Both';
      NO_IO_CHECK='Both';
      NO_ASSERT_CHECK='TRUE';
      NO_DIR_CHECK='TRUE';
      ALLOW_CONNECT='TRUE';
    'VSS'<123>:
      PIN_NUMBER='(0,0,0,0,0,0,0,0,0,0,0,0,0,0,0,0,0,0,0,0,0,0,0,0,0,0,0,0,0,DR2~
0)';
      PINUSE='GROUND';
      NO_LOAD_CHECK='Both';
      NO_IO_CHECK='Both';
      NO_ASSERT_CHECK='TRUE';
      NO_DIR_CHECK='TRUE';
      ALLOW_CONNECT='TRUE';
    'VSS'<122>:
      PIN_NUMBER='(0,0,0,0,0,0,0,0,0,0,0,0,0,0,0,0,0,0,0,0,0,0,0,0,0,0,0,0,0,DR2~
2)';
      PINUSE='GROUND';
      NO_LOAD_CHECK='Both';
      NO_IO_CHECK='Both';
      NO_ASSERT_CHECK='TRUE';
      NO_DIR_CHECK='TRUE';
      ALLOW_CONNECT='TRUE';
    'VSS'<121>:
      PIN_NUMBER='(0,0,0,0,0,0,0,0,0,0,0,0,0,0,0,0,0,0,0,0,0,0,0,0,0,0,0,0,0,DR2~
4)';
      PINUSE='GROUND';
      NO_LOAD_CHECK='Both';
      NO_IO_CHECK='Both';
      NO_ASSERT_CHECK='TRUE';
      NO_DIR_CHECK='TRUE';
      ALLOW_CONNECT='TRUE';
    'VSS'<120>:
      PIN_NUMBER='(0,0,0,0,0,0,0,0,0,0,0,0,0,0,0,0,0,0,0,0,0,0,0,0,0,0,0,0,0,DR2~
6)';
      PINUSE='GROUND';
      NO_LOAD_CHECK='Both';
      NO_IO_CHECK='Both';
      NO_ASSERT_CHECK='TRUE';
      NO_DIR_CHECK='TRUE';
      ALLOW_CONNECT='TRUE';
    'VSS'<119>:
      PIN_NUMBER='(0,0,0,0,0,0,0,0,0,0,0,0,0,0,0,0,0,0,0,0,0,0,0,0,0,0,0,0,0,DR2~
8)';
      PINUSE='GROUND';
      NO_LOAD_CHECK='Both';
      NO_IO_CHECK='Both';
      NO_ASSERT_CHECK='TRUE';
      NO_DIR_CHECK='TRUE';
      ALLOW_CONNECT='TRUE';
    'VSS'<118>:
      PIN_NUMBER='(0,0,0,0,0,0,0,0,0,0,0,0,0,0,0,0,0,0,0,0,0,0,0,0,0,0,0,0,0,DR3~
0)';
      PINUSE='GROUND';
      NO_LOAD_CHECK='Both';
      NO_IO_CHECK='Both';
      NO_ASSERT_CHECK='TRUE';
      NO_DIR_CHECK='TRUE';
      ALLOW_CONNECT='TRUE';
    'VSS'<117>:
      PIN_NUMBER='(0,0,0,0,0,0,0,0,0,0,0,0,0,0,0,0,0,0,0,0,0,0,0,0,0,0,0,0,0,DR3~
2)';
      PINUSE='GROUND';
      NO_LOAD_CHECK='Both';
      NO_IO_CHECK='Both';
      NO_ASSERT_CHECK='TRUE';
      NO_DIR_CHECK='TRUE';
      ALLOW_CONNECT='TRUE';
    'VSS'<116>:
      PIN_NUMBER='(0,0,0,0,0,0,0,0,0,0,0,0,0,0,0,0,0,0,0,0,0,0,0,0,0,0,0,0,0,DR3~
4)';
      PINUSE='GROUND';
      NO_LOAD_CHECK='Both';
      NO_IO_CHECK='Both';
      NO_ASSERT_CHECK='TRUE';
      NO_DIR_CHECK='TRUE';
      ALLOW_CONNECT='TRUE';
    'VSS'<115>:
      PIN_NUMBER='(0,0,0,0,0,0,0,0,0,0,0,0,0,0,0,0,0,0,0,0,0,0,0,0,0,0,0,0,0,DR3~
6)';
      PINUSE='GROUND';
      NO_LOAD_CHECK='Both';
      NO_IO_CHECK='Both';
      NO_ASSERT_CHECK='TRUE';
      NO_DIR_CHECK='TRUE';
      ALLOW_CONNECT='TRUE';
    'VSS'<114>:
      PIN_NUMBER='(0,0,0,0,0,0,0,0,0,0,0,0,0,0,0,0,0,0,0,0,0,0,0,0,0,0,0,0,0,DR3~
8)';
      PINUSE='GROUND';
      NO_LOAD_CHECK='Both';
      NO_IO_CHECK='Both';
      NO_ASSERT_CHECK='TRUE';
      NO_DIR_CHECK='TRUE';
      ALLOW_CONNECT='TRUE';
    'VSS'<113>:
      PIN_NUMBER='(0,0,0,0,0,0,0,0,0,0,0,0,0,0,0,0,0,0,0,0,0,0,0,0,0,0,0,0,0,DR4~
0)';
      PINUSE='GROUND';
      NO_LOAD_CHECK='Both';
      NO_IO_CHECK='Both';
      NO_ASSERT_CHECK='TRUE';
      NO_DIR_CHECK='TRUE';
      ALLOW_CONNECT='TRUE';
    'VSS'<112>:
      PIN_NUMBER='(0,0,0,0,0,0,0,0,0,0,0,0,0,0,0,0,0,0,0,0,0,0,0,0,0,0,0,0,0,DR4~
2)';
      PINUSE='GROUND';
      NO_LOAD_CHECK='Both';
      NO_IO_CHECK='Both';
      NO_ASSERT_CHECK='TRUE';
      NO_DIR_CHECK='TRUE';
      ALLOW_CONNECT='TRUE';
    'VSS'<111>:
      PIN_NUMBER='(0,0,0,0,0,0,0,0,0,0,0,0,0,0,0,0,0,0,0,0,0,0,0,0,0,0,0,0,0,DR6~
6)';
      PINUSE='GROUND';
      NO_LOAD_CHECK='Both';
      NO_IO_CHECK='Both';
      NO_ASSERT_CHECK='TRUE';
      NO_DIR_CHECK='TRUE';
      ALLOW_CONNECT='TRUE';
    'VSS'<110>:
      PIN_NUMBER='(0,0,0,0,0,0,0,0,0,0,0,0,0,0,0,0,0,0,0,0,0,0,0,0,0,0,0,0,0,DR6~
8)';
      PINUSE='GROUND';
      NO_LOAD_CHECK='Both';
      NO_IO_CHECK='Both';
      NO_ASSERT_CHECK='TRUE';
      NO_DIR_CHECK='TRUE';
      ALLOW_CONNECT='TRUE';
    'VSS'<109>:
      PIN_NUMBER='(0,0,0,0,0,0,0,0,0,0,0,0,0,0,0,0,0,0,0,0,0,0,0,0,0,0,0,0,0,DR7~
0)';
      PINUSE='GROUND';
      NO_LOAD_CHECK='Both';
      NO_IO_CHECK='Both';
      NO_ASSERT_CHECK='TRUE';
      NO_DIR_CHECK='TRUE';
      ALLOW_CONNECT='TRUE';
    'VSS'<108>:
      PIN_NUMBER='(0,0,0,0,0,0,0,0,0,0,0,0,0,0,0,0,0,0,0,0,0,0,0,0,0,0,0,0,0,DR7~
2)';
      PINUSE='GROUND';
      NO_LOAD_CHECK='Both';
      NO_IO_CHECK='Both';
      NO_ASSERT_CHECK='TRUE';
      NO_DIR_CHECK='TRUE';
      ALLOW_CONNECT='TRUE';
    'VSS'<107>:
      PIN_NUMBER='(0,0,0,0,0,0,0,0,0,0,0,0,0,0,0,0,0,0,0,0,0,0,0,0,0,0,0,0,0,DR7~
4)';
      PINUSE='GROUND';
      NO_LOAD_CHECK='Both';
      NO_IO_CHECK='Both';
      NO_ASSERT_CHECK='TRUE';
      NO_DIR_CHECK='TRUE';
      ALLOW_CONNECT='TRUE';
    'VSS'<106>:
      PIN_NUMBER='(0,0,0,0,0,0,0,0,0,0,0,0,0,0,0,0,0,0,0,0,0,0,0,0,0,0,0,0,0,DR7~
6)';
      PINUSE='GROUND';
      NO_LOAD_CHECK='Both';
      NO_IO_CHECK='Both';
      NO_ASSERT_CHECK='TRUE';
      NO_DIR_CHECK='TRUE';
      ALLOW_CONNECT='TRUE';
    'VSS'<105>:
      PIN_NUMBER='(0,0,0,0,0,0,0,0,0,0,0,0,0,0,0,0,0,0,0,0,0,0,0,0,0,0,0,0,0,DR7~
8)';
      PINUSE='GROUND';
      NO_LOAD_CHECK='Both';
      NO_IO_CHECK='Both';
      NO_ASSERT_CHECK='TRUE';
      NO_DIR_CHECK='TRUE';
      ALLOW_CONNECT='TRUE';
    'VSS'<104>:
      PIN_NUMBER='(0,0,0,0,0,0,0,0,0,0,0,0,0,0,0,0,0,0,0,0,0,0,0,0,0,0,0,0,0,DT3~
)';
      PINUSE='GROUND';
      NO_LOAD_CHECK='Both';
      NO_IO_CHECK='Both';
      NO_ASSERT_CHECK='TRUE';
      NO_DIR_CHECK='TRUE';
      ALLOW_CONNECT='TRUE';
    'VSS'<103>:
      PIN_NUMBER='(0,0,0,0,0,0,0,0,0,0,0,0,0,0,0,0,0,0,0,0,0,0,0,0,0,0,0,0,0,DT1~
7)';
      PINUSE='GROUND';
      NO_LOAD_CHECK='Both';
      NO_IO_CHECK='Both';
      NO_ASSERT_CHECK='TRUE';
      NO_DIR_CHECK='TRUE';
      ALLOW_CONNECT='TRUE';
    'VSS'<102>:
      PIN_NUMBER='(0,0,0,0,0,0,0,0,0,0,0,0,0,0,0,0,0,0,0,0,0,0,0,0,0,0,0,0,0,DH2~
1)';
      PINUSE='GROUND';
      NO_LOAD_CHECK='Both';
      NO_IO_CHECK='Both';
      NO_ASSERT_CHECK='TRUE';
      NO_DIR_CHECK='TRUE';
      ALLOW_CONNECT='TRUE';
    'VSS'<101>:
      PIN_NUMBER='(0,0,0,0,0,0,0,0,0,0,0,0,0,0,0,0,0,0,0,0,0,0,0,0,0,0,0,0,0,DT6~
5)';
      PINUSE='GROUND';
      NO_LOAD_CHECK='Both';
      NO_IO_CHECK='Both';
      NO_ASSERT_CHECK='TRUE';
      NO_DIR_CHECK='TRUE';
      ALLOW_CONNECT='TRUE';
    'VSS'<100>:
      PIN_NUMBER='(0,0,0,0,0,0,0,0,0,0,0,0,0,0,0,0,0,0,0,0,0,0,0,0,0,0,0,0,0,DT6~
9)';
      PINUSE='GROUND';
      NO_LOAD_CHECK='Both';
      NO_IO_CHECK='Both';
      NO_ASSERT_CHECK='TRUE';
      NO_DIR_CHECK='TRUE';
      ALLOW_CONNECT='TRUE';
    'VSS'<99>:
      PIN_NUMBER='(0,0,0,0,0,0,0,0,0,0,0,0,0,0,0,0,0,0,0,0,0,0,0,0,0,0,0,0,0,DT7~
9)';
      PINUSE='GROUND';
      NO_LOAD_CHECK='Both';
      NO_IO_CHECK='Both';
      NO_ASSERT_CHECK='TRUE';
      NO_DIR_CHECK='TRUE';
      ALLOW_CONNECT='TRUE';
    'VSS'<98>:
      PIN_NUMBER='(0,0,0,0,0,0,0,0,0,0,0,0,0,0,0,0,0,0,0,0,0,0,0,0,0,0,0,0,0,DT8~
3)';
      PINUSE='GROUND';
      NO_LOAD_CHECK='Both';
      NO_IO_CHECK='Both';
      NO_ASSERT_CHECK='TRUE';
      NO_DIR_CHECK='TRUE';
      ALLOW_CONNECT='TRUE';
    'VSS'<97>:
      PIN_NUMBER='(0,0,0,0,0,0,0,0,0,0,0,0,0,0,0,0,0,0,0,0,0,0,0,0,0,0,0,0,0,DT8~
5)';
      PINUSE='GROUND';
      NO_LOAD_CHECK='Both';
      NO_IO_CHECK='Both';
      NO_ASSERT_CHECK='TRUE';
      NO_DIR_CHECK='TRUE';
      ALLOW_CONNECT='TRUE';
    'VSS'<96>:
      PIN_NUMBER='(0,0,0,0,0,0,0,0,0,0,0,0,0,0,0,0,0,0,0,0,0,0,0,0,0,0,0,0,0,DU1~
0)';
      PINUSE='GROUND';
      NO_LOAD_CHECK='Both';
      NO_IO_CHECK='Both';
      NO_ASSERT_CHECK='TRUE';
      NO_DIR_CHECK='TRUE';
      ALLOW_CONNECT='TRUE';
    'VSS'<95>:
      PIN_NUMBER='(0,0,0,0,0,0,0,0,0,0,0,0,0,0,0,0,0,0,0,0,0,0,0,0,0,0,0,0,0,DU1~
4)';
      PINUSE='GROUND';
      NO_LOAD_CHECK='Both';
      NO_IO_CHECK='Both';
      NO_ASSERT_CHECK='TRUE';
      NO_DIR_CHECK='TRUE';
      ALLOW_CONNECT='TRUE';
    'VSS'<94>:
      PIN_NUMBER='(0,0,0,0,0,0,0,0,0,0,0,0,0,0,0,0,0,0,0,0,0,0,0,0,0,0,0,0,0,CN1~
4)';
      PINUSE='GROUND';
      NO_LOAD_CHECK='Both';
      NO_IO_CHECK='Both';
      NO_ASSERT_CHECK='TRUE';
      NO_DIR_CHECK='TRUE';
      ALLOW_CONNECT='TRUE';
    'VSS'<93>:
      PIN_NUMBER='(0,0,0,0,0,0,0,0,0,0,0,0,0,0,0,0,0,0,0,0,0,0,0,0,0,0,0,0,0,DU2~
2)';
      PINUSE='GROUND';
      NO_LOAD_CHECK='Both';
      NO_IO_CHECK='Both';
      NO_ASSERT_CHECK='TRUE';
      NO_DIR_CHECK='TRUE';
      ALLOW_CONNECT='TRUE';
    'VSS'<92>:
      PIN_NUMBER='(0,0,0,0,0,0,0,0,0,0,0,0,0,0,0,0,0,0,0,0,0,0,0,0,0,0,0,0,0,DU2~
6)';
      PINUSE='GROUND';
      NO_LOAD_CHECK='Both';
      NO_IO_CHECK='Both';
      NO_ASSERT_CHECK='TRUE';
      NO_DIR_CHECK='TRUE';
      ALLOW_CONNECT='TRUE';
    'VSS'<91>:
      PIN_NUMBER='(0,0,0,0,0,0,0,0,0,0,0,0,0,0,0,0,0,0,0,0,0,0,0,0,0,0,0,0,0,DU3~
2)';
      PINUSE='GROUND';
      NO_LOAD_CHECK='Both';
      NO_IO_CHECK='Both';
      NO_ASSERT_CHECK='TRUE';
      NO_DIR_CHECK='TRUE';
      ALLOW_CONNECT='TRUE';
    'VSS'<90>:
      PIN_NUMBER='(0,0,0,0,0,0,0,0,0,0,0,0,0,0,0,0,0,0,0,0,0,0,0,0,0,0,0,0,0,DU3~
8)';
      PINUSE='GROUND';
      NO_LOAD_CHECK='Both';
      NO_IO_CHECK='Both';
      NO_ASSERT_CHECK='TRUE';
      NO_DIR_CHECK='TRUE';
      ALLOW_CONNECT='TRUE';
    'VSS'<89>:
      PIN_NUMBER='(0,0,0,0,0,0,0,0,0,0,0,0,0,0,0,0,0,0,0,0,0,0,0,0,0,0,0,0,0,DU7~
0)';
      PINUSE='GROUND';
      NO_LOAD_CHECK='Both';
      NO_IO_CHECK='Both';
      NO_ASSERT_CHECK='TRUE';
      NO_DIR_CHECK='TRUE';
      ALLOW_CONNECT='TRUE';
    'VSS'<88>:
      PIN_NUMBER='(0,0,0,0,0,0,0,0,0,0,0,0,0,0,0,0,0,0,0,0,0,0,0,0,0,0,0,0,0,DU7~
2)';
      PINUSE='GROUND';
      NO_LOAD_CHECK='Both';
      NO_IO_CHECK='Both';
      NO_ASSERT_CHECK='TRUE';
      NO_DIR_CHECK='TRUE';
      ALLOW_CONNECT='TRUE';
    'VSS'<87>:
      PIN_NUMBER='(0,0,0,0,0,0,0,0,0,0,0,0,0,0,0,0,0,0,0,0,0,0,0,0,0,0,0,0,0,DU7~
8)';
      PINUSE='GROUND';
      NO_LOAD_CHECK='Both';
      NO_IO_CHECK='Both';
      NO_ASSERT_CHECK='TRUE';
      NO_DIR_CHECK='TRUE';
      ALLOW_CONNECT='TRUE';
    'VSS'<86>:
      PIN_NUMBER='(0,0,0,0,0,0,0,0,0,0,0,0,0,0,0,0,0,0,0,0,0,0,0,0,0,0,0,0,0,DU8~
0)';
      PINUSE='GROUND';
      NO_LOAD_CHECK='Both';
      NO_IO_CHECK='Both';
      NO_ASSERT_CHECK='TRUE';
      NO_DIR_CHECK='TRUE';
      ALLOW_CONNECT='TRUE';
    'VSS'<85>:
      PIN_NUMBER='(0,0,0,0,0,0,0,0,0,0,0,0,0,0,0,0,0,0,0,0,0,0,0,0,0,0,0,0,0,DU8~
2)';
      PINUSE='GROUND';
      NO_LOAD_CHECK='Both';
      NO_IO_CHECK='Both';
      NO_ASSERT_CHECK='TRUE';
      NO_DIR_CHECK='TRUE';
      ALLOW_CONNECT='TRUE';
    'VSS'<84>:
      PIN_NUMBER='(0,0,0,0,0,0,0,0,0,0,0,0,0,0,0,0,0,0,0,0,0,0,0,0,0,0,0,0,0,DU8~
4)';
      PINUSE='GROUND';
      NO_LOAD_CHECK='Both';
      NO_IO_CHECK='Both';
      NO_ASSERT_CHECK='TRUE';
      NO_DIR_CHECK='TRUE';
      ALLOW_CONNECT='TRUE';
    'VSS'<83>:
      PIN_NUMBER='(0,0,0,0,0,0,0,0,0,0,0,0,0,0,0,0,0,0,0,0,0,0,0,0,0,0,0,0,0,DV2~
1)';
      PINUSE='GROUND';
      NO_LOAD_CHECK='Both';
      NO_IO_CHECK='Both';
      NO_ASSERT_CHECK='TRUE';
      NO_DIR_CHECK='TRUE';
      ALLOW_CONNECT='TRUE';
    'VSS'<82>:
      PIN_NUMBER='(0,0,0,0,0,0,0,0,0,0,0,0,0,0,0,0,0,0,0,0,0,0,0,0,0,0,0,0,0,DV2~
5)';
      PINUSE='GROUND';
      NO_LOAD_CHECK='Both';
      NO_IO_CHECK='Both';
      NO_ASSERT_CHECK='TRUE';
      NO_DIR_CHECK='TRUE';
      ALLOW_CONNECT='TRUE';
    'VSS'<81>:
      PIN_NUMBER='(0,0,0,0,0,0,0,0,0,0,0,0,0,0,0,0,0,0,0,0,0,0,0,0,0,0,0,0,0,DV2~
7)';
      PINUSE='GROUND';
      NO_LOAD_CHECK='Both';
      NO_IO_CHECK='Both';
      NO_ASSERT_CHECK='TRUE';
      NO_DIR_CHECK='TRUE';
      ALLOW_CONNECT='TRUE';
    'VSS'<80>:
      PIN_NUMBER='(0,0,0,0,0,0,0,0,0,0,0,0,0,0,0,0,0,0,0,0,0,0,0,0,0,0,0,0,0,DV3~
1)';
      PINUSE='GROUND';
      NO_LOAD_CHECK='Both';
      NO_IO_CHECK='Both';
      NO_ASSERT_CHECK='TRUE';
      NO_DIR_CHECK='TRUE';
      ALLOW_CONNECT='TRUE';
    'VSS'<79>:
      PIN_NUMBER='(0,0,0,0,0,0,0,0,0,0,0,0,0,0,0,0,0,0,0,0,0,0,0,0,0,0,0,0,0,DV3~
3)';
      PINUSE='GROUND';
      NO_LOAD_CHECK='Both';
      NO_IO_CHECK='Both';
      NO_ASSERT_CHECK='TRUE';
      NO_DIR_CHECK='TRUE';
      ALLOW_CONNECT='TRUE';
    'VSS'<78>:
      PIN_NUMBER='(0,0,0,0,0,0,0,0,0,0,0,0,0,0,0,0,0,0,0,0,0,0,0,0,0,0,0,0,0,DV3~
7)';
      PINUSE='GROUND';
      NO_LOAD_CHECK='Both';
      NO_IO_CHECK='Both';
      NO_ASSERT_CHECK='TRUE';
      NO_DIR_CHECK='TRUE';
      ALLOW_CONNECT='TRUE';
    'VSS'<77>:
      PIN_NUMBER='(0,0,0,0,0,0,0,0,0,0,0,0,0,0,0,0,0,0,0,0,0,0,0,0,0,0,0,0,0,DV3~
9)';
      PINUSE='GROUND';
      NO_LOAD_CHECK='Both';
      NO_IO_CHECK='Both';
      NO_ASSERT_CHECK='TRUE';
      NO_DIR_CHECK='TRUE';
      ALLOW_CONNECT='TRUE';
    'VSS'<76>:
      PIN_NUMBER='(0,0,0,0,0,0,0,0,0,0,0,0,0,0,0,0,0,0,0,0,0,0,0,0,0,0,0,0,0,DV7~
3)';
      PINUSE='GROUND';
      NO_LOAD_CHECK='Both';
      NO_IO_CHECK='Both';
      NO_ASSERT_CHECK='TRUE';
      NO_DIR_CHECK='TRUE';
      ALLOW_CONNECT='TRUE';
    'VSS'<75>:
      PIN_NUMBER='(0,0,0,0,0,0,0,0,0,0,0,0,0,0,0,0,0,0,0,0,0,0,0,0,0,0,0,0,0,DV7~
7)';
      PINUSE='GROUND';
      NO_LOAD_CHECK='Both';
      NO_IO_CHECK='Both';
      NO_ASSERT_CHECK='TRUE';
      NO_DIR_CHECK='TRUE';
      ALLOW_CONNECT='TRUE';
    'VSS'<74>:
      PIN_NUMBER='(0,0,0,0,0,0,0,0,0,0,0,0,0,0,0,0,0,0,0,0,0,0,0,0,0,0,0,0,0,DV8~
1)';
      PINUSE='GROUND';
      NO_LOAD_CHECK='Both';
      NO_IO_CHECK='Both';
      NO_ASSERT_CHECK='TRUE';
      NO_DIR_CHECK='TRUE';
      ALLOW_CONNECT='TRUE';
    'VSS'<73>:
      PIN_NUMBER='(0,0,0,0,0,0,0,0,0,0,0,0,0,0,0,0,0,0,0,0,0,0,0,0,0,0,0,0,0,DW1~
2)';
      PINUSE='GROUND';
      NO_LOAD_CHECK='Both';
      NO_IO_CHECK='Both';
      NO_ASSERT_CHECK='TRUE';
      NO_DIR_CHECK='TRUE';
      ALLOW_CONNECT='TRUE';
    'VSS'<72>:
      PIN_NUMBER='(0,0,0,0,0,0,0,0,0,0,0,0,0,0,0,0,0,0,0,0,0,0,0,0,0,0,0,0,0,DW2~
0)';
      PINUSE='GROUND';
      NO_LOAD_CHECK='Both';
      NO_IO_CHECK='Both';
      NO_ASSERT_CHECK='TRUE';
      NO_DIR_CHECK='TRUE';
      ALLOW_CONNECT='TRUE';
    'VSS'<71>:
      PIN_NUMBER='(0,0,0,0,0,0,0,0,0,0,0,0,0,0,0,0,0,0,0,0,0,0,0,0,0,0,0,0,0,DW2~
4)';
      PINUSE='GROUND';
      NO_LOAD_CHECK='Both';
      NO_IO_CHECK='Both';
      NO_ASSERT_CHECK='TRUE';
      NO_DIR_CHECK='TRUE';
      ALLOW_CONNECT='TRUE';
    'VSS'<70>:
      PIN_NUMBER='(0,0,0,0,0,0,0,0,0,0,0,0,0,0,0,0,0,0,0,0,0,0,0,0,0,0,0,0,0,DW2~
8)';
      PINUSE='GROUND';
      NO_LOAD_CHECK='Both';
      NO_IO_CHECK='Both';
      NO_ASSERT_CHECK='TRUE';
      NO_DIR_CHECK='TRUE';
      ALLOW_CONNECT='TRUE';
    'VSS'<69>:
      PIN_NUMBER='(0,0,0,0,0,0,0,0,0,0,0,0,0,0,0,0,0,0,0,0,0,0,0,0,0,0,0,0,0,DW3~
0)';
      PINUSE='GROUND';
      NO_LOAD_CHECK='Both';
      NO_IO_CHECK='Both';
      NO_ASSERT_CHECK='TRUE';
      NO_DIR_CHECK='TRUE';
      ALLOW_CONNECT='TRUE';
    'VSS'<68>:
      PIN_NUMBER='(0,0,0,0,0,0,0,0,0,0,0,0,0,0,0,0,0,0,0,0,0,0,0,0,0,0,0,0,0,DW3~
4)';
      PINUSE='GROUND';
      NO_LOAD_CHECK='Both';
      NO_IO_CHECK='Both';
      NO_ASSERT_CHECK='TRUE';
      NO_DIR_CHECK='TRUE';
      ALLOW_CONNECT='TRUE';
    'VSS'<67>:
      PIN_NUMBER='(0,0,0,0,0,0,0,0,0,0,0,0,0,0,0,0,0,0,0,0,0,0,0,0,0,0,0,0,0,DW3~
6)';
      PINUSE='GROUND';
      NO_LOAD_CHECK='Both';
      NO_IO_CHECK='Both';
      NO_ASSERT_CHECK='TRUE';
      NO_DIR_CHECK='TRUE';
      ALLOW_CONNECT='TRUE';
    'VSS'<66>:
      PIN_NUMBER='(0,0,0,0,0,0,0,0,0,0,0,0,0,0,0,0,0,0,0,0,0,0,0,0,0,0,0,0,0,DW4~
0)';
      PINUSE='GROUND';
      NO_LOAD_CHECK='Both';
      NO_IO_CHECK='Both';
      NO_ASSERT_CHECK='TRUE';
      NO_DIR_CHECK='TRUE';
      ALLOW_CONNECT='TRUE';
    'VSS'<65>:
      PIN_NUMBER='(0,0,0,0,0,0,0,0,0,0,0,0,0,0,0,0,0,0,0,0,0,0,0,0,0,0,0,0,0,DW6~
4)';
      PINUSE='GROUND';
      NO_LOAD_CHECK='Both';
      NO_IO_CHECK='Both';
      NO_ASSERT_CHECK='TRUE';
      NO_DIR_CHECK='TRUE';
      ALLOW_CONNECT='TRUE';
    'VSS'<64>:
      PIN_NUMBER='(0,0,0,0,0,0,0,0,0,0,0,0,0,0,0,0,0,0,0,0,0,0,0,0,0,0,0,0,0,DW6~
6)';
      PINUSE='GROUND';
      NO_LOAD_CHECK='Both';
      NO_IO_CHECK='Both';
      NO_ASSERT_CHECK='TRUE';
      NO_DIR_CHECK='TRUE';
      ALLOW_CONNECT='TRUE';
    'VSS'<63>:
      PIN_NUMBER='(0,0,0,0,0,0,0,0,0,0,0,0,0,0,0,0,0,0,0,0,0,0,0,0,0,0,0,0,0,DW6~
8)';
      PINUSE='GROUND';
      NO_LOAD_CHECK='Both';
      NO_IO_CHECK='Both';
      NO_ASSERT_CHECK='TRUE';
      NO_DIR_CHECK='TRUE';
      ALLOW_CONNECT='TRUE';
    'VSS'<62>:
      PIN_NUMBER='(0,0,0,0,0,0,0,0,0,0,0,0,0,0,0,0,0,0,0,0,0,0,0,0,0,0,0,0,0,DW7~
0)';
      PINUSE='GROUND';
      NO_LOAD_CHECK='Both';
      NO_IO_CHECK='Both';
      NO_ASSERT_CHECK='TRUE';
      NO_DIR_CHECK='TRUE';
      ALLOW_CONNECT='TRUE';
    'VSS'<61>:
      PIN_NUMBER='(0,0,0,0,0,0,0,0,0,0,0,0,0,0,0,0,0,0,0,0,0,0,0,0,0,0,0,0,0,DW7~
2)';
      PINUSE='GROUND';
      NO_LOAD_CHECK='Both';
      NO_IO_CHECK='Both';
      NO_ASSERT_CHECK='TRUE';
      NO_DIR_CHECK='TRUE';
      ALLOW_CONNECT='TRUE';
    'VSS'<60>:
      PIN_NUMBER='(0,0,0,0,0,0,0,0,0,0,0,0,0,0,0,0,0,0,0,0,0,0,0,0,0,0,0,0,0,DW7~
4)';
      PINUSE='GROUND';
      NO_LOAD_CHECK='Both';
      NO_IO_CHECK='Both';
      NO_ASSERT_CHECK='TRUE';
      NO_DIR_CHECK='TRUE';
      ALLOW_CONNECT='TRUE';
    'VSS'<59>:
      PIN_NUMBER='(0,0,0,0,0,0,0,0,0,0,0,0,0,0,0,0,0,0,0,0,0,0,0,0,0,0,0,0,0,DW7~
6)';
      PINUSE='GROUND';
      NO_LOAD_CHECK='Both';
      NO_IO_CHECK='Both';
      NO_ASSERT_CHECK='TRUE';
      NO_DIR_CHECK='TRUE';
      ALLOW_CONNECT='TRUE';
    'VSS'<58>:
      PIN_NUMBER='(0,0,0,0,0,0,0,0,0,0,0,0,0,0,0,0,0,0,0,0,0,0,0,0,0,0,0,0,0,DW8~
)';
      PINUSE='GROUND';
      NO_LOAD_CHECK='Both';
      NO_IO_CHECK='Both';
      NO_ASSERT_CHECK='TRUE';
      NO_DIR_CHECK='TRUE';
      ALLOW_CONNECT='TRUE';
    'VSS'<57>:
      PIN_NUMBER='(0,0,0,0,0,0,0,0,0,0,0,0,0,0,0,0,0,0,0,0,0,0,0,0,0,0,0,0,0,DW8~
2)';
      PINUSE='GROUND';
      NO_LOAD_CHECK='Both';
      NO_IO_CHECK='Both';
      NO_ASSERT_CHECK='TRUE';
      NO_DIR_CHECK='TRUE';
      ALLOW_CONNECT='TRUE';
    'VSS'<56>:
      PIN_NUMBER='(0,0,0,0,0,0,0,0,0,0,0,0,0,0,0,0,0,0,0,0,0,0,0,0,0,0,0,0,0,DW8~
4)';
      PINUSE='GROUND';
      NO_LOAD_CHECK='Both';
      NO_IO_CHECK='Both';
      NO_ASSERT_CHECK='TRUE';
      NO_DIR_CHECK='TRUE';
      ALLOW_CONNECT='TRUE';
    'VSS'<55>:
      PIN_NUMBER='(0,0,0,0,0,0,0,0,0,0,0,0,0,0,0,0,0,0,0,0,0,0,0,0,0,0,0,0,0,DY5~
)';
      PINUSE='GROUND';
      NO_LOAD_CHECK='Both';
      NO_IO_CHECK='Both';
      NO_ASSERT_CHECK='TRUE';
      NO_DIR_CHECK='TRUE';
      ALLOW_CONNECT='TRUE';
    'VSS'<54>:
      PIN_NUMBER='(0,0,0,0,0,0,0,0,0,0,0,0,0,0,0,0,0,0,0,0,0,0,0,0,0,0,0,0,0,DY1~
9)';
      PINUSE='GROUND';
      NO_LOAD_CHECK='Both';
      NO_IO_CHECK='Both';
      NO_ASSERT_CHECK='TRUE';
      NO_DIR_CHECK='TRUE';
      ALLOW_CONNECT='TRUE';
    'VSS'<53>:
      PIN_NUMBER='(0,0,0,0,0,0,0,0,0,0,0,0,0,0,0,0,0,0,0,0,0,0,0,0,0,0,0,0,0,DY2~
3)';
      PINUSE='GROUND';
      NO_LOAD_CHECK='Both';
      NO_IO_CHECK='Both';
      NO_ASSERT_CHECK='TRUE';
      NO_DIR_CHECK='TRUE';
      ALLOW_CONNECT='TRUE';
    'VSS'<52>:
      PIN_NUMBER='(0,0,0,0,0,0,0,0,0,0,0,0,0,0,0,0,0,0,0,0,0,0,0,0,0,0,0,0,0,DY2~
9)';
      PINUSE='GROUND';
      NO_LOAD_CHECK='Both';
      NO_IO_CHECK='Both';
      NO_ASSERT_CHECK='TRUE';
      NO_DIR_CHECK='TRUE';
      ALLOW_CONNECT='TRUE';
    'VSS'<51>:
      PIN_NUMBER='(0,0,0,0,0,0,0,0,0,0,0,0,0,0,0,0,0,0,0,0,0,0,0,0,0,0,0,0,0,DY3~
5)';
      PINUSE='GROUND';
      NO_LOAD_CHECK='Both';
      NO_IO_CHECK='Both';
      NO_ASSERT_CHECK='TRUE';
      NO_DIR_CHECK='TRUE';
      ALLOW_CONNECT='TRUE';
    'VSS'<50>:
      PIN_NUMBER='(0,0,0,0,0,0,0,0,0,0,0,0,0,0,0,0,0,0,0,0,0,0,0,0,0,0,0,0,0,DY4~
1)';
      PINUSE='GROUND';
      NO_LOAD_CHECK='Both';
      NO_IO_CHECK='Both';
      NO_ASSERT_CHECK='TRUE';
      NO_DIR_CHECK='TRUE';
      ALLOW_CONNECT='TRUE';
    'VSS'<49>:
      PIN_NUMBER='(0,0,0,0,0,0,0,0,0,0,0,0,0,0,0,0,0,0,0,0,0,0,0,0,0,0,0,0,0,DY7~
1)';
      PINUSE='GROUND';
      NO_LOAD_CHECK='Both';
      NO_IO_CHECK='Both';
      NO_ASSERT_CHECK='TRUE';
      NO_DIR_CHECK='TRUE';
      ALLOW_CONNECT='TRUE';
    'VSS'<48>:
      PIN_NUMBER='(0,0,0,0,0,0,0,0,0,0,0,0,0,0,0,0,0,0,0,0,0,0,0,0,0,0,0,0,0,DY7~
5)';
      PINUSE='GROUND';
      NO_LOAD_CHECK='Both';
      NO_IO_CHECK='Both';
      NO_ASSERT_CHECK='TRUE';
      NO_DIR_CHECK='TRUE';
      ALLOW_CONNECT='TRUE';
    'VSS'<47>:
      PIN_NUMBER='(0,0,0,0,0,0,0,0,0,0,0,0,0,0,0,0,0,0,0,0,0,0,0,0,0,0,0,0,0,EA6~
)';
      PINUSE='GROUND';
      NO_LOAD_CHECK='Both';
      NO_IO_CHECK='Both';
      NO_ASSERT_CHECK='TRUE';
      NO_DIR_CHECK='TRUE';
      ALLOW_CONNECT='TRUE';
    'VSS'<46>:
      PIN_NUMBER='(0,0,0,0,0,0,0,0,0,0,0,0,0,0,0,0,0,0,0,0,0,0,0,0,0,0,0,0,0,J16~
)';
      PINUSE='GROUND';
      NO_LOAD_CHECK='Both';
      NO_IO_CHECK='Both';
      NO_ASSERT_CHECK='TRUE';
      NO_DIR_CHECK='TRUE';
      ALLOW_CONNECT='TRUE';
    'VSS'<45>:
      PIN_NUMBER='(0,0,0,0,0,0,0,0,0,0,0,0,0,0,0,0,0,0,0,0,0,0,0,0,0,0,0,0,0,EA1~
6)';
      PINUSE='GROUND';
      NO_LOAD_CHECK='Both';
      NO_IO_CHECK='Both';
      NO_ASSERT_CHECK='TRUE';
      NO_DIR_CHECK='TRUE';
      ALLOW_CONNECT='TRUE';
    'VSS'<44>:
      PIN_NUMBER='(0,0,0,0,0,0,0,0,0,0,0,0,0,0,0,0,0,0,0,0,0,0,0,0,0,0,0,0,0,EA2~
0)';
      PINUSE='GROUND';
      NO_LOAD_CHECK='Both';
      NO_IO_CHECK='Both';
      NO_ASSERT_CHECK='TRUE';
      NO_DIR_CHECK='TRUE';
      ALLOW_CONNECT='TRUE';
    'VSS'<43>:
      PIN_NUMBER='(0,0,0,0,0,0,0,0,0,0,0,0,0,0,0,0,0,0,0,0,0,0,0,0,0,0,0,0,0,EA2~
2)';
      PINUSE='GROUND';
      NO_LOAD_CHECK='Both';
      NO_IO_CHECK='Both';
      NO_ASSERT_CHECK='TRUE';
      NO_DIR_CHECK='TRUE';
      ALLOW_CONNECT='TRUE';
    'VSS'<42>:
      PIN_NUMBER='(0,0,0,0,0,0,0,0,0,0,0,0,0,0,0,0,0,0,0,0,0,0,0,0,0,0,0,0,0,EA4~
2)';
      PINUSE='GROUND';
      NO_LOAD_CHECK='Both';
      NO_IO_CHECK='Both';
      NO_ASSERT_CHECK='TRUE';
      NO_DIR_CHECK='TRUE';
      ALLOW_CONNECT='TRUE';
    'VSS'<41>:
      PIN_NUMBER='(0,0,0,0,0,0,0,0,0,0,0,0,0,0,0,0,0,0,0,0,0,0,0,0,0,0,0,0,0,EA6~
4)';
      PINUSE='GROUND';
      NO_LOAD_CHECK='Both';
      NO_IO_CHECK='Both';
      NO_ASSERT_CHECK='TRUE';
      NO_DIR_CHECK='TRUE';
      ALLOW_CONNECT='TRUE';
    'VSS'<40>:
      PIN_NUMBER='(0,0,0,0,0,0,0,0,0,0,0,0,0,0,0,0,0,0,0,0,0,0,0,0,0,0,0,0,0,EA7~
0)';
      PINUSE='GROUND';
      NO_LOAD_CHECK='Both';
      NO_IO_CHECK='Both';
      NO_ASSERT_CHECK='TRUE';
      NO_DIR_CHECK='TRUE';
      ALLOW_CONNECT='TRUE';
    'VSS'<39>:
      PIN_NUMBER='(0,0,0,0,0,0,0,0,0,0,0,0,0,0,0,0,0,0,0,0,0,0,0,0,0,0,0,0,0,EA7~
6)';
      PINUSE='GROUND';
      NO_LOAD_CHECK='Both';
      NO_IO_CHECK='Both';
      NO_ASSERT_CHECK='TRUE';
      NO_DIR_CHECK='TRUE';
      ALLOW_CONNECT='TRUE';
    'VSS'<38>:
      PIN_NUMBER='(0,0,0,0,0,0,0,0,0,0,0,0,0,0,0,0,0,0,0,0,0,0,0,0,0,0,0,0,0,EA7~
8)';
      PINUSE='GROUND';
      NO_LOAD_CHECK='Both';
      NO_IO_CHECK='Both';
      NO_ASSERT_CHECK='TRUE';
      NO_DIR_CHECK='TRUE';
      ALLOW_CONNECT='TRUE';
    'VSS'<37>:
      PIN_NUMBER='(0,0,0,0,0,0,0,0,0,0,0,0,0,0,0,0,0,0,0,0,0,0,0,0,0,0,0,0,0,EA8~
0)';
      PINUSE='GROUND';
      NO_LOAD_CHECK='Both';
      NO_IO_CHECK='Both';
      NO_ASSERT_CHECK='TRUE';
      NO_DIR_CHECK='TRUE';
      ALLOW_CONNECT='TRUE';
    'VSS'<36>:
      PIN_NUMBER='(0,0,0,0,0,0,0,0,0,0,0,0,0,0,0,0,0,0,0,0,0,0,0,0,0,0,0,0,0,EA8~
2)';
      PINUSE='GROUND';
      NO_LOAD_CHECK='Both';
      NO_IO_CHECK='Both';
      NO_ASSERT_CHECK='TRUE';
      NO_DIR_CHECK='TRUE';
      ALLOW_CONNECT='TRUE';
    'VSS'<35>:
      PIN_NUMBER='(0,0,0,0,0,0,0,0,0,0,0,0,0,0,0,0,0,0,0,0,0,0,0,0,0,0,0,0,0,EB1~
3)';
      PINUSE='GROUND';
      NO_LOAD_CHECK='Both';
      NO_IO_CHECK='Both';
      NO_ASSERT_CHECK='TRUE';
      NO_DIR_CHECK='TRUE';
      ALLOW_CONNECT='TRUE';
    'VSS'<34>:
      PIN_NUMBER='(0,0,0,0,0,0,0,0,0,0,0,0,0,0,0,0,0,0,0,0,0,0,0,0,0,0,0,0,0,BR1~
8)';
      PINUSE='GROUND';
      NO_LOAD_CHECK='Both';
      NO_IO_CHECK='Both';
      NO_ASSERT_CHECK='TRUE';
      NO_DIR_CHECK='TRUE';
      ALLOW_CONNECT='TRUE';
    'VSS'<33>:
      PIN_NUMBER='(0,0,0,0,0,0,0,0,0,0,0,0,0,0,0,0,0,0,0,0,0,0,0,0,0,0,0,0,0,EB2~
3)';
      PINUSE='GROUND';
      NO_LOAD_CHECK='Both';
      NO_IO_CHECK='Both';
      NO_ASSERT_CHECK='TRUE';
      NO_DIR_CHECK='TRUE';
      ALLOW_CONNECT='TRUE';
    'VSS'<32>:
      PIN_NUMBER='(0,0,0,0,0,0,0,0,0,0,0,0,0,0,0,0,0,0,0,0,0,0,0,0,0,0,0,0,0,EB2~
5)';
      PINUSE='GROUND';
      NO_LOAD_CHECK='Both';
      NO_IO_CHECK='Both';
      NO_ASSERT_CHECK='TRUE';
      NO_DIR_CHECK='TRUE';
      ALLOW_CONNECT='TRUE';
    'VSS'<31>:
      PIN_NUMBER='(0,0,0,0,0,0,0,0,0,0,0,0,0,0,0,0,0,0,0,0,0,0,0,0,0,0,0,0,0,EB2~
7)';
      PINUSE='GROUND';
      NO_LOAD_CHECK='Both';
      NO_IO_CHECK='Both';
      NO_ASSERT_CHECK='TRUE';
      NO_DIR_CHECK='TRUE';
      ALLOW_CONNECT='TRUE';
    'VSS'<30>:
      PIN_NUMBER='(0,0,0,0,0,0,0,0,0,0,0,0,0,0,0,0,0,0,0,0,0,0,0,0,0,0,0,0,0,EB2~
9)';
      PINUSE='GROUND';
      NO_LOAD_CHECK='Both';
      NO_IO_CHECK='Both';
      NO_ASSERT_CHECK='TRUE';
      NO_DIR_CHECK='TRUE';
      ALLOW_CONNECT='TRUE';
    'VSS'<29>:
      PIN_NUMBER='(0,0,0,0,0,0,0,0,0,0,0,0,0,0,0,0,0,0,0,0,0,0,0,0,0,0,0,0,0,EB3~
1)';
      PINUSE='GROUND';
      NO_LOAD_CHECK='Both';
      NO_IO_CHECK='Both';
      NO_ASSERT_CHECK='TRUE';
      NO_DIR_CHECK='TRUE';
      ALLOW_CONNECT='TRUE';
    'VSS'<28>:
      PIN_NUMBER='(0,0,0,0,0,0,0,0,0,0,0,0,0,0,0,0,0,0,0,0,0,0,0,0,0,0,0,0,0,EB3~
3)';
      PINUSE='GROUND';
      NO_LOAD_CHECK='Both';
      NO_IO_CHECK='Both';
      NO_ASSERT_CHECK='TRUE';
      NO_DIR_CHECK='TRUE';
      ALLOW_CONNECT='TRUE';
    'VSS'<27>:
      PIN_NUMBER='(0,0,0,0,0,0,0,0,0,0,0,0,0,0,0,0,0,0,0,0,0,0,0,0,0,0,0,0,0,EB3~
5)';
      PINUSE='GROUND';
      NO_LOAD_CHECK='Both';
      NO_IO_CHECK='Both';
      NO_ASSERT_CHECK='TRUE';
      NO_DIR_CHECK='TRUE';
      ALLOW_CONNECT='TRUE';
    'VSS'<26>:
      PIN_NUMBER='(0,0,0,0,0,0,0,0,0,0,0,0,0,0,0,0,0,0,0,0,0,0,0,0,0,0,0,0,0,EB3~
7)';
      PINUSE='GROUND';
      NO_LOAD_CHECK='Both';
      NO_IO_CHECK='Both';
      NO_ASSERT_CHECK='TRUE';
      NO_DIR_CHECK='TRUE';
      ALLOW_CONNECT='TRUE';
    'VSS'<25>:
      PIN_NUMBER='(0,0,0,0,0,0,0,0,0,0,0,0,0,0,0,0,0,0,0,0,0,0,0,0,0,0,0,0,0,EB3~
9)';
      PINUSE='GROUND';
      NO_LOAD_CHECK='Both';
      NO_IO_CHECK='Both';
      NO_ASSERT_CHECK='TRUE';
      NO_DIR_CHECK='TRUE';
      ALLOW_CONNECT='TRUE';
    'VSS'<24>:
      PIN_NUMBER='(0,0,0,0,0,0,0,0,0,0,0,0,0,0,0,0,0,0,0,0,0,0,0,0,0,0,0,0,0,EB4~
1)';
      PINUSE='GROUND';
      NO_LOAD_CHECK='Both';
      NO_IO_CHECK='Both';
      NO_ASSERT_CHECK='TRUE';
      NO_DIR_CHECK='TRUE';
      ALLOW_CONNECT='TRUE';
    'VSS'<23>:
      PIN_NUMBER='(0,0,0,0,0,0,0,0,0,0,0,0,0,0,0,0,0,0,0,0,0,0,0,0,0,0,0,0,0,EB6~
5)';
      PINUSE='GROUND';
      NO_LOAD_CHECK='Both';
      NO_IO_CHECK='Both';
      NO_ASSERT_CHECK='TRUE';
      NO_DIR_CHECK='TRUE';
      ALLOW_CONNECT='TRUE';
    'VSS'<22>:
      PIN_NUMBER='(0,0,0,0,0,0,0,0,0,0,0,0,0,0,0,0,0,0,0,0,0,0,0,0,0,0,0,0,0,EB6~
9)';
      PINUSE='GROUND';
      NO_LOAD_CHECK='Both';
      NO_IO_CHECK='Both';
      NO_ASSERT_CHECK='TRUE';
      NO_DIR_CHECK='TRUE';
      ALLOW_CONNECT='TRUE';
    'VSS'<21>:
      PIN_NUMBER='(0,0,0,0,0,0,0,0,0,0,0,0,0,0,0,0,0,0,0,0,0,0,0,0,0,0,0,0,0,EC1~
0)';
      PINUSE='GROUND';
      NO_LOAD_CHECK='Both';
      NO_IO_CHECK='Both';
      NO_ASSERT_CHECK='TRUE';
      NO_DIR_CHECK='TRUE';
      ALLOW_CONNECT='TRUE';
    'VSS'<20>:
      PIN_NUMBER='(0,0,0,0,0,0,0,0,0,0,0,0,0,0,0,0,0,0,0,0,0,0,0,0,0,0,0,0,0,EC7~
0)';
      PINUSE='GROUND';
      NO_LOAD_CHECK='Both';
      NO_IO_CHECK='Both';
      NO_ASSERT_CHECK='TRUE';
      NO_DIR_CHECK='TRUE';
      ALLOW_CONNECT='TRUE';
    'VSS'<19>:
      PIN_NUMBER='(0,0,0,0,0,0,0,0,0,0,0,0,0,0,0,0,0,0,0,0,0,0,0,0,0,0,0,0,0,EC7~
2)';
      PINUSE='GROUND';
      NO_LOAD_CHECK='Both';
      NO_IO_CHECK='Both';
      NO_ASSERT_CHECK='TRUE';
      NO_DIR_CHECK='TRUE';
      ALLOW_CONNECT='TRUE';
    'VSS'<18>:
      PIN_NUMBER='(0,0,0,0,0,0,0,0,0,0,0,0,0,0,0,0,0,0,0,0,0,0,0,0,0,0,0,0,0,EC7~
4)';
      PINUSE='GROUND';
      NO_LOAD_CHECK='Both';
      NO_IO_CHECK='Both';
      NO_ASSERT_CHECK='TRUE';
      NO_DIR_CHECK='TRUE';
      ALLOW_CONNECT='TRUE';
    'VSS'<17>:
      PIN_NUMBER='(0,0,0,0,0,0,0,0,0,0,0,0,0,0,0,0,0,0,0,0,0,0,0,0,0,0,0,0,0,EC7~
6)';
      PINUSE='GROUND';
      NO_LOAD_CHECK='Both';
      NO_IO_CHECK='Both';
      NO_ASSERT_CHECK='TRUE';
      NO_DIR_CHECK='TRUE';
      ALLOW_CONNECT='TRUE';
    'VSS'<16>:
      PIN_NUMBER='(0,0,0,0,0,0,0,0,0,0,0,0,0,0,0,0,0,0,0,0,0,0,0,0,0,0,0,0,0,ED1~
1)';
      PINUSE='GROUND';
      NO_LOAD_CHECK='Both';
      NO_IO_CHECK='Both';
      NO_ASSERT_CHECK='TRUE';
      NO_DIR_CHECK='TRUE';
      ALLOW_CONNECT='TRUE';
    'VSS'<15>:
      PIN_NUMBER='(0,0,0,0,0,0,0,0,0,0,0,0,0,0,0,0,0,0,0,0,0,0,0,0,0,0,0,0,0,ED1~
5)';
      PINUSE='GROUND';
      NO_LOAD_CHECK='Both';
      NO_IO_CHECK='Both';
      NO_ASSERT_CHECK='TRUE';
      NO_DIR_CHECK='TRUE';
      ALLOW_CONNECT='TRUE';
    'VSS'<14>:
      PIN_NUMBER='(0,0,0,0,0,0,0,0,0,0,0,0,0,0,0,0,0,0,0,0,0,0,0,0,0,0,0,0,0,ED2~
3)';
      PINUSE='GROUND';
      NO_LOAD_CHECK='Both';
      NO_IO_CHECK='Both';
      NO_ASSERT_CHECK='TRUE';
      NO_DIR_CHECK='TRUE';
      ALLOW_CONNECT='TRUE';
    'VSS'<13>:
      PIN_NUMBER='(0,0,0,0,0,0,0,0,0,0,0,0,0,0,0,0,0,0,0,0,0,0,0,0,0,0,0,0,0,ED2~
9)';
      PINUSE='GROUND';
      NO_LOAD_CHECK='Both';
      NO_IO_CHECK='Both';
      NO_ASSERT_CHECK='TRUE';
      NO_DIR_CHECK='TRUE';
      ALLOW_CONNECT='TRUE';
    'VSS'<12>:
      PIN_NUMBER='(0,0,0,0,0,0,0,0,0,0,0,0,0,0,0,0,0,0,0,0,0,0,0,0,0,0,0,0,0,ED3~
5)';
      PINUSE='GROUND';
      NO_LOAD_CHECK='Both';
      NO_IO_CHECK='Both';
      NO_ASSERT_CHECK='TRUE';
      NO_DIR_CHECK='TRUE';
      ALLOW_CONNECT='TRUE';
    'VSS'<11>:
      PIN_NUMBER='(0,0,0,0,0,0,0,0,0,0,0,0,0,0,0,0,0,0,0,0,0,0,0,0,0,0,0,0,0,ED7~
7)';
      PINUSE='GROUND';
      NO_LOAD_CHECK='Both';
      NO_IO_CHECK='Both';
      NO_ASSERT_CHECK='TRUE';
      NO_DIR_CHECK='TRUE';
      ALLOW_CONNECT='TRUE';
    'VSS'<10>:
      PIN_NUMBER='(0,0,0,0,0,0,0,0,0,0,0,0,0,0,0,0,0,0,0,0,0,0,0,0,0,0,0,0,0,EE2~
4)';
      PINUSE='GROUND';
      NO_LOAD_CHECK='Both';
      NO_IO_CHECK='Both';
      NO_ASSERT_CHECK='TRUE';
      NO_DIR_CHECK='TRUE';
      ALLOW_CONNECT='TRUE';
    'VSS'<9>:
      PIN_NUMBER='(0,0,0,0,0,0,0,0,0,0,0,0,0,0,0,0,0,0,0,0,0,0,0,0,0,0,0,0,0,EE2~
8)';
      PINUSE='GROUND';
      NO_LOAD_CHECK='Both';
      NO_IO_CHECK='Both';
      NO_ASSERT_CHECK='TRUE';
      NO_DIR_CHECK='TRUE';
      ALLOW_CONNECT='TRUE';
    'VSS'<8>:
      PIN_NUMBER='(0,0,0,0,0,0,0,0,0,0,0,0,0,0,0,0,0,0,0,0,0,0,0,0,0,0,0,0,0,EE3~
0)';
      PINUSE='GROUND';
      NO_LOAD_CHECK='Both';
      NO_IO_CHECK='Both';
      NO_ASSERT_CHECK='TRUE';
      NO_DIR_CHECK='TRUE';
      ALLOW_CONNECT='TRUE';
    'VSS'<7>:
      PIN_NUMBER='(0,0,0,0,0,0,0,0,0,0,0,0,0,0,0,0,0,0,0,0,0,0,0,0,0,0,0,0,0,EE3~
4)';
      PINUSE='GROUND';
      NO_LOAD_CHECK='Both';
      NO_IO_CHECK='Both';
      NO_ASSERT_CHECK='TRUE';
      NO_DIR_CHECK='TRUE';
      ALLOW_CONNECT='TRUE';
    'VSS'<6>:
      PIN_NUMBER='(0,0,0,0,0,0,0,0,0,0,0,0,0,0,0,0,0,0,0,0,0,0,0,0,0,0,0,0,0,EE3~
6)';
      PINUSE='GROUND';
      NO_LOAD_CHECK='Both';
      NO_IO_CHECK='Both';
      NO_ASSERT_CHECK='TRUE';
      NO_DIR_CHECK='TRUE';
      ALLOW_CONNECT='TRUE';
    'VSS'<5>:
      PIN_NUMBER='(0,0,0,0,0,0,0,0,0,0,0,0,0,0,0,0,0,0,0,0,0,0,0,0,0,0,0,0,0,EE7~
0)';
      PINUSE='GROUND';
      NO_LOAD_CHECK='Both';
      NO_IO_CHECK='Both';
      NO_ASSERT_CHECK='TRUE';
      NO_DIR_CHECK='TRUE';
      ALLOW_CONNECT='TRUE';
    'VSS'<4>:
      PIN_NUMBER='(0,0,0,0,0,0,0,0,0,0,0,0,0,0,0,0,0,0,0,0,0,0,0,0,0,0,0,0,0,EE7~
6)';
      PINUSE='GROUND';
      NO_LOAD_CHECK='Both';
      NO_IO_CHECK='Both';
      NO_ASSERT_CHECK='TRUE';
      NO_DIR_CHECK='TRUE';
      ALLOW_CONNECT='TRUE';
    'VSS'<3>:
      PIN_NUMBER='(0,0,0,0,0,0,0,0,0,0,0,0,0,0,0,0,0,0,0,0,0,0,0,0,0,0,0,0,0,EE7~
8)';
      PINUSE='GROUND';
      NO_LOAD_CHECK='Both';
      NO_IO_CHECK='Both';
      NO_ASSERT_CHECK='TRUE';
      NO_DIR_CHECK='TRUE';
      ALLOW_CONNECT='TRUE';
    'VSS'<2>:
      PIN_NUMBER='(0,0,0,0,0,0,0,0,0,0,0,0,0,0,0,0,0,0,0,0,0,0,0,0,0,0,0,0,0,EF7~
1)';
      PINUSE='GROUND';
      NO_LOAD_CHECK='Both';
      NO_IO_CHECK='Both';
      NO_ASSERT_CHECK='TRUE';
      NO_DIR_CHECK='TRUE';
      ALLOW_CONNECT='TRUE';
    'VSS'<1>:
      PIN_NUMBER='(0,0,0,0,0,0,0,0,0,0,0,0,0,0,0,0,0,0,0,0,0,0,0,0,0,0,0,0,0,EF7~
5)';
      PINUSE='GROUND';
      NO_LOAD_CHECK='Both';
      NO_IO_CHECK='Both';
      NO_ASSERT_CHECK='TRUE';
      NO_DIR_CHECK='TRUE';
      ALLOW_CONNECT='TRUE';
    'VSS'<0>:
      PIN_NUMBER='(0,0,0,0,0,0,0,0,0,0,0,0,0,0,0,0,0,0,0,0,0,0,0,0,0,0,0,0,0,EF7~
9)';
      PINUSE='GROUND';
      NO_LOAD_CHECK='Both';
      NO_IO_CHECK='Both';
      NO_ASSERT_CHECK='TRUE';
      NO_DIR_CHECK='TRUE';
      ALLOW_CONNECT='TRUE';
    'VSS_VCCIN_SENSE':
      PIN_NUMBER='(0,0,0,0,0,0,0,0,0,0,0,0,0,0,0,0,0,0,AY85,0,0,0,0,0,0,0,0,0,0,~
0)';
      PINUSE='POWER';
      NO_LOAD_CHECK='Both';
      NO_IO_CHECK='Both';
      NO_ASSERT_CHECK='TRUE';
      NO_DIR_CHECK='TRUE';
      ALLOW_CONNECT='TRUE';
    'VSS_VCCIO_SENSE':
      PIN_NUMBER='(0,0,0,0,0,0,0,0,0,0,0,0,0,0,0,0,0,0,0,0,0,BF5,0,0,0,0,0,0,0,0~
)';
      PINUSE='POWER';
      NO_LOAD_CHECK='Both';
      NO_IO_CHECK='Both';
      NO_ASSERT_CHECK='TRUE';
      NO_DIR_CHECK='TRUE';
      ALLOW_CONNECT='TRUE';
    'VSS_VCCSA_SENSE':
      PIN_NUMBER='(0,0,0,0,0,0,0,0,0,0,0,0,0,0,0,0,0,0,0,0,0,CG76,0,0,0,0,0,0,0,~
0)';
      PINUSE='POWER';
      NO_LOAD_CHECK='Both';
      NO_IO_CHECK='Both';
      NO_ASSERT_CHECK='TRUE';
      NO_DIR_CHECK='TRUE';
      ALLOW_CONNECT='TRUE';
  end_pin;
  body
      PART_NAME='SKX_EXT_B';
      PHYS_DES_PREFIX='U';
      ENVCOMP='';
      PART_NUMBER='TBD';
      JEDEC_TYPE='XBGA3647_5_P0B';
      DESCRIPTION='SOCKET_P3647 U-PROC/DUAL SOCKET SKYLAKE EP EX PAD CHANGES';
      CLASS='IC';
      COMPONENT_TYPE='BGA';
      HEIGHT='0.276 IN';
      LPID='2725';
      SPEED_URL='http://speed.intel.com:8081/speed/module/pdm/item/pdm_item_deta~
il_direct.asp?item_cde=TBD&item_rev=01&url_param=unused';
      STATUS='';
      RPL='';
      AML='';
      BUS_UNIT='';
      DAYS='';
      PARENT_PART_TYPE='SKX_EXT_B_BGA1';
      PARENT_PPT='SKX_EXT_B';
      PARENT_PPT_PART='SKX_EXT_B_BGA1-IC,TBD';
  end_body;
end_primitive;
primitive 'SLG55021_SM-IC,G56246-001';
  pin
    'GND':
      PIN_NUMBER='(4)';
      PINUSE='GROUND';
      NO_LOAD_CHECK='Both';
      NO_IO_CHECK='Both';
      NO_ASSERT_CHECK='TRUE';
      NO_DIR_CHECK='TRUE';
      ALLOW_CONNECT='TRUE';
    'THPAD':
      PIN_NUMBER='(9)';
      PINUSE='GROUND';
      NO_LOAD_CHECK='Both';
      NO_IO_CHECK='Both';
      NO_ASSERT_CHECK='TRUE';
      NO_DIR_CHECK='TRUE';
      ALLOW_CONNECT='TRUE';
    'VCC':
      PIN_NUMBER='(1)';
      PINUSE='POWER';
      NO_LOAD_CHECK='Both';
      NO_IO_CHECK='Both';
      NO_ASSERT_CHECK='TRUE';
      NO_DIR_CHECK='TRUE';
      ALLOW_CONNECT='TRUE';
    'ON':
      PIN_NUMBER='(2)';
      INPUT_LOAD='(-0.01,0.01)';
      PINUSE='IN';
    'SHDN_N':
      PIN_NUMBER='(3)';
      INPUT_LOAD='(-0.01,0.01)';
      PINUSE='IN';
    'D':
      PIN_NUMBER='(5)';
      INPUT_LOAD='(-0.01,0.01)';
      PINUSE='IN';
    'S':
      PIN_NUMBER='(6)';
      INPUT_LOAD='(-0.01,0.01)';
      PINUSE='IN';
    'G':
      PIN_NUMBER='(7)';
      OUTPUT_LOAD='(1.0,-1.0)';
      PINUSE='OUT';
    'PG':
      PIN_NUMBER='(8)';
      OUTPUT_LOAD='(1.0,-1.0)';
      PINUSE='OUT';
  end_pin;
  body
      PART_NAME='SLG55021';
      PHYS_DES_PREFIX='EU';
      ENVCOMP='';
      PART_NUMBER='G56246-001';
      JEDEC_TYPE='DFN8_8_5MA';
      DESCRIPTION='IC,LIN,DRVR,8,TDFN,SLG55021,FETDVR';
      CLASS='IC';
      COMPONENT_TYPE='LCC';
      HEIGHT='0.031 IN';
      LPID='2554';
      SPEED_URL='http://speed.intel.com:8081/speed/module/pdm/item/pdm_item_deta~
il_direct.asp?item_cde=G56246-001&item_rev=01&url_param=unused';
      STATUS='';
      RPL='';
      AML='';
      BUS_UNIT='';
      DAYS='';
      PARENT_PART_TYPE='SLG55021_SM';
      PARENT_PPT='SLG55021';
      PARENT_PPT_PART='SLG55021_SM-IC,G56246-001';
  end_body;
end_primitive;
primitive 'SMC-CON13-GP_CONN-GC2-SMC-CON1A';
  pin
    '1':
      PIN_NUMBER='(1)';
      PIN_TYPE='ANALOG';
      NO_LOAD_CHECK='Both';
      NO_IO_CHECK='Both';
      NO_ASSERT_CHECK='TRUE';
      NO_DIR_CHECK='TRUE';
      ALLOW_CONNECT='TRUE';
      PINUSE='UNSPEC';
    '2':
      PIN_NUMBER='(2)';
      PIN_TYPE='ANALOG';
      NO_LOAD_CHECK='Both';
      NO_IO_CHECK='Both';
      NO_ASSERT_CHECK='TRUE';
      NO_DIR_CHECK='TRUE';
      ALLOW_CONNECT='TRUE';
      PINUSE='UNSPEC';
    '3':
      PIN_NUMBER='(3)';
      PIN_TYPE='ANALOG';
      NO_LOAD_CHECK='Both';
      NO_IO_CHECK='Both';
      NO_ASSERT_CHECK='TRUE';
      NO_DIR_CHECK='TRUE';
      ALLOW_CONNECT='TRUE';
      PINUSE='UNSPEC';
    '4':
      PIN_NUMBER='(4)';
      PIN_TYPE='ANALOG';
      NO_LOAD_CHECK='Both';
      NO_IO_CHECK='Both';
      NO_ASSERT_CHECK='TRUE';
      NO_DIR_CHECK='TRUE';
      ALLOW_CONNECT='TRUE';
      PINUSE='UNSPEC';
    '5':
      PIN_NUMBER='(5)';
      PIN_TYPE='ANALOG';
      NO_LOAD_CHECK='Both';
      NO_IO_CHECK='Both';
      NO_ASSERT_CHECK='TRUE';
      NO_DIR_CHECK='TRUE';
      ALLOW_CONNECT='TRUE';
      PINUSE='UNSPEC';
    '6':
      PIN_NUMBER='(6)';
      PIN_TYPE='ANALOG';
      NO_LOAD_CHECK='Both';
      NO_IO_CHECK='Both';
      NO_ASSERT_CHECK='TRUE';
      NO_DIR_CHECK='TRUE';
      ALLOW_CONNECT='TRUE';
      PINUSE='UNSPEC';
    '7':
      PIN_NUMBER='(7)';
      PIN_TYPE='ANALOG';
      NO_LOAD_CHECK='Both';
      NO_IO_CHECK='Both';
      NO_ASSERT_CHECK='TRUE';
      NO_DIR_CHECK='TRUE';
      ALLOW_CONNECT='TRUE';
      PINUSE='UNSPEC';
    '8':
      PIN_NUMBER='(8)';
      PIN_TYPE='ANALOG';
      NO_LOAD_CHECK='Both';
      NO_IO_CHECK='Both';
      NO_ASSERT_CHECK='TRUE';
      NO_DIR_CHECK='TRUE';
      ALLOW_CONNECT='TRUE';
      PINUSE='UNSPEC';
    '9':
      PIN_NUMBER='(9)';
      PIN_TYPE='ANALOG';
      NO_LOAD_CHECK='Both';
      NO_IO_CHECK='Both';
      NO_ASSERT_CHECK='TRUE';
      NO_DIR_CHECK='TRUE';
      ALLOW_CONNECT='TRUE';
      PINUSE='UNSPEC';
    '10':
      PIN_NUMBER='(10)';
      PIN_TYPE='ANALOG';
      NO_LOAD_CHECK='Both';
      NO_IO_CHECK='Both';
      NO_ASSERT_CHECK='TRUE';
      NO_DIR_CHECK='TRUE';
      ALLOW_CONNECT='TRUE';
      PINUSE='UNSPEC';
    '11':
      PIN_NUMBER='(11)';
      PIN_TYPE='ANALOG';
      NO_LOAD_CHECK='Both';
      NO_IO_CHECK='Both';
      NO_ASSERT_CHECK='TRUE';
      NO_DIR_CHECK='TRUE';
      ALLOW_CONNECT='TRUE';
      PINUSE='UNSPEC';
    '12':
      PIN_NUMBER='(12)';
      PIN_TYPE='ANALOG';
      NO_LOAD_CHECK='Both';
      NO_IO_CHECK='Both';
      NO_ASSERT_CHECK='TRUE';
      NO_DIR_CHECK='TRUE';
      ALLOW_CONNECT='TRUE';
      PINUSE='UNSPEC';
    '13':
      PIN_NUMBER='(13)';
      PIN_TYPE='ANALOG';
      NO_LOAD_CHECK='Both';
      NO_IO_CHECK='Both';
      NO_ASSERT_CHECK='TRUE';
      NO_DIR_CHECK='TRUE';
      ALLOW_CONNECT='TRUE';
      PINUSE='UNSPEC';
    'PTH1':
      PIN_NUMBER='(PTH1)';
      PIN_TYPE='ANALOG';
      NO_LOAD_CHECK='Both';
      NO_IO_CHECK='Both';
      NO_ASSERT_CHECK='TRUE';
      NO_DIR_CHECK='TRUE';
      ALLOW_CONNECT='TRUE';
      PINUSE='UNSPEC';
    'PTH2':
      PIN_NUMBER='(PTH2)';
      PIN_TYPE='ANALOG';
      NO_LOAD_CHECK='Both';
      NO_IO_CHECK='Both';
      NO_ASSERT_CHECK='TRUE';
      NO_DIR_CHECK='TRUE';
      ALLOW_CONNECT='TRUE';
      PINUSE='UNSPEC';
  end_pin;
  body
      PART_NAME='SMC-CON13-GP';
      BODY_NAME='SMC-CON13-GP';
      PHYS_DES_PREFIX='CN';
      CLASS='IO';
      DESCRIPTION='HEAD ML 13P T1M-13-GF-S-RA-TR SMD';
      JEDEC_TYPE='T1M-13-GF-S-RA-TR';
      PARENT_PART_TYPE='SMC-CON13-GP';
      PARENT_PPT='SMC-CON13-GP';
      PARENT_PPT_PART='SMC-CON13-GP_CONN-GC2-SMC-CON13-GP,021.D0181.0113';
  end_body;
end_primitive;
primitive 'SMC-CONN60A-22-GP_CONN-G7-SMC-A';
  pin
    '1':
      PIN_NUMBER='(1)';
      PIN_TYPE='ANALOG';
      NO_LOAD_CHECK='Both';
      NO_IO_CHECK='Both';
      NO_ASSERT_CHECK='TRUE';
      NO_DIR_CHECK='TRUE';
      ALLOW_CONNECT='TRUE';
      PINUSE='UNSPEC';
    '3':
      PIN_NUMBER='(3)';
      PIN_TYPE='ANALOG';
      NO_LOAD_CHECK='Both';
      NO_IO_CHECK='Both';
      NO_ASSERT_CHECK='TRUE';
      NO_DIR_CHECK='TRUE';
      ALLOW_CONNECT='TRUE';
      PINUSE='UNSPEC';
    '5':
      PIN_NUMBER='(5)';
      PIN_TYPE='ANALOG';
      NO_LOAD_CHECK='Both';
      NO_IO_CHECK='Both';
      NO_ASSERT_CHECK='TRUE';
      NO_DIR_CHECK='TRUE';
      ALLOW_CONNECT='TRUE';
      PINUSE='UNSPEC';
    '7':
      PIN_NUMBER='(7)';
      PIN_TYPE='ANALOG';
      NO_LOAD_CHECK='Both';
      NO_IO_CHECK='Both';
      NO_ASSERT_CHECK='TRUE';
      NO_DIR_CHECK='TRUE';
      ALLOW_CONNECT='TRUE';
      PINUSE='UNSPEC';
    '2':
      PIN_NUMBER='(2)';
      PIN_TYPE='ANALOG';
      NO_LOAD_CHECK='Both';
      NO_IO_CHECK='Both';
      NO_ASSERT_CHECK='TRUE';
      NO_DIR_CHECK='TRUE';
      ALLOW_CONNECT='TRUE';
      PINUSE='UNSPEC';
    '4':
      PIN_NUMBER='(4)';
      PIN_TYPE='ANALOG';
      NO_LOAD_CHECK='Both';
      NO_IO_CHECK='Both';
      NO_ASSERT_CHECK='TRUE';
      NO_DIR_CHECK='TRUE';
      ALLOW_CONNECT='TRUE';
      PINUSE='UNSPEC';
    '6':
      PIN_NUMBER='(6)';
      PIN_TYPE='ANALOG';
      NO_LOAD_CHECK='Both';
      NO_IO_CHECK='Both';
      NO_ASSERT_CHECK='TRUE';
      NO_DIR_CHECK='TRUE';
      ALLOW_CONNECT='TRUE';
      PINUSE='UNSPEC';
    '8':
      PIN_NUMBER='(8)';
      PIN_TYPE='ANALOG';
      NO_LOAD_CHECK='Both';
      NO_IO_CHECK='Both';
      NO_ASSERT_CHECK='TRUE';
      NO_DIR_CHECK='TRUE';
      ALLOW_CONNECT='TRUE';
      PINUSE='UNSPEC';
    '9':
      PIN_NUMBER='(9)';
      PIN_TYPE='ANALOG';
      NO_LOAD_CHECK='Both';
      NO_IO_CHECK='Both';
      NO_ASSERT_CHECK='TRUE';
      NO_DIR_CHECK='TRUE';
      ALLOW_CONNECT='TRUE';
      PINUSE='UNSPEC';
    '11':
      PIN_NUMBER='(11)';
      PIN_TYPE='ANALOG';
      NO_LOAD_CHECK='Both';
      NO_IO_CHECK='Both';
      NO_ASSERT_CHECK='TRUE';
      NO_DIR_CHECK='TRUE';
      ALLOW_CONNECT='TRUE';
      PINUSE='UNSPEC';
    '13':
      PIN_NUMBER='(13)';
      PIN_TYPE='ANALOG';
      NO_LOAD_CHECK='Both';
      NO_IO_CHECK='Both';
      NO_ASSERT_CHECK='TRUE';
      NO_DIR_CHECK='TRUE';
      ALLOW_CONNECT='TRUE';
      PINUSE='UNSPEC';
    '15':
      PIN_NUMBER='(15)';
      PIN_TYPE='ANALOG';
      NO_LOAD_CHECK='Both';
      NO_IO_CHECK='Both';
      NO_ASSERT_CHECK='TRUE';
      NO_DIR_CHECK='TRUE';
      ALLOW_CONNECT='TRUE';
      PINUSE='UNSPEC';
    '17':
      PIN_NUMBER='(17)';
      PIN_TYPE='ANALOG';
      NO_LOAD_CHECK='Both';
      NO_IO_CHECK='Both';
      NO_ASSERT_CHECK='TRUE';
      NO_DIR_CHECK='TRUE';
      ALLOW_CONNECT='TRUE';
      PINUSE='UNSPEC';
    '19':
      PIN_NUMBER='(19)';
      PIN_TYPE='ANALOG';
      NO_LOAD_CHECK='Both';
      NO_IO_CHECK='Both';
      NO_ASSERT_CHECK='TRUE';
      NO_DIR_CHECK='TRUE';
      ALLOW_CONNECT='TRUE';
      PINUSE='UNSPEC';
    '21':
      PIN_NUMBER='(21)';
      PIN_TYPE='ANALOG';
      NO_LOAD_CHECK='Both';
      NO_IO_CHECK='Both';
      NO_ASSERT_CHECK='TRUE';
      NO_DIR_CHECK='TRUE';
      ALLOW_CONNECT='TRUE';
      PINUSE='UNSPEC';
    '23':
      PIN_NUMBER='(23)';
      PIN_TYPE='ANALOG';
      NO_LOAD_CHECK='Both';
      NO_IO_CHECK='Both';
      NO_ASSERT_CHECK='TRUE';
      NO_DIR_CHECK='TRUE';
      ALLOW_CONNECT='TRUE';
      PINUSE='UNSPEC';
    '25':
      PIN_NUMBER='(25)';
      PIN_TYPE='ANALOG';
      NO_LOAD_CHECK='Both';
      NO_IO_CHECK='Both';
      NO_ASSERT_CHECK='TRUE';
      NO_DIR_CHECK='TRUE';
      ALLOW_CONNECT='TRUE';
      PINUSE='UNSPEC';
    '27':
      PIN_NUMBER='(27)';
      PIN_TYPE='ANALOG';
      NO_LOAD_CHECK='Both';
      NO_IO_CHECK='Both';
      NO_ASSERT_CHECK='TRUE';
      NO_DIR_CHECK='TRUE';
      ALLOW_CONNECT='TRUE';
      PINUSE='UNSPEC';
    '29':
      PIN_NUMBER='(29)';
      PIN_TYPE='ANALOG';
      NO_LOAD_CHECK='Both';
      NO_IO_CHECK='Both';
      NO_ASSERT_CHECK='TRUE';
      NO_DIR_CHECK='TRUE';
      ALLOW_CONNECT='TRUE';
      PINUSE='UNSPEC';
    '31':
      PIN_NUMBER='(31)';
      PIN_TYPE='ANALOG';
      NO_LOAD_CHECK='Both';
      NO_IO_CHECK='Both';
      NO_ASSERT_CHECK='TRUE';
      NO_DIR_CHECK='TRUE';
      ALLOW_CONNECT='TRUE';
      PINUSE='UNSPEC';
    '33':
      PIN_NUMBER='(33)';
      PIN_TYPE='ANALOG';
      NO_LOAD_CHECK='Both';
      NO_IO_CHECK='Both';
      NO_ASSERT_CHECK='TRUE';
      NO_DIR_CHECK='TRUE';
      ALLOW_CONNECT='TRUE';
      PINUSE='UNSPEC';
    '35':
      PIN_NUMBER='(35)';
      PIN_TYPE='ANALOG';
      NO_LOAD_CHECK='Both';
      NO_IO_CHECK='Both';
      NO_ASSERT_CHECK='TRUE';
      NO_DIR_CHECK='TRUE';
      ALLOW_CONNECT='TRUE';
      PINUSE='UNSPEC';
    '37':
      PIN_NUMBER='(37)';
      PIN_TYPE='ANALOG';
      NO_LOAD_CHECK='Both';
      NO_IO_CHECK='Both';
      NO_ASSERT_CHECK='TRUE';
      NO_DIR_CHECK='TRUE';
      ALLOW_CONNECT='TRUE';
      PINUSE='UNSPEC';
    '39':
      PIN_NUMBER='(39)';
      PIN_TYPE='ANALOG';
      NO_LOAD_CHECK='Both';
      NO_IO_CHECK='Both';
      NO_ASSERT_CHECK='TRUE';
      NO_DIR_CHECK='TRUE';
      ALLOW_CONNECT='TRUE';
      PINUSE='UNSPEC';
    '41':
      PIN_NUMBER='(41)';
      PIN_TYPE='ANALOG';
      NO_LOAD_CHECK='Both';
      NO_IO_CHECK='Both';
      NO_ASSERT_CHECK='TRUE';
      NO_DIR_CHECK='TRUE';
      ALLOW_CONNECT='TRUE';
      PINUSE='UNSPEC';
    '43':
      PIN_NUMBER='(43)';
      PIN_TYPE='ANALOG';
      NO_LOAD_CHECK='Both';
      NO_IO_CHECK='Both';
      NO_ASSERT_CHECK='TRUE';
      NO_DIR_CHECK='TRUE';
      ALLOW_CONNECT='TRUE';
      PINUSE='UNSPEC';
    '45':
      PIN_NUMBER='(45)';
      PIN_TYPE='ANALOG';
      NO_LOAD_CHECK='Both';
      NO_IO_CHECK='Both';
      NO_ASSERT_CHECK='TRUE';
      NO_DIR_CHECK='TRUE';
      ALLOW_CONNECT='TRUE';
      PINUSE='UNSPEC';
    '47':
      PIN_NUMBER='(47)';
      PIN_TYPE='ANALOG';
      NO_LOAD_CHECK='Both';
      NO_IO_CHECK='Both';
      NO_ASSERT_CHECK='TRUE';
      NO_DIR_CHECK='TRUE';
      ALLOW_CONNECT='TRUE';
      PINUSE='UNSPEC';
    '49':
      PIN_NUMBER='(49)';
      PIN_TYPE='ANALOG';
      NO_LOAD_CHECK='Both';
      NO_IO_CHECK='Both';
      NO_ASSERT_CHECK='TRUE';
      NO_DIR_CHECK='TRUE';
      ALLOW_CONNECT='TRUE';
      PINUSE='UNSPEC';
    '51':
      PIN_NUMBER='(51)';
      PIN_TYPE='ANALOG';
      NO_LOAD_CHECK='Both';
      NO_IO_CHECK='Both';
      NO_ASSERT_CHECK='TRUE';
      NO_DIR_CHECK='TRUE';
      ALLOW_CONNECT='TRUE';
      PINUSE='UNSPEC';
    '53':
      PIN_NUMBER='(53)';
      PIN_TYPE='ANALOG';
      NO_LOAD_CHECK='Both';
      NO_IO_CHECK='Both';
      NO_ASSERT_CHECK='TRUE';
      NO_DIR_CHECK='TRUE';
      ALLOW_CONNECT='TRUE';
      PINUSE='UNSPEC';
    '55':
      PIN_NUMBER='(55)';
      PIN_TYPE='ANALOG';
      NO_LOAD_CHECK='Both';
      NO_IO_CHECK='Both';
      NO_ASSERT_CHECK='TRUE';
      NO_DIR_CHECK='TRUE';
      ALLOW_CONNECT='TRUE';
      PINUSE='UNSPEC';
    '57':
      PIN_NUMBER='(57)';
      PIN_TYPE='ANALOG';
      NO_LOAD_CHECK='Both';
      NO_IO_CHECK='Both';
      NO_ASSERT_CHECK='TRUE';
      NO_DIR_CHECK='TRUE';
      ALLOW_CONNECT='TRUE';
      PINUSE='UNSPEC';
    '59':
      PIN_NUMBER='(59)';
      PIN_TYPE='ANALOG';
      NO_LOAD_CHECK='Both';
      NO_IO_CHECK='Both';
      NO_ASSERT_CHECK='TRUE';
      NO_DIR_CHECK='TRUE';
      ALLOW_CONNECT='TRUE';
      PINUSE='UNSPEC';
    '10':
      PIN_NUMBER='(10)';
      PIN_TYPE='ANALOG';
      NO_LOAD_CHECK='Both';
      NO_IO_CHECK='Both';
      NO_ASSERT_CHECK='TRUE';
      NO_DIR_CHECK='TRUE';
      ALLOW_CONNECT='TRUE';
      PINUSE='UNSPEC';
    '12':
      PIN_NUMBER='(12)';
      PIN_TYPE='ANALOG';
      NO_LOAD_CHECK='Both';
      NO_IO_CHECK='Both';
      NO_ASSERT_CHECK='TRUE';
      NO_DIR_CHECK='TRUE';
      ALLOW_CONNECT='TRUE';
      PINUSE='UNSPEC';
    '14':
      PIN_NUMBER='(14)';
      PIN_TYPE='ANALOG';
      NO_LOAD_CHECK='Both';
      NO_IO_CHECK='Both';
      NO_ASSERT_CHECK='TRUE';
      NO_DIR_CHECK='TRUE';
      ALLOW_CONNECT='TRUE';
      PINUSE='UNSPEC';
    '16':
      PIN_NUMBER='(16)';
      PIN_TYPE='ANALOG';
      NO_LOAD_CHECK='Both';
      NO_IO_CHECK='Both';
      NO_ASSERT_CHECK='TRUE';
      NO_DIR_CHECK='TRUE';
      ALLOW_CONNECT='TRUE';
      PINUSE='UNSPEC';
    '18':
      PIN_NUMBER='(18)';
      PIN_TYPE='ANALOG';
      NO_LOAD_CHECK='Both';
      NO_IO_CHECK='Both';
      NO_ASSERT_CHECK='TRUE';
      NO_DIR_CHECK='TRUE';
      ALLOW_CONNECT='TRUE';
      PINUSE='UNSPEC';
    '20':
      PIN_NUMBER='(20)';
      PIN_TYPE='ANALOG';
      NO_LOAD_CHECK='Both';
      NO_IO_CHECK='Both';
      NO_ASSERT_CHECK='TRUE';
      NO_DIR_CHECK='TRUE';
      ALLOW_CONNECT='TRUE';
      PINUSE='UNSPEC';
    '22':
      PIN_NUMBER='(22)';
      PIN_TYPE='ANALOG';
      NO_LOAD_CHECK='Both';
      NO_IO_CHECK='Both';
      NO_ASSERT_CHECK='TRUE';
      NO_DIR_CHECK='TRUE';
      ALLOW_CONNECT='TRUE';
      PINUSE='UNSPEC';
    '24':
      PIN_NUMBER='(24)';
      PIN_TYPE='ANALOG';
      NO_LOAD_CHECK='Both';
      NO_IO_CHECK='Both';
      NO_ASSERT_CHECK='TRUE';
      NO_DIR_CHECK='TRUE';
      ALLOW_CONNECT='TRUE';
      PINUSE='UNSPEC';
    '26':
      PIN_NUMBER='(26)';
      PIN_TYPE='ANALOG';
      NO_LOAD_CHECK='Both';
      NO_IO_CHECK='Both';
      NO_ASSERT_CHECK='TRUE';
      NO_DIR_CHECK='TRUE';
      ALLOW_CONNECT='TRUE';
      PINUSE='UNSPEC';
    '28':
      PIN_NUMBER='(28)';
      PIN_TYPE='ANALOG';
      NO_LOAD_CHECK='Both';
      NO_IO_CHECK='Both';
      NO_ASSERT_CHECK='TRUE';
      NO_DIR_CHECK='TRUE';
      ALLOW_CONNECT='TRUE';
      PINUSE='UNSPEC';
    '30':
      PIN_NUMBER='(30)';
      PIN_TYPE='ANALOG';
      NO_LOAD_CHECK='Both';
      NO_IO_CHECK='Both';
      NO_ASSERT_CHECK='TRUE';
      NO_DIR_CHECK='TRUE';
      ALLOW_CONNECT='TRUE';
      PINUSE='UNSPEC';
    '32':
      PIN_NUMBER='(32)';
      PIN_TYPE='ANALOG';
      NO_LOAD_CHECK='Both';
      NO_IO_CHECK='Both';
      NO_ASSERT_CHECK='TRUE';
      NO_DIR_CHECK='TRUE';
      ALLOW_CONNECT='TRUE';
      PINUSE='UNSPEC';
    '34':
      PIN_NUMBER='(34)';
      PIN_TYPE='ANALOG';
      NO_LOAD_CHECK='Both';
      NO_IO_CHECK='Both';
      NO_ASSERT_CHECK='TRUE';
      NO_DIR_CHECK='TRUE';
      ALLOW_CONNECT='TRUE';
      PINUSE='UNSPEC';
    '36':
      PIN_NUMBER='(36)';
      PIN_TYPE='ANALOG';
      NO_LOAD_CHECK='Both';
      NO_IO_CHECK='Both';
      NO_ASSERT_CHECK='TRUE';
      NO_DIR_CHECK='TRUE';
      ALLOW_CONNECT='TRUE';
      PINUSE='UNSPEC';
    '38':
      PIN_NUMBER='(38)';
      PIN_TYPE='ANALOG';
      NO_LOAD_CHECK='Both';
      NO_IO_CHECK='Both';
      NO_ASSERT_CHECK='TRUE';
      NO_DIR_CHECK='TRUE';
      ALLOW_CONNECT='TRUE';
      PINUSE='UNSPEC';
    '40':
      PIN_NUMBER='(40)';
      PIN_TYPE='ANALOG';
      NO_LOAD_CHECK='Both';
      NO_IO_CHECK='Both';
      NO_ASSERT_CHECK='TRUE';
      NO_DIR_CHECK='TRUE';
      ALLOW_CONNECT='TRUE';
      PINUSE='UNSPEC';
    '42':
      PIN_NUMBER='(42)';
      PIN_TYPE='ANALOG';
      NO_LOAD_CHECK='Both';
      NO_IO_CHECK='Both';
      NO_ASSERT_CHECK='TRUE';
      NO_DIR_CHECK='TRUE';
      ALLOW_CONNECT='TRUE';
      PINUSE='UNSPEC';
    '44':
      PIN_NUMBER='(44)';
      PIN_TYPE='ANALOG';
      NO_LOAD_CHECK='Both';
      NO_IO_CHECK='Both';
      NO_ASSERT_CHECK='TRUE';
      NO_DIR_CHECK='TRUE';
      ALLOW_CONNECT='TRUE';
      PINUSE='UNSPEC';
    '46':
      PIN_NUMBER='(46)';
      PIN_TYPE='ANALOG';
      NO_LOAD_CHECK='Both';
      NO_IO_CHECK='Both';
      NO_ASSERT_CHECK='TRUE';
      NO_DIR_CHECK='TRUE';
      ALLOW_CONNECT='TRUE';
      PINUSE='UNSPEC';
    '48':
      PIN_NUMBER='(48)';
      PIN_TYPE='ANALOG';
      NO_LOAD_CHECK='Both';
      NO_IO_CHECK='Both';
      NO_ASSERT_CHECK='TRUE';
      NO_DIR_CHECK='TRUE';
      ALLOW_CONNECT='TRUE';
      PINUSE='UNSPEC';
    '50':
      PIN_NUMBER='(50)';
      PIN_TYPE='ANALOG';
      NO_LOAD_CHECK='Both';
      NO_IO_CHECK='Both';
      NO_ASSERT_CHECK='TRUE';
      NO_DIR_CHECK='TRUE';
      ALLOW_CONNECT='TRUE';
      PINUSE='UNSPEC';
    '52':
      PIN_NUMBER='(52)';
      PIN_TYPE='ANALOG';
      NO_LOAD_CHECK='Both';
      NO_IO_CHECK='Both';
      NO_ASSERT_CHECK='TRUE';
      NO_DIR_CHECK='TRUE';
      ALLOW_CONNECT='TRUE';
      PINUSE='UNSPEC';
    '54':
      PIN_NUMBER='(54)';
      PIN_TYPE='ANALOG';
      NO_LOAD_CHECK='Both';
      NO_IO_CHECK='Both';
      NO_ASSERT_CHECK='TRUE';
      NO_DIR_CHECK='TRUE';
      ALLOW_CONNECT='TRUE';
      PINUSE='UNSPEC';
    '56':
      PIN_NUMBER='(56)';
      PIN_TYPE='ANALOG';
      NO_LOAD_CHECK='Both';
      NO_IO_CHECK='Both';
      NO_ASSERT_CHECK='TRUE';
      NO_DIR_CHECK='TRUE';
      ALLOW_CONNECT='TRUE';
      PINUSE='UNSPEC';
    '58':
      PIN_NUMBER='(58)';
      PIN_TYPE='ANALOG';
      NO_LOAD_CHECK='Both';
      NO_IO_CHECK='Both';
      NO_ASSERT_CHECK='TRUE';
      NO_DIR_CHECK='TRUE';
      ALLOW_CONNECT='TRUE';
      PINUSE='UNSPEC';
    '60':
      PIN_NUMBER='(60)';
      PIN_TYPE='ANALOG';
      NO_LOAD_CHECK='Both';
      NO_IO_CHECK='Both';
      NO_ASSERT_CHECK='TRUE';
      NO_DIR_CHECK='TRUE';
      ALLOW_CONNECT='TRUE';
      PINUSE='UNSPEC';
    'NP1':
      PIN_NUMBER='(NP1)';
      PIN_TYPE='ANALOG';
      NO_LOAD_CHECK='Both';
      NO_IO_CHECK='Both';
      NO_ASSERT_CHECK='TRUE';
      NO_DIR_CHECK='TRUE';
      ALLOW_CONNECT='TRUE';
      PINUSE='UNSPEC';
    'NP2':
      PIN_NUMBER='(NP2)';
      PIN_TYPE='ANALOG';
      NO_LOAD_CHECK='Both';
      NO_IO_CHECK='Both';
      NO_ASSERT_CHECK='TRUE';
      NO_DIR_CHECK='TRUE';
      ALLOW_CONNECT='TRUE';
      PINUSE='UNSPEC';
    'PTH1':
      PIN_NUMBER='(PTH1)';
      PIN_TYPE='ANALOG';
      NO_LOAD_CHECK='Both';
      NO_IO_CHECK='Both';
      NO_ASSERT_CHECK='TRUE';
      NO_DIR_CHECK='TRUE';
      ALLOW_CONNECT='TRUE';
      PINUSE='UNSPEC';
    'PTH2':
      PIN_NUMBER='(PTH2)';
      PIN_TYPE='ANALOG';
      NO_LOAD_CHECK='Both';
      NO_IO_CHECK='Both';
      NO_ASSERT_CHECK='TRUE';
      NO_DIR_CHECK='TRUE';
      ALLOW_CONNECT='TRUE';
      PINUSE='UNSPEC';
  end_pin;
  body
      PART_NAME='SMC-CONN60A-22-GP';
      BODY_NAME='SMC-CONN60A-22-GP';
      PHYS_DES_PREFIX='CN';
      CLASS='IO';
      DESCRIPTION='CONN 60P HSEC8-130-01-S-DV-A-WT-K-TR';
      JEDEC_TYPE='HSEC8-130-01-SDVAWTKTR';
      PARENT_PART_TYPE='SMC-CONN60A-22-GP';
      PARENT_PPT='SMC-CONN60A-22-GP';
      PARENT_PPT_PART='SMC-CONN60A-22-GP_CONN-G7-SMC-CONN60A-22-GP,020.C0082.0060';
  end_body;
end_primitive;
primitive 'SN74LVC2G07DCKR-GP_DISCRET-G4-A';
  pin
    '1A':
      PIN_NUMBER='(1)';
      INPUT_LOAD='(-0.01,0.01)';
      PINUSE='IN';
    'GND':
      PIN_NUMBER='(2)';
      PINUSE='POWER';
      NO_LOAD_CHECK='Both';
      NO_IO_CHECK='Both';
      NO_ASSERT_CHECK='TRUE';
      NO_DIR_CHECK='TRUE';
      ALLOW_CONNECT='TRUE';
    '2A':
      PIN_NUMBER='(3)';
      INPUT_LOAD='(-0.01,0.01)';
      PINUSE='IN';
    '2Y':
      PIN_NUMBER='(4)';
      OUTPUT_LOAD='(1.0,-1.0)';
      PINUSE='OUT';
    'VCC':
      PIN_NUMBER='(5)';
      PINUSE='POWER';
      NO_LOAD_CHECK='Both';
      NO_IO_CHECK='Both';
      NO_ASSERT_CHECK='TRUE';
      NO_DIR_CHECK='TRUE';
      ALLOW_CONNECT='TRUE';
    '1Y':
      PIN_NUMBER='(6)';
      OUTPUT_LOAD='(1.0,-1.0)';
      PINUSE='OUT';
  end_pin;
  body
      PART_NAME='SN74LVC2G07DCKR-GP';
      BODY_NAME='SN74LVC2G07DCKR-GP';
      PHYS_DES_PREFIX='U';
      CLASS='DISCRETE';
      DESCRIPTION='IC CMOS SN74LVC2G07DCKR SC-70';
      JEDEC_TYPE='SC70-6H44';
      PARENT_PART_TYPE='SN74LVC2G07DCKR-GP';
      PARENT_PPT='SN74LVC2G07DCKR-GP';
      PARENT_PPT_PART='SN74LVC2G07DCKR-GP_DISCRET-G4-SN74LVC2G07DCKR-GP,73.02G07.02J';
  end_body;
end_primitive;
primitive 'SOCKET_P_MECH_A_LEFT-P0,PLASTIA';
  pin
  end_pin;
  body
      CLASS='MECHANICAL';
      PART_NAME='SOCKET_P_MECH_A';
      PINCOUNT='0';
      BODY_NAME='SOCKET_P_MECH_A';
      PHYS_DES_PREFIX='XLU';
      ENVCOMP='NO;NO;NO;NO;NO;NO';
      PART_NUMBER='H37604-201';
      DESCRIPTION='SOCKET_P0 LEFT VendorT';
      JEDEC_TYPE='XLGA3647_H3760X_LEFT_P0';
      HEIGHT='0.276 IN';
      COMPONENT_TYPE='BGA';
      SPEED_URL='http://speed.intel.com:8081/speed/module/pdm/item/pdm_item_deta~
il_direct.asp?item_cde=H37604-201&item_rev=01&url_param=unused';
      STATUS='Design';
      RPL='YES';
      AML='2';
      BUS_UNIT='ATD SUBSTRATE';
      DAYS='???';
      PARENT_PART_TYPE='SOCKET_P_MECH_A_LEFT';
      PARENT_PPT='SOCKET_P_MECH_A';
      PARENT_PPT_PART='SOCKET_P_MECH_A_LEFT-P0,PLASTIC,H37604-201';
  end_body;
end_primitive;
primitive 'SOCKET_P_MECH_A_RIGHT-P0,PLASTA';
  pin
  end_pin;
  body
      CLASS='MECHANICAL';
      PART_NAME='SOCKET_P_MECH_A';
      PINCOUNT='0';
      BODY_NAME='SOCKET_P_MECH_A';
      PHYS_DES_PREFIX='XRU';
      ENVCOMP='NO;NO;NO;NO;NO;NO';
      PART_NUMBER='H37604-101';
      DESCRIPTION='SOCKET_P0 RIGHT VendorT';
      JEDEC_TYPE='XLGA3647_H3760X_RIGHT_P0';
      HEIGHT='0.276 IN';
      COMPONENT_TYPE='BGA';
      SPEED_URL='http://speed.intel.com:8081/speed/module/pdm/item/pdm_item_deta~
il_direct.asp?item_cde=H37604-101&item_rev=01&url_param=unused';
      STATUS='Design';
      RPL='YES';
      AML='1';
      BUS_UNIT='ATD SUBSTRATE';
      DAYS='???';
      PARENT_PART_TYPE='SOCKET_P_MECH_A_RIGHT';
      PARENT_PPT='SOCKET_P_MECH_A';
      PARENT_PPT_PART='SOCKET_P_MECH_A_RIGHT-P0,PLASTIC,H37604-101';
  end_body;
end_primitive;
primitive 'SPRINGVILLE_SM1-IC,G47144-004';
  pin
    'CBOT':
      PIN_NUMBER='(37)';
      PIN_TYPE='ANALOG';
      NO_LOAD_CHECK='Both';
      NO_IO_CHECK='Both';
      NO_ASSERT_CHECK='TRUE';
      NO_DIR_CHECK='TRUE';
      ALLOW_CONNECT='TRUE';
      PINUSE='UNSPEC';
    'CTOP':
      PIN_NUMBER='(40)';
      PIN_TYPE='ANALOG';
      NO_LOAD_CHECK='Both';
      NO_IO_CHECK='Both';
      NO_ASSERT_CHECK='TRUE';
      NO_DIR_CHECK='TRUE';
      ALLOW_CONNECT='TRUE';
      PINUSE='UNSPEC';
    'DEV_OFF_N':
      PIN_NUMBER='(28)';
      INPUT_LOAD='(-0.01,0.01)';
      PINUSE='IN';
    'GND':
      PIN_NUMBER='(65)';
      PINUSE='GROUND';
      NO_LOAD_CHECK='Both';
      NO_IO_CHECK='Both';
      NO_ASSERT_CHECK='TRUE';
      NO_DIR_CHECK='TRUE';
      ALLOW_CONNECT='TRUE';
    'JTAG_CLK':
      PIN_NUMBER='(19)';
      INPUT_LOAD='(-0.01,0.01)';
      PINUSE='IN';
    'JTAG_TDI':
      PIN_NUMBER='(29)';
      INPUT_LOAD='(-0.01,0.01)';
      PINUSE='IN';
    'JTAG_TDO':
      PIN_NUMBER='(4)';
      OUTPUT_LOAD='(1.0,-1.0)';
      PINUSE='OUT';
    'JTAG_TMS':
      PIN_NUMBER='(18)';
      INPUT_LOAD='(-0.01,0.01)';
      PINUSE='IN';
    'LAN_PWR_GOOD':
      PIN_NUMBER='(1)';
      INPUT_LOAD='(-0.01,0.01)';
      PINUSE='IN';
    'LED0':
      PIN_NUMBER='(31)';
      OUTPUT_LOAD='(1.0,-1.0)';
      PINUSE='OUT';
    'LED1':
      PIN_NUMBER='(30)';
      OUTPUT_LOAD='(1.0,-1.0)';
      PINUSE='OUT';
    'LED2':
      PIN_NUMBER='(33)';
      OUTPUT_LOAD='(1.0,-1.0)';
      PINUSE='OUT';
    'MDI_MINUS0_SFP_I2C_DATA':
      PIN_NUMBER='(57)';
      BIDIRECTIONAL='TRUE';
      INPUT_LOAD='(-0.01,0.01)';
      OUTPUT_LOAD='(1.0,-1.0)';
      PINUSE='BI';
    'MDI_MINUS1_SRDS_SIG_DET':
      PIN_NUMBER='(54)';
      BIDIRECTIONAL='TRUE';
      INPUT_LOAD='(-0.01,0.01)';
      OUTPUT_LOAD='(1.0,-1.0)';
      PINUSE='BI';
    'MDI_MINUS2_SETN':
      PIN_NUMBER='(52)';
      BIDIRECTIONAL='TRUE';
      INPUT_LOAD='(-0.01,0.01)';
      OUTPUT_LOAD='(1.0,-1.0)';
      PINUSE='BI';
    'MDI_MINUS3_SERN':
      PIN_NUMBER='(49)';
      BIDIRECTIONAL='TRUE';
      INPUT_LOAD='(-0.01,0.01)';
      OUTPUT_LOAD='(1.0,-1.0)';
      PINUSE='BI';
    'MDI_PLUS0_NC':
      PIN_NUMBER='(58)';
      BIDIRECTIONAL='TRUE';
      INPUT_LOAD='(-0.01,0.01)';
      OUTPUT_LOAD='(1.0,-1.0)';
      PINUSE='BI';
    'MDI_PLUS1_SFP_I2C_CLK':
      PIN_NUMBER='(55)';
      BIDIRECTIONAL='TRUE';
      INPUT_LOAD='(-0.01,0.01)';
      OUTPUT_LOAD='(1.0,-1.0)';
      PINUSE='BI';
    'MDI_PLUS2_SETP':
      PIN_NUMBER='(53)';
      BIDIRECTIONAL='TRUE';
      INPUT_LOAD='(-0.01,0.01)';
      OUTPUT_LOAD='(1.0,-1.0)';
      PINUSE='BI';
    'MDI_PLUS3_SERP':
      PIN_NUMBER='(50)';
      BIDIRECTIONAL='TRUE';
      INPUT_LOAD='(-0.01,0.01)';
      OUTPUT_LOAD='(1.0,-1.0)';
      PINUSE='BI';
    'NC':
      PIN_NUMBER='(22)';
      INPUT_LOAD='(-0.01,0.01)';
      PINUSE='IN';
    'NC_SI_ARB_IN':
      PIN_NUMBER='(43)';
      INPUT_LOAD='(-0.01,0.01)';
      PINUSE='IN';
    'NC_SI_ARB_OUT':
      PIN_NUMBER='(44)';
      OUTPUT_LOAD='(1.0,-1.0)';
      PINUSE='OUT';
    'NC_SI_CLK_IN':
      PIN_NUMBER='(2)';
      INPUT_LOAD='(-0.01,0.01)';
      PINUSE='IN';
    'NC_SI_CRS_DV':
      PIN_NUMBER='(3)';
      OUTPUT_LOAD='(1.0,-1.0)';
      PINUSE='OUT';
    'NC_SI_RXD0':
      PIN_NUMBER='(6)';
      OUTPUT_LOAD='(1.0,-1.0)';
      PINUSE='OUT';
    'NC_SI_RXD1':
      PIN_NUMBER='(5)';
      OUTPUT_LOAD='(1.0,-1.0)';
      PINUSE='OUT';
    'NC_SI_TXD0':
      PIN_NUMBER='(9)';
      INPUT_LOAD='(-0.01,0.01)';
      PINUSE='IN';
    'NC_SI_TXD1':
      PIN_NUMBER='(8)';
      INPUT_LOAD='(-0.01,0.01)';
      PINUSE='IN';
    'NC_SI_TX_EN':
      PIN_NUMBER='(7)';
      INPUT_LOAD='(-0.01,0.01)';
      PINUSE='IN';
    'NVM_CS_N':
      PIN_NUMBER='(15)';
      OUTPUT_LOAD='(1.0,-1.0)';
      PINUSE='OUT';
    'NVM_SI':
      PIN_NUMBER='(12)';
      OUTPUT_LOAD='(1.0,-1.0)';
      PINUSE='OUT';
    'NVM_SK':
      PIN_NUMBER='(13)';
      OUTPUT_LOAD='(1.0,-1.0)';
      PINUSE='OUT';
    'NVM_SO':
      PIN_NUMBER='(14)';
      INPUT_LOAD='(-0.01,0.01)';
      PINUSE='IN';
    'PECLKN':
      PIN_NUMBER='(25)';
      INPUT_LOAD='(-0.01,0.01)';
      PINUSE='IN';
    'PECLKP':
      PIN_NUMBER='(26)';
      INPUT_LOAD='(-0.01,0.01)';
      PINUSE='IN';
    'PE_RN':
      PIN_NUMBER='(23)';
      INPUT_LOAD='(-0.01,0.01)';
      PINUSE='IN';
    'PE_RP':
      PIN_NUMBER='(24)';
      INPUT_LOAD='(-0.01,0.01)';
      PINUSE='IN';
    'PE_RST_N':
      PIN_NUMBER='(17)';
      INPUT_LOAD='(-0.01,0.01)';
      PINUSE='IN';
    'PE_TN':
      PIN_NUMBER='(20)';
      OUTPUT_LOAD='(1.0,-1.0)';
      PINUSE='OUT';
    'PE_TP':
      PIN_NUMBER='(21)';
      OUTPUT_LOAD='(1.0,-1.0)';
      PINUSE='OUT';
    'PE_WAKE_N':
      PIN_NUMBER='(16)';
      BIDIRECTIONAL='TRUE';
      INPUT_LOAD='(-0.01,0.01)';
      OUTPUT_LOAD='(1.0,-1.0)';
      PINUSE='BI';
    'RSET':
      PIN_NUMBER='(48)';
      PIN_TYPE='ANALOG';
      NO_LOAD_CHECK='Both';
      NO_IO_CHECK='Both';
      NO_ASSERT_CHECK='TRUE';
      NO_DIR_CHECK='TRUE';
      ALLOW_CONNECT='TRUE';
      PINUSE='UNSPEC';
    'SDP0':
      PIN_NUMBER='(63)';
      BIDIRECTIONAL='TRUE';
      INPUT_LOAD='(-0.01,0.01)';
      OUTPUT_LOAD='(1.0,-1.0)';
      PINUSE='BI';
    'SDP1_PCIE_DIS_SDP1':
      PIN_NUMBER='(61)';
      BIDIRECTIONAL='TRUE';
      INPUT_LOAD='(-0.01,0.01)';
      OUTPUT_LOAD='(1.0,-1.0)';
      PINUSE='BI';
    'SDP2':
      PIN_NUMBER='(62)';
      BIDIRECTIONAL='TRUE';
      INPUT_LOAD='(-0.01,0.01)';
      OUTPUT_LOAD='(1.0,-1.0)';
      PINUSE='BI';
    'SDP3':
      PIN_NUMBER='(60)';
      BIDIRECTIONAL='TRUE';
      INPUT_LOAD='(-0.01,0.01)';
      OUTPUT_LOAD='(1.0,-1.0)';
      PINUSE='BI';
    'SMB_ALRT_N':
      PIN_NUMBER='(35)';
      OUTPUT_LOAD='(1.0,-1.0)';
      PINUSE='OUT';
    'SMB_CLK':
      PIN_NUMBER='(34)';
      BIDIRECTIONAL='TRUE';
      INPUT_LOAD='(-0.01,0.01)';
      OUTPUT_LOAD='(1.0,-1.0)';
      PINUSE='BI';
    'SMB_DATA':
      PIN_NUMBER='(36)';
      BIDIRECTIONAL='TRUE';
      INPUT_LOAD='(-0.01,0.01)';
      OUTPUT_LOAD='(1.0,-1.0)';
      PINUSE='BI';
    'VDD0P9'<3>:
      PIN_NUMBER='(42)';
      PINUSE='POWER';
      NO_LOAD_CHECK='Both';
      NO_IO_CHECK='Both';
      NO_ASSERT_CHECK='TRUE';
      NO_DIR_CHECK='TRUE';
      ALLOW_CONNECT='TRUE';
    'VDD0P9'<2>:
      PIN_NUMBER='(11)';
      PINUSE='POWER';
      NO_LOAD_CHECK='Both';
      NO_IO_CHECK='Both';
      NO_ASSERT_CHECK='TRUE';
      NO_DIR_CHECK='TRUE';
      ALLOW_CONNECT='TRUE';
    'VDD0P9'<1>:
      PIN_NUMBER='(32)';
      PINUSE='POWER';
      NO_LOAD_CHECK='Both';
      NO_IO_CHECK='Both';
      NO_ASSERT_CHECK='TRUE';
      NO_DIR_CHECK='TRUE';
      ALLOW_CONNECT='TRUE';
    'VDD0P9'<0>:
      PIN_NUMBER='(59)';
      PINUSE='POWER';
      NO_LOAD_CHECK='Both';
      NO_IO_CHECK='Both';
      NO_ASSERT_CHECK='TRUE';
      NO_DIR_CHECK='TRUE';
      ALLOW_CONNECT='TRUE';
    'VDD0P9_OUT':
      PIN_NUMBER='(38)';
      PINUSE='POWER';
      NO_LOAD_CHECK='Both';
      NO_IO_CHECK='Both';
      NO_ASSERT_CHECK='TRUE';
      NO_DIR_CHECK='TRUE';
      ALLOW_CONNECT='TRUE';
    'VDD1P5'<1>:
      PIN_NUMBER='(47)';
      PINUSE='POWER';
      NO_LOAD_CHECK='Both';
      NO_IO_CHECK='Both';
      NO_ASSERT_CHECK='TRUE';
      NO_DIR_CHECK='TRUE';
      ALLOW_CONNECT='TRUE';
    'VDD1P5'<0>:
      PIN_NUMBER='(56)';
      PINUSE='POWER';
      NO_LOAD_CHECK='Both';
      NO_IO_CHECK='Both';
      NO_ASSERT_CHECK='TRUE';
      NO_DIR_CHECK='TRUE';
      ALLOW_CONNECT='TRUE';
    'VDD1P5_OUT':
      PIN_NUMBER='(39)';
      PINUSE='POWER';
      NO_LOAD_CHECK='Both';
      NO_IO_CHECK='Both';
      NO_ASSERT_CHECK='TRUE';
      NO_DIR_CHECK='TRUE';
      ALLOW_CONNECT='TRUE';
    'VDD3P3'<4>:
      PIN_NUMBER='(10)';
      PINUSE='POWER';
      NO_LOAD_CHECK='Both';
      NO_IO_CHECK='Both';
      NO_ASSERT_CHECK='TRUE';
      NO_DIR_CHECK='TRUE';
      ALLOW_CONNECT='TRUE';
    'VDD3P3'<3>:
      PIN_NUMBER='(27)';
      PINUSE='POWER';
      NO_LOAD_CHECK='Both';
      NO_IO_CHECK='Both';
      NO_ASSERT_CHECK='TRUE';
      NO_DIR_CHECK='TRUE';
      ALLOW_CONNECT='TRUE';
    'VDD3P3'<2>:
      PIN_NUMBER='(41)';
      PINUSE='POWER';
      NO_LOAD_CHECK='Both';
      NO_IO_CHECK='Both';
      NO_ASSERT_CHECK='TRUE';
      NO_DIR_CHECK='TRUE';
      ALLOW_CONNECT='TRUE';
    'VDD3P3'<1>:
      PIN_NUMBER='(51)';
      PINUSE='POWER';
      NO_LOAD_CHECK='Both';
      NO_IO_CHECK='Both';
      NO_ASSERT_CHECK='TRUE';
      NO_DIR_CHECK='TRUE';
      ALLOW_CONNECT='TRUE';
    'VDD3P3'<0>:
      PIN_NUMBER='(64)';
      PINUSE='POWER';
      NO_LOAD_CHECK='Both';
      NO_IO_CHECK='Both';
      NO_ASSERT_CHECK='TRUE';
      NO_DIR_CHECK='TRUE';
      ALLOW_CONNECT='TRUE';
    'XTAL1':
      PIN_NUMBER='(46)';
      INPUT_LOAD='(-0.01,0.01)';
      PINUSE='IN';
    'XTAL2':
      PIN_NUMBER='(45)';
      OUTPUT_LOAD='(1.0,-1.0)';
      PINUSE='OUT';
  end_pin;
  body
      PART_NAME='SPRINGVILLE';
      PHYS_DES_PREFIX='EU';
      ENVCOMP='YES;YES;YES;UNK;ok;VLD';
      PART_NUMBER='G47144-004';
      JEDEC_TYPE='QFN64_36_5ME';
      DESCRIPTION='(USE SYM_2)SPRINGVILLE GbE CONTROLLER,A2(142 SQ TH PAD)';
      CLASS='IC';
      COMPONENT_TYPE='LCC';
      HEIGHT='0.039 IN';
      LPID='2655';
      SPEED_URL='http://speed.intel.com:8081/speed/module/pdm/item/pdm_item_deta~
il_direct.asp?item_cde=G47144-004&item_rev=01&url_param=unused';
      STATUS='Approved';
      RPL='NO';
      AML='1';
      BUS_UNIT='LAD_SILICON';
      DAYS='84';
      PARENT_PART_TYPE='SPRINGVILLE_SM1';
      PARENT_PPT='SPRINGVILLE';
      PARENT_PPT_PART='SPRINGVILLE_SM1-IC,G47144-004';
  end_body;
end_primitive;
primitive 'ST220U10VDM-LGP_SMD-TCG-ST220UA';
  pin
    '1':
      PIN_NUMBER='(1)';
      PIN_TYPE='ANALOG';
      NO_LOAD_CHECK='Both';
      NO_IO_CHECK='Both';
      NO_ASSERT_CHECK='TRUE';
      NO_DIR_CHECK='TRUE';
      ALLOW_CONNECT='TRUE';
      PINUSE='UNSPEC';
    '2':
      PIN_NUMBER='(2)';
      PIN_TYPE='ANALOG';
      NO_LOAD_CHECK='Both';
      NO_IO_CHECK='Both';
      NO_ASSERT_CHECK='TRUE';
      NO_DIR_CHECK='TRUE';
      ALLOW_CONNECT='TRUE';
      PINUSE='UNSPEC';
  end_pin;
  body
      PART_NAME='ST220U10VDM-LGP';
      BODY_NAME='ST220U10VDM-LGP';
      PHYS_DES_PREFIX='TC';
      CLASS='DISCRETE';
      DESCRIPTION='CHIP CAP POS 220U 10V M7343';
      JEDEC_TYPE='CT7343H119';
      PARENT_PART_TYPE='ST220U10VDM-LGP';
      PARENT_PPT='ST220U10VDM-LGP';
      PARENT_PPT_PART='ST220U10VDM-LGP_SMD-TCG-ST220U10VDM-LGP,77.22271.L03,220UF,IRP=2400MA,10V,ESR=25MOHM,TMAX=105C';
  end_body;
end_primitive;
primitive 'ST270U2D5VBM-GP_SMD-TCG2-ST270A';
  pin
    '1':
      PIN_NUMBER='(1)';
      PIN_TYPE='ANALOG';
      NO_LOAD_CHECK='Both';
      NO_IO_CHECK='Both';
      NO_ASSERT_CHECK='TRUE';
      NO_DIR_CHECK='TRUE';
      ALLOW_CONNECT='TRUE';
      PINUSE='UNSPEC';
    '2':
      PIN_NUMBER='(2)';
      PIN_TYPE='ANALOG';
      NO_LOAD_CHECK='Both';
      NO_IO_CHECK='Both';
      NO_ASSERT_CHECK='TRUE';
      NO_DIR_CHECK='TRUE';
      ALLOW_CONNECT='TRUE';
      PINUSE='UNSPEC';
  end_pin;
  body
      PART_NAME='ST270U2D5VBM-GP';
      BODY_NAME='ST270U2D5VBM-GP';
      PHYS_DES_PREFIX='TC';
      CLASS='DISCRETE';
      DESCRIPTION='CHIP CAP POLY T 270UF 2.5V M3528 TPSF';
      JEDEC_TYPE='CT3528H79';
      PARENT_PART_TYPE='ST270U2D5VBM-GP';
      PARENT_PPT='ST270U2D5VBM-GP';
      PARENT_PPT_PART='ST270U2D5VBM-GP_SMD-TCG2-ST270U2D5VBM-GP,077.C2771.0001';
  end_body;
end_primitive;
primitive 'ST470U6D3VDM-7-GP_SMD-TCG4-ST4A';
  pin
    '1':
      PIN_NUMBER='(1)';
      PIN_TYPE='ANALOG';
      NO_LOAD_CHECK='Both';
      NO_IO_CHECK='Both';
      NO_ASSERT_CHECK='TRUE';
      NO_DIR_CHECK='TRUE';
      ALLOW_CONNECT='TRUE';
      PINUSE='UNSPEC';
    '2':
      PIN_NUMBER='(2)';
      PIN_TYPE='ANALOG';
      NO_LOAD_CHECK='Both';
      NO_IO_CHECK='Both';
      NO_ASSERT_CHECK='TRUE';
      NO_DIR_CHECK='TRUE';
      ALLOW_CONNECT='TRUE';
      PINUSE='UNSPEC';
  end_pin;
  body
      PART_NAME='ST470U6D3VDM-7-GP';
      BODY_NAME='ST470U6D3VDM-7-GP';
      PHYS_DES_PREFIX='TC';
      CLASS='DISCRETE';
      DESCRIPTION='CHIP CAP POLY T 470U 6.3V M 6TPE470MAZU';
      JEDEC_TYPE='CT7343H60';
      PARENT_PART_TYPE='ST470U6D3VDM-7-GP';
      PARENT_PPT='ST470U6D3VDM-7-GP';
      PARENT_PPT_PART='ST470U6D3VDM-7-GP_SMD-TCG4-ST470U6D3VDM-7-GP,077.C4771.0061,470UF,IRP=1.7A,6.3V,ESR=35MOHM,TMAX=105C';
  end_body;
end_primitive;
primitive 'STANDOFF_TH1-SO,H72821-001';
  pin
    'IO1':
      PIN_NUMBER='(1)';
      BIDIRECTIONAL='TRUE';
      INPUT_LOAD='(-0.01,0.01)';
      OUTPUT_LOAD='(1.0,-1.0)';
      PINUSE='BI';
  end_pin;
  body
      PART_NAME='STANDOFF';
      PHYS_DES_PREFIX='RM';
      ENVCOMP='';
      PART_NUMBER='H72821-001';
      JEDEC_TYPE='STANDOFF177';
      CLASS='IO';
      HEIGHT='0.167 IN';
      COMPONENT_TYPE='PSEUDO';
      LEAD_LENGTH='0.067';
      LPID='';
      SPEED_URL='http://speed.intel.com:8081/speed/module/pdm/item/pdm_item_deta~
il_direct.asp?item_cde=H72821-001&item_rev=01&url_param=unused';
      STATUS='';
      RPL='';
      AML='';
      BUS_UNIT='';
      DAYS='';
      PARENT_PART_TYPE='STANDOFF_TH1';
      PARENT_PPT='STANDOFF';
      PARENT_PPT_PART='STANDOFF_TH1-SO,H72821-001';
  end_body;
end_primitive;
primitive 'STFT363B238R224H453-GP_DISCRETA';
  pin
    '1':
      PIN_NUMBER='(1)';
      PIN_TYPE='ANALOG';
      NO_LOAD_CHECK='Both';
      NO_IO_CHECK='Both';
      NO_ASSERT_CHECK='TRUE';
      NO_DIR_CHECK='TRUE';
      ALLOW_CONNECT='TRUE';
      PINUSE='UNSPEC';
  end_pin;
  body
      PART_NAME='STFT363B238R224H453-GP';
      BODY_NAME='STFT363B238R224H453-GP';
      PHYS_DES_PREFIX='HS';
      CLASS='DISCRETE';
      DESCRIPTION='THUMB SCREW SMT M3X0.5 L4.6';
      JEDEC_TYPE='STFT363B238R224H453';
      PARENT_PART_TYPE='STFT363B238R224H453-GP';
      PARENT_PPT='STFT363B238R224H453-GP';
      PARENT_PPT_PART='STFT363B238R224H453-GP_DISCRET-GC1-STFT363B238R224H453-GP,086.2AT24.04R6';
  end_body;
end_primitive;
primitive 'SW-SLIDE75-GP_DISCRET-G6-SW-SLA';
  pin
    '1':
      PIN_NUMBER='(1)';
      PIN_TYPE='ANALOG';
      NO_LOAD_CHECK='Both';
      NO_IO_CHECK='Both';
      NO_ASSERT_CHECK='TRUE';
      NO_DIR_CHECK='TRUE';
      ALLOW_CONNECT='TRUE';
      PINUSE='UNSPEC';
    '2':
      PIN_NUMBER='(2)';
      PIN_TYPE='ANALOG';
      NO_LOAD_CHECK='Both';
      NO_IO_CHECK='Both';
      NO_ASSERT_CHECK='TRUE';
      NO_DIR_CHECK='TRUE';
      ALLOW_CONNECT='TRUE';
      PINUSE='UNSPEC';
    '3':
      PIN_NUMBER='(3)';
      PIN_TYPE='ANALOG';
      NO_LOAD_CHECK='Both';
      NO_IO_CHECK='Both';
      NO_ASSERT_CHECK='TRUE';
      NO_DIR_CHECK='TRUE';
      ALLOW_CONNECT='TRUE';
      PINUSE='UNSPEC';
    '4':
      PIN_NUMBER='(4)';
      PIN_TYPE='ANALOG';
      NO_LOAD_CHECK='Both';
      NO_IO_CHECK='Both';
      NO_ASSERT_CHECK='TRUE';
      NO_DIR_CHECK='TRUE';
      ALLOW_CONNECT='TRUE';
      PINUSE='UNSPEC';
    '5':
      PIN_NUMBER='(5)';
      PIN_TYPE='ANALOG';
      NO_LOAD_CHECK='Both';
      NO_IO_CHECK='Both';
      NO_ASSERT_CHECK='TRUE';
      NO_DIR_CHECK='TRUE';
      ALLOW_CONNECT='TRUE';
      PINUSE='UNSPEC';
    'NP1':
      PIN_NUMBER='(NP1)';
      PIN_TYPE='ANALOG';
      NO_LOAD_CHECK='Both';
      NO_IO_CHECK='Both';
      NO_ASSERT_CHECK='TRUE';
      NO_DIR_CHECK='TRUE';
      ALLOW_CONNECT='TRUE';
      PINUSE='UNSPEC';
    'NP2':
      PIN_NUMBER='(NP2)';
      PIN_TYPE='ANALOG';
      NO_LOAD_CHECK='Both';
      NO_IO_CHECK='Both';
      NO_ASSERT_CHECK='TRUE';
      NO_DIR_CHECK='TRUE';
      ALLOW_CONNECT='TRUE';
      PINUSE='UNSPEC';
    '6':
      PIN_NUMBER='(6)';
      PIN_TYPE='ANALOG';
      NO_LOAD_CHECK='Both';
      NO_IO_CHECK='Both';
      NO_ASSERT_CHECK='TRUE';
      NO_DIR_CHECK='TRUE';
      ALLOW_CONNECT='TRUE';
      PINUSE='UNSPEC';
    '7':
      PIN_NUMBER='(7)';
      PIN_TYPE='ANALOG';
      NO_LOAD_CHECK='Both';
      NO_IO_CHECK='Both';
      NO_ASSERT_CHECK='TRUE';
      NO_DIR_CHECK='TRUE';
      ALLOW_CONNECT='TRUE';
      PINUSE='UNSPEC';
  end_pin;
  body
      PART_NAME='SW-SLIDE75-GP';
      BODY_NAME='SW-SLIDE75-GP';
      PHYS_DES_PREFIX='SW';
      CLASS='IO';
      DESCRIPTION='SW SLIDE 3P MSS3-V-T/R SMD';
      JEDEC_TYPE='MSS3-V-T-R';
      PARENT_PART_TYPE='SW-SLIDE75-GP';
      PARENT_PPT='SW-SLIDE75-GP';
      PARENT_PPT_PART='SW-SLIDE75-GP_DISCRET-G6-SW-SLIDE75-GP,62.40018.461';
  end_body;
end_primitive;
primitive 'SWITCH_D37771002_SM-IC,D37771-A';
  pin
    'PIN4':
      PIN_NUMBER='(4)';
      PINUSE='UNSPEC';
      NO_LOAD_CHECK='Both';
      NO_IO_CHECK='Both';
    'PIN3':
      PIN_NUMBER='(3)';
      PINUSE='UNSPEC';
      NO_LOAD_CHECK='Both';
      NO_IO_CHECK='Both';
    'PIN1':
      PIN_NUMBER='(1)';
      PINUSE='UNSPEC';
      NO_LOAD_CHECK='Both';
      NO_IO_CHECK='Both';
    'PIN2':
      PIN_NUMBER='(2)';
      PINUSE='UNSPEC';
      NO_LOAD_CHECK='Both';
      NO_IO_CHECK='Both';
  end_pin;
  body
      PART_NAME='SWITCH_D37771002';
      PHYS_DES_PREFIX='S';
      ENVCOMP='UNK;UNK;UNK;UNK;ok;CIP';
      PART_NUMBER='D37771-002';
      JEDEC_TYPE='SSW4RPE';
      CLASS='IC';
      DESCRIPTION='CONN,SWIT,TACTILE,VT,SPST,1,50.0V,SMT';
      HEIGHT='0.396 IN';
      COMPONENT_TYPE='SMTOTHER';
      LPID='';
      SPEED_URL='http://speed.intel.com:8081/speed/module/pdm/item/pdm_item_deta~
il_direct.asp?item_cde=D37771-002&item_rev=01&url_param=unused';
      STATUS='Design';
      RPL='NO';
      AML='1';
      BUS_UNIT='SMO_BOARDS';
      DAYS='???';
      PARENT_PART_TYPE='SWITCH_D37771002_SM';
      PARENT_PPT='SWITCH_D37771002';
      PARENT_PPT_PART='SWITCH_D37771002_SM-IC,D37771-002';
  end_body;
end_primitive;
primitive 'SWITCH_D90553001_SMLF-IC,D9055A';
  pin
    'A':
      PIN_NUMBER='(1)';
      INPUT_LOAD='(-0.01,0.01)';
      PINUSE='IN';
    'B':
      PIN_NUMBER='(2)';
      INPUT_LOAD='(-0.01,0.01)';
      OUTPUT_LOAD='(1.0,-1.0)';
      OUTPUT_TYPE='(TS,TS)';
      BIDIRECTIONAL='TRUE';
      PINUSE='BI';
  end_pin;
  body
      PART_NAME='SWITCH_D90553001';
      PHYS_DES_PREFIX='S';
      ENVCOMP='YES;YES;UNK;UNK;ok;CIP';
      PART_NUMBER='D90553-001';
      JEDEC_TYPE='SSW2RPB';
      DESCRIPTION='SW PB SMT TL1015AF160QG';
      CLASS='IC';
      HEIGHT='0.083 IN';
      COMPONENT_TYPE='SMTOTHER';
      LPID='';
      SPEED_URL='http://speed.intel.com:8081/speed/module/pdm/item/pdm_item_deta~
il_direct.asp?item_cde=D90553-001&item_rev=01&url_param=unused';
      STATUS='Conditional';
      RPL='NO';
      AML='1';
      BUS_UNIT='SMO_BOARDS';
      DAYS='???';
      PARENT_PART_TYPE='SWITCH_D90553001_SMLF';
      PARENT_PPT='SWITCH_D90553001';
      PARENT_PPT_PART='SWITCH_D90553001_SMLF-IC,D90553-001';
  end_body;
end_primitive;
primitive 'TC7PZ14FU-GP_DISCRET-GA1-TC7PZA';
  pin
    '1A':
      PIN_NUMBER='(1)';
      INPUT_LOAD='(-0.01,0.01)';
      PINUSE='IN';
    'GND':
      PIN_NUMBER='(2)';
      PINUSE='POWER';
      NO_LOAD_CHECK='Both';
      NO_IO_CHECK='Both';
      NO_ASSERT_CHECK='TRUE';
      NO_DIR_CHECK='TRUE';
      ALLOW_CONNECT='TRUE';
    '2A':
      PIN_NUMBER='(3)';
      INPUT_LOAD='(-0.01,0.01)';
      PINUSE='IN';
    '2Y':
      PIN_NUMBER='(4)';
      OUTPUT_LOAD='(1.0,-1.0)';
      PINUSE='OUT';
    'VCC':
      PIN_NUMBER='(5)';
      PINUSE='POWER';
      NO_LOAD_CHECK='Both';
      NO_IO_CHECK='Both';
      NO_ASSERT_CHECK='TRUE';
      NO_DIR_CHECK='TRUE';
      ALLOW_CONNECT='TRUE';
    '1Y':
      PIN_NUMBER='(6)';
      OUTPUT_LOAD='(1.0,-1.0)';
      PINUSE='OUT';
  end_pin;
  body
      PART_NAME='TC7PZ14FU-GP';
      BODY_NAME='TC7PZ14FU-GP';
      PHYS_DES_PREFIX='U';
      CLASS='IC';
      DESCRIPTION='IC CMOS TC7PZ14FU SSOP6';
      JEDEC_TYPE='SC70-6H44';
      PARENT_PART_TYPE='TC7PZ14FU-GP';
      PARENT_PPT='TC7PZ14FU-GP';
      PARENT_PPT_PART='TC7PZ14FU-GP_DISCRET-GA1-TC7PZ14FU-GP,073.7PZ14.0007';
  end_body;
end_primitive;
primitive 'TCA9517DGKR-GP_DISCRET-G8-TCA9A';
  pin
    'VCCA':
      PIN_NUMBER='(1)';
      PINUSE='POWER';
      NO_LOAD_CHECK='Both';
      NO_IO_CHECK='Both';
      NO_ASSERT_CHECK='TRUE';
      NO_DIR_CHECK='TRUE';
      ALLOW_CONNECT='TRUE';
    'SCLA':
      PIN_NUMBER='(2)';
      PIN_TYPE='ANALOG';
      NO_LOAD_CHECK='Both';
      NO_IO_CHECK='Both';
      NO_ASSERT_CHECK='TRUE';
      NO_DIR_CHECK='TRUE';
      ALLOW_CONNECT='TRUE';
      PINUSE='UNSPEC';
    'SDAA':
      PIN_NUMBER='(3)';
      PIN_TYPE='ANALOG';
      NO_LOAD_CHECK='Both';
      NO_IO_CHECK='Both';
      NO_ASSERT_CHECK='TRUE';
      NO_DIR_CHECK='TRUE';
      ALLOW_CONNECT='TRUE';
      PINUSE='UNSPEC';
    'GND':
      PIN_NUMBER='(4)';
      PINUSE='POWER';
      NO_LOAD_CHECK='Both';
      NO_IO_CHECK='Both';
      NO_ASSERT_CHECK='TRUE';
      NO_DIR_CHECK='TRUE';
      ALLOW_CONNECT='TRUE';
    'VCCB':
      PIN_NUMBER='(8)';
      PINUSE='POWER';
      NO_LOAD_CHECK='Both';
      NO_IO_CHECK='Both';
      NO_ASSERT_CHECK='TRUE';
      NO_DIR_CHECK='TRUE';
      ALLOW_CONNECT='TRUE';
    'SCLB':
      PIN_NUMBER='(7)';
      PIN_TYPE='ANALOG';
      NO_LOAD_CHECK='Both';
      NO_IO_CHECK='Both';
      NO_ASSERT_CHECK='TRUE';
      NO_DIR_CHECK='TRUE';
      ALLOW_CONNECT='TRUE';
      PINUSE='UNSPEC';
    'SDAB':
      PIN_NUMBER='(6)';
      PIN_TYPE='ANALOG';
      NO_LOAD_CHECK='Both';
      NO_IO_CHECK='Both';
      NO_ASSERT_CHECK='TRUE';
      NO_DIR_CHECK='TRUE';
      ALLOW_CONNECT='TRUE';
      PINUSE='UNSPEC';
    'EN':
      PIN_NUMBER='(5)';
      PIN_TYPE='ANALOG';
      NO_LOAD_CHECK='Both';
      NO_IO_CHECK='Both';
      NO_ASSERT_CHECK='TRUE';
      NO_DIR_CHECK='TRUE';
      ALLOW_CONNECT='TRUE';
      PINUSE='UNSPEC';
  end_pin;
  body
      PART_NAME='TCA9517DGKR-GP';
      BODY_NAME='TCA9517DGKR-GP';
      PHYS_DES_PREFIX='U';
      CLASS='IC';
      DESCRIPTION='IC REPEATER TCA9517DGKR MSOP 8P';
      JEDEC_TYPE='MSOP8-1H44';
      PARENT_PART_TYPE='TCA9517DGKR-GP';
      PARENT_PPT='TCA9517DGKR-GP';
      PARENT_PPT_PART='TCA9517DGKR-GP_DISCRET-G8-TCA9517DGKR-GP,071.09517.0009';
  end_body;
end_primitive;
primitive 'TCA9555PWR-GP_DISCRET-GC1-TCA9A';
  pin
    'INT#':
      PIN_NUMBER='(1)';
      OUTPUT_LOAD='(1.0,-1.0)';
      PINUSE='OUT';
    'A1':
      PIN_NUMBER='(2)';
      INPUT_LOAD='(-0.01,0.01)';
      PINUSE='IN';
    'A2':
      PIN_NUMBER='(3)';
      INPUT_LOAD='(-0.01,0.01)';
      PINUSE='IN';
    'P00':
      PIN_NUMBER='(4)';
      BIDIRECTIONAL='TRUE';
      INPUT_LOAD='(-0.01,0.01)';
      OUTPUT_LOAD='(1.0,-1.0)';
      PINUSE='BI';
    'P01':
      PIN_NUMBER='(5)';
      BIDIRECTIONAL='TRUE';
      INPUT_LOAD='(-0.01,0.01)';
      OUTPUT_LOAD='(1.0,-1.0)';
      PINUSE='BI';
    'P02':
      PIN_NUMBER='(6)';
      BIDIRECTIONAL='TRUE';
      INPUT_LOAD='(-0.01,0.01)';
      OUTPUT_LOAD='(1.0,-1.0)';
      PINUSE='BI';
    'P03':
      PIN_NUMBER='(7)';
      BIDIRECTIONAL='TRUE';
      INPUT_LOAD='(-0.01,0.01)';
      OUTPUT_LOAD='(1.0,-1.0)';
      PINUSE='BI';
    'P04':
      PIN_NUMBER='(8)';
      BIDIRECTIONAL='TRUE';
      INPUT_LOAD='(-0.01,0.01)';
      OUTPUT_LOAD='(1.0,-1.0)';
      PINUSE='BI';
    'P05':
      PIN_NUMBER='(9)';
      BIDIRECTIONAL='TRUE';
      INPUT_LOAD='(-0.01,0.01)';
      OUTPUT_LOAD='(1.0,-1.0)';
      PINUSE='BI';
    'P06':
      PIN_NUMBER='(10)';
      BIDIRECTIONAL='TRUE';
      INPUT_LOAD='(-0.01,0.01)';
      OUTPUT_LOAD='(1.0,-1.0)';
      PINUSE='BI';
    'P07':
      PIN_NUMBER='(11)';
      BIDIRECTIONAL='TRUE';
      INPUT_LOAD='(-0.01,0.01)';
      OUTPUT_LOAD='(1.0,-1.0)';
      PINUSE='BI';
    'GND':
      PIN_NUMBER='(12)';
      PINUSE='POWER';
      NO_LOAD_CHECK='Both';
      NO_IO_CHECK='Both';
      NO_ASSERT_CHECK='TRUE';
      NO_DIR_CHECK='TRUE';
      ALLOW_CONNECT='TRUE';
    'VCC':
      PIN_NUMBER='(24)';
      PINUSE='POWER';
      NO_LOAD_CHECK='Both';
      NO_IO_CHECK='Both';
      NO_ASSERT_CHECK='TRUE';
      NO_DIR_CHECK='TRUE';
      ALLOW_CONNECT='TRUE';
    'SDA':
      PIN_NUMBER='(23)';
      PIN_TYPE='ANALOG';
      NO_LOAD_CHECK='Both';
      NO_IO_CHECK='Both';
      NO_ASSERT_CHECK='TRUE';
      NO_DIR_CHECK='TRUE';
      ALLOW_CONNECT='TRUE';
      PINUSE='UNSPEC';
    'SCL':
      PIN_NUMBER='(22)';
      PIN_TYPE='ANALOG';
      NO_LOAD_CHECK='Both';
      NO_IO_CHECK='Both';
      NO_ASSERT_CHECK='TRUE';
      NO_DIR_CHECK='TRUE';
      ALLOW_CONNECT='TRUE';
      PINUSE='UNSPEC';
    'A0':
      PIN_NUMBER='(21)';
      INPUT_LOAD='(-0.01,0.01)';
      PINUSE='IN';
    'P10':
      PIN_NUMBER='(13)';
      BIDIRECTIONAL='TRUE';
      INPUT_LOAD='(-0.01,0.01)';
      OUTPUT_LOAD='(1.0,-1.0)';
      PINUSE='BI';
    'P11':
      PIN_NUMBER='(14)';
      BIDIRECTIONAL='TRUE';
      INPUT_LOAD='(-0.01,0.01)';
      OUTPUT_LOAD='(1.0,-1.0)';
      PINUSE='BI';
    'P12':
      PIN_NUMBER='(15)';
      BIDIRECTIONAL='TRUE';
      INPUT_LOAD='(-0.01,0.01)';
      OUTPUT_LOAD='(1.0,-1.0)';
      PINUSE='BI';
    'P13':
      PIN_NUMBER='(16)';
      BIDIRECTIONAL='TRUE';
      INPUT_LOAD='(-0.01,0.01)';
      OUTPUT_LOAD='(1.0,-1.0)';
      PINUSE='BI';
    'P14':
      PIN_NUMBER='(17)';
      BIDIRECTIONAL='TRUE';
      INPUT_LOAD='(-0.01,0.01)';
      OUTPUT_LOAD='(1.0,-1.0)';
      PINUSE='BI';
    'P15':
      PIN_NUMBER='(18)';
      BIDIRECTIONAL='TRUE';
      INPUT_LOAD='(-0.01,0.01)';
      OUTPUT_LOAD='(1.0,-1.0)';
      PINUSE='BI';
    'P16':
      PIN_NUMBER='(19)';
      BIDIRECTIONAL='TRUE';
      INPUT_LOAD='(-0.01,0.01)';
      OUTPUT_LOAD='(1.0,-1.0)';
      PINUSE='BI';
    'P17':
      PIN_NUMBER='(20)';
      BIDIRECTIONAL='TRUE';
      INPUT_LOAD='(-0.01,0.01)';
      OUTPUT_LOAD='(1.0,-1.0)';
      PINUSE='BI';
  end_pin;
  body
      PART_NAME='TCA9555PWR-GP';
      BODY_NAME='TCA9555PWR-GP';
      PHYS_DES_PREFIX='U';
      CLASS='IC';
      DESCRIPTION='IC I/O EXPANDER TCA9555PWR TSSOP 24P';
      JEDEC_TYPE='TSOIC24H48';
      PARENT_PART_TYPE='TCA9555PWR-GP';
      PARENT_PPT='TCA9555PWR-GP';
      PARENT_PPT_PART='TCA9555PWR-GP_DISCRET-GC1-TCA9555PWR-GP,071.09555.000W';
  end_body;
end_primitive;
primitive 'TEST-PAD-12P-1-GP-U_DISCRET-GBA';
  pin
    'GND'<0>:
      PIN_NUMBER='(3)';
      PINUSE='POWER';
      NO_LOAD_CHECK='Both';
      NO_IO_CHECK='Both';
      NO_ASSERT_CHECK='TRUE';
      NO_DIR_CHECK='TRUE';
      ALLOW_CONNECT='TRUE';
    'GND'<1>:
      PIN_NUMBER='(4)';
      PINUSE='POWER';
      NO_LOAD_CHECK='Both';
      NO_IO_CHECK='Both';
      NO_ASSERT_CHECK='TRUE';
      NO_DIR_CHECK='TRUE';
      ALLOW_CONNECT='TRUE';
    'GND'<2>:
      PIN_NUMBER='(5)';
      PINUSE='POWER';
      NO_LOAD_CHECK='Both';
      NO_IO_CHECK='Both';
      NO_ASSERT_CHECK='TRUE';
      NO_DIR_CHECK='TRUE';
      ALLOW_CONNECT='TRUE';
    'GND'<3>:
      PIN_NUMBER='(6)';
      PINUSE='POWER';
      NO_LOAD_CHECK='Both';
      NO_IO_CHECK='Both';
      NO_ASSERT_CHECK='TRUE';
      NO_DIR_CHECK='TRUE';
      ALLOW_CONNECT='TRUE';
    'GND'<4>:
      PIN_NUMBER='(7)';
      PINUSE='POWER';
      NO_LOAD_CHECK='Both';
      NO_IO_CHECK='Both';
      NO_ASSERT_CHECK='TRUE';
      NO_DIR_CHECK='TRUE';
      ALLOW_CONNECT='TRUE';
    'GND'<5>:
      PIN_NUMBER='(8)';
      PINUSE='POWER';
      NO_LOAD_CHECK='Both';
      NO_IO_CHECK='Both';
      NO_ASSERT_CHECK='TRUE';
      NO_DIR_CHECK='TRUE';
      ALLOW_CONNECT='TRUE';
    'GND'<6>:
      PIN_NUMBER='(9)';
      PINUSE='POWER';
      NO_LOAD_CHECK='Both';
      NO_IO_CHECK='Both';
      NO_ASSERT_CHECK='TRUE';
      NO_DIR_CHECK='TRUE';
      ALLOW_CONNECT='TRUE';
    'GND'<7>:
      PIN_NUMBER='(10)';
      PINUSE='POWER';
      NO_LOAD_CHECK='Both';
      NO_IO_CHECK='Both';
      NO_ASSERT_CHECK='TRUE';
      NO_DIR_CHECK='TRUE';
      ALLOW_CONNECT='TRUE';
    'GND'<8>:
      PIN_NUMBER='(11)';
      PINUSE='POWER';
      NO_LOAD_CHECK='Both';
      NO_IO_CHECK='Both';
      NO_ASSERT_CHECK='TRUE';
      NO_DIR_CHECK='TRUE';
      ALLOW_CONNECT='TRUE';
    'GND'<9>:
      PIN_NUMBER='(12)';
      PINUSE='POWER';
      NO_LOAD_CHECK='Both';
      NO_IO_CHECK='Both';
      NO_ASSERT_CHECK='TRUE';
      NO_DIR_CHECK='TRUE';
      ALLOW_CONNECT='TRUE';
    'DP':
      PIN_NUMBER='(1)';
      PIN_TYPE='ANALOG';
      NO_LOAD_CHECK='Both';
      NO_IO_CHECK='Both';
      NO_ASSERT_CHECK='TRUE';
      NO_DIR_CHECK='TRUE';
      ALLOW_CONNECT='TRUE';
      PINUSE='UNSPEC';
    'DN':
      PIN_NUMBER='(2)';
      PIN_TYPE='ANALOG';
      NO_LOAD_CHECK='Both';
      NO_IO_CHECK='Both';
      NO_ASSERT_CHECK='TRUE';
      NO_DIR_CHECK='TRUE';
      ALLOW_CONNECT='TRUE';
      PINUSE='UNSPEC';
  end_pin;
  body
      PART_NAME='TEST-PAD-12P-1-GP-U';
      BODY_NAME='TEST-PAD-12P-1-GP-U';
      PHYS_DES_PREFIX='PAD';
      CLASS='DISCRETE';
      DESCRIPTION='TEST PAD 3P FOR COUPON TRACE';
      JEDEC_TYPE='TEST-PAD-12P-1-U';
      PARENT_PART_TYPE='TEST-PAD-12P-1-GP-U';
      PARENT_PPT='TEST-PAD-12P-1-GP-U';
      PARENT_PPT_PART='TEST-PAD-12P-1-GP-U_DISCRET-GB1-TEST-PAD-12P-1-GP-U,ZZ.00PAD.MJ1';
  end_body;
end_primitive;
primitive 'TMP421_TSSOP-IC,G62962-001';
  pin
    'A'<1>:
      PIN_NUMBER='(3)';
      INPUT_LOAD='(-0.01,0.01)';
      PINUSE='IN';
    'A'<0>:
      PIN_NUMBER='(4)';
      INPUT_LOAD='(-0.01,0.01)';
      PINUSE='IN';
    'DXN':
      PIN_NUMBER='(2)';
      INPUT_LOAD='(-0.01,0.01)';
      PINUSE='IN';
    'DXP':
      PIN_NUMBER='(1)';
      INPUT_LOAD='(-0.01,0.01)';
      PINUSE='IN';
    'GND':
      PIN_NUMBER='(5)';
      PINUSE='GROUND';
      NO_LOAD_CHECK='Both';
      NO_IO_CHECK='Both';
      NO_ASSERT_CHECK='TRUE';
      NO_DIR_CHECK='TRUE';
      ALLOW_CONNECT='TRUE';
    'SCL':
      PIN_NUMBER='(7)';
      BIDIRECTIONAL='TRUE';
      INPUT_LOAD='(-0.01,0.01)';
      OUTPUT_LOAD='(1.0,-1.0)';
      PINUSE='BI';
    'SDA':
      PIN_NUMBER='(6)';
      BIDIRECTIONAL='TRUE';
      INPUT_LOAD='(-0.01,0.01)';
      OUTPUT_LOAD='(1.0,-1.0)';
      PINUSE='BI';
    'VP':
      PIN_NUMBER='(8)';
      PINUSE='POWER';
      NO_LOAD_CHECK='Both';
      NO_IO_CHECK='Both';
      NO_ASSERT_CHECK='TRUE';
      NO_DIR_CHECK='TRUE';
      ALLOW_CONNECT='TRUE';
  end_pin;
  body
      PART_NAME='TMP421';
      PHYS_DES_PREFIX='U';
      ENVCOMP='YES;YES;YES;UNK;ok;VLD';
      PART_NUMBER='G62962-001';
      JEDEC_TYPE='TSSOP8_7_65MB';
      DESCRIPTION='IC,TEMP SENSOR,SOT23-8,TMP421';
      CLASS='IC';
      COMPONENT_TYPE='SMALLSMT';
      HEIGHT='0.057 IN';
      LPID='2407';
      SPEED_URL='http://speed.intel.com:8081/speed/module/pdm/item/pdm_item_deta~
il_direct.asp?item_cde=G62962-001&item_rev=01&url_param=unused';
      STATUS='Design';
      RPL='YES';
      AML='1';
      BUS_UNIT='SMO_IC';
      DAYS='???';
      PARENT_PART_TYPE='TMP421_TSSOP';
      PARENT_PPT='TMP421';
      PARENT_PPT_PART='TMP421_TSSOP-IC,G62962-001';
  end_body;
end_primitive;
primitive 'TPAD-DIFF-4P-GP_DISCRET-GB3-TPA';
  pin
    '1':
      PIN_NUMBER='(1)';
      PIN_TYPE='ANALOG';
      NO_LOAD_CHECK='Both';
      NO_IO_CHECK='Both';
      NO_ASSERT_CHECK='TRUE';
      NO_DIR_CHECK='TRUE';
      ALLOW_CONNECT='TRUE';
      PINUSE='UNSPEC';
    '2':
      PIN_NUMBER='(2)';
      PIN_TYPE='ANALOG';
      NO_LOAD_CHECK='Both';
      NO_IO_CHECK='Both';
      NO_ASSERT_CHECK='TRUE';
      NO_DIR_CHECK='TRUE';
      ALLOW_CONNECT='TRUE';
      PINUSE='UNSPEC';
    'GND1':
      PIN_NUMBER='(GND1)';
      PINUSE='POWER';
      NO_LOAD_CHECK='Both';
      NO_IO_CHECK='Both';
      NO_ASSERT_CHECK='TRUE';
      NO_DIR_CHECK='TRUE';
      ALLOW_CONNECT='TRUE';
    'GND2':
      PIN_NUMBER='(GND2)';
      PINUSE='POWER';
      NO_LOAD_CHECK='Both';
      NO_IO_CHECK='Both';
      NO_ASSERT_CHECK='TRUE';
      NO_DIR_CHECK='TRUE';
      ALLOW_CONNECT='TRUE';
  end_pin;
  body
      PART_NAME='TPAD-DIFF-4P-GP';
      BODY_NAME='TPAD-DIFF-4P-GP';
      PHYS_DES_PREFIX='PAD';
      CLASS='DISCRETE';
      DESCRIPTION='TEST PAD FOR DIFFERENTL IMPEDANCE';
      JEDEC_TYPE='TPAD-DIFF-4P';
      PARENT_PART_TYPE='TPAD-DIFF-4P-GP';
      PARENT_PPT='TPAD-DIFF-4P-GP';
      PARENT_PPT_PART='TPAD-DIFF-4P-GP_DISCRET-GB3-TPAD-DIFF-4P-GP,ZZ.00PAD.NW1';
  end_body;
end_primitive;
primitive 'TPAD-SE-2P-GP_DISCRET-GA1-TPADA';
  pin
    '1':
      PIN_NUMBER='(1)';
      PIN_TYPE='ANALOG';
      NO_LOAD_CHECK='Both';
      NO_IO_CHECK='Both';
      NO_ASSERT_CHECK='TRUE';
      NO_DIR_CHECK='TRUE';
      ALLOW_CONNECT='TRUE';
      PINUSE='UNSPEC';
    'GND1':
      PIN_NUMBER='(GND1)';
      PINUSE='POWER';
      NO_LOAD_CHECK='Both';
      NO_IO_CHECK='Both';
      NO_ASSERT_CHECK='TRUE';
      NO_DIR_CHECK='TRUE';
      ALLOW_CONNECT='TRUE';
  end_pin;
  body
      PART_NAME='TPAD-SE-2P-GP';
      BODY_NAME='TPAD-SE-2P-GP';
      PHYS_DES_PREFIX='TP';
      CLASS='DISCRETE';
      DESCRIPTION='TEST PAD FOR SINGLE-ENDED IMPEDANCE';
      JEDEC_TYPE='TPAD-SE-2P';
      PARENT_PART_TYPE='TPAD-SE-2P-GP';
      PARENT_PPT='TPAD-SE-2P-GP';
      PARENT_PPT_PART='TPAD-SE-2P-GP_DISCRET-GA1-TPAD-SE-2P-GP,ZZ.00PAD.NU1';
  end_body;
end_primitive;
primitive 'TPS2061_SM-IC,H66405-001';
  pin
    'EN_N':
      PIN_NUMBER='(4)';
      INPUT_LOAD='(-0.01,0.01)';
      PINUSE='IN';
    'GND':
      PIN_NUMBER='(2)';
      PINUSE='GROUND';
      NO_LOAD_CHECK='Both';
      NO_IO_CHECK='Both';
      NO_ASSERT_CHECK='TRUE';
      NO_DIR_CHECK='TRUE';
      ALLOW_CONNECT='TRUE';
    'IN':
      PIN_NUMBER='(5)';
      INPUT_LOAD='(-0.01,0.01)';
      PINUSE='IN';
    'OC_N':
      PIN_NUMBER='(3)';
      OUTPUT_LOAD='(1.0,-1.0)';
      PINUSE='OUT';
    'OUT':
      PIN_NUMBER='(1)';
      OUTPUT_LOAD='(1.0,-1.0)';
      PINUSE='OUT';
  end_pin;
  body
      PART_NAME='TPS2061';
      PHYS_DES_PREFIX='U';
      ENVCOMP='';
      PART_NUMBER='H66405-001';
      JEDEC_TYPE='SOT23_5C';
      DESCRIPTION='IC,LIN,ANALOGSWITCH,SOT23,TPS2061D';
      CLASS='IC';
      COMPONENT_TYPE='SMALLSMT';
      HEIGHT='0.057 IN';
      LPID='1815';
      SPEED_URL='http://speed.intel.com:8081/speed/module/pdm/item/pdm_item_deta~
il_direct.asp?item_cde=H66405-001&item_rev=01&url_param=unused';
      STATUS='';
      RPL='';
      AML='';
      BUS_UNIT='';
      DAYS='';
      PARENT_PART_TYPE='TPS2061_SM';
      PARENT_PPT='TPS2061';
      PARENT_PPT_PART='TPS2061_SM-IC,H66405-001';
  end_body;
end_primitive;
primitive 'TPS3700_SM-IC,H69492-001';
  pin
    'GND':
      PIN_NUMBER='(5)';
      PINUSE='GROUND';
      NO_LOAD_CHECK='Both';
      NO_IO_CHECK='Both';
      NO_ASSERT_CHECK='TRUE';
      NO_DIR_CHECK='TRUE';
      ALLOW_CONNECT='TRUE';
    'INAP':
      PIN_NUMBER='(4)';
      BIDIRECTIONAL='TRUE';
      INPUT_LOAD='(-0.01,0.01)';
      OUTPUT_LOAD='(1.0,-1.0)';
      PINUSE='BI';
    'INBN':
      PIN_NUMBER='(3)';
      BIDIRECTIONAL='TRUE';
      INPUT_LOAD='(-0.01,0.01)';
      OUTPUT_LOAD='(1.0,-1.0)';
      PINUSE='BI';
    'OUTA':
      PIN_NUMBER='(6)';
      OUTPUT_LOAD='(1.0,-1.0)';
      PINUSE='OUT';
    'OUTB':
      PIN_NUMBER='(1)';
      OUTPUT_LOAD='(1.0,-1.0)';
      PINUSE='OUT';
    'VDD':
      PIN_NUMBER='(2)';
      PINUSE='POWER';
      NO_LOAD_CHECK='Both';
      NO_IO_CHECK='Both';
      NO_ASSERT_CHECK='TRUE';
      NO_DIR_CHECK='TRUE';
      ALLOW_CONNECT='TRUE';
  end_pin;
  body
      PART_NAME='TPS3700';
      PHYS_DES_PREFIX='U';
      ENVCOMP='';
      PART_NUMBER='H69492-001';
      JEDEC_TYPE='MLFP6_6_5MB';
      DESCRIPTION='IC,LIN,TPS3700,REF';
      CLASS='IC';
      COMPONENT_TYPE='LCC';
      HEIGHT='0.031 IN';
      LPID='3849';
      SPEED_URL='http://speed.intel.com:8081/speed/module/pdm/item/pdm_item_deta~
il_direct.asp?item_cde=H69492-001&item_rev=01&url_param=unused';
      STATUS='';
      RPL='';
      AML='';
      BUS_UNIT='';
      DAYS='';
      PARENT_PART_TYPE='TPS3700_SM';
      PARENT_PPT='TPS3700';
      PARENT_PPT_PART='TPS3700_SM-IC,H69492-001';
  end_body;
end_primitive;
primitive 'TPS54821_LCC-IC,H63269-001';
  pin
    'BOOT':
      PIN_NUMBER='(13)';
      PIN_TYPE='ANALOG';
      NO_LOAD_CHECK='Both';
      NO_IO_CHECK='Both';
      NO_ASSERT_CHECK='TRUE';
      NO_DIR_CHECK='TRUE';
      ALLOW_CONNECT='TRUE';
      PINUSE='UNSPEC';
    'COMP':
      PIN_NUMBER='(8)';
      BIDIRECTIONAL='TRUE';
      INPUT_LOAD='(-0.01,0.01)';
      OUTPUT_LOAD='(1.0,-1.0)';
      PINUSE='BI';
    'EN':
      PIN_NUMBER='(10)';
      INPUT_LOAD='(-0.01,0.01)';
      PINUSE='IN';
    'GND'<1>:
      PIN_NUMBER='(3)';
      PINUSE='GROUND';
      NO_LOAD_CHECK='Both';
      NO_IO_CHECK='Both';
      NO_ASSERT_CHECK='TRUE';
      NO_DIR_CHECK='TRUE';
      ALLOW_CONNECT='TRUE';
    'GND'<0>:
      PIN_NUMBER='(2)';
      PINUSE='GROUND';
      NO_LOAD_CHECK='Both';
      NO_IO_CHECK='Both';
      NO_ASSERT_CHECK='TRUE';
      NO_DIR_CHECK='TRUE';
      ALLOW_CONNECT='TRUE';
    'PH'<1>:
      PIN_NUMBER='(12)';
      OUTPUT_LOAD='(1.0,-1.0)';
      PINUSE='OUT';
    'PH'<0>:
      PIN_NUMBER='(11)';
      OUTPUT_LOAD='(1.0,-1.0)';
      PINUSE='OUT';
    'PVIN'<1>:
      PIN_NUMBER='(5)';
      INPUT_LOAD='(-0.01,0.01)';
      PINUSE='IN';
    'PVIN'<0>:
      PIN_NUMBER='(4)';
      INPUT_LOAD='(-0.01,0.01)';
      PINUSE='IN';
    'PWRGD':
      PIN_NUMBER='(14)';
      OUTPUT_LOAD='(1.0,-1.0)';
      PINUSE='OUT';
    'RT_CLK':
      PIN_NUMBER='(1)';
      INPUT_LOAD='(-0.01,0.01)';
      PINUSE='IN';
    'SS_TR':
      PIN_NUMBER='(9)';
      INPUT_LOAD='(-0.01,0.01)';
      PINUSE='IN';
    'THPAD':
      PIN_NUMBER='(15)';
      PINUSE='GROUND';
      NO_LOAD_CHECK='Both';
      NO_IO_CHECK='Both';
      NO_ASSERT_CHECK='TRUE';
      NO_DIR_CHECK='TRUE';
      ALLOW_CONNECT='TRUE';
    'VIN':
      PIN_NUMBER='(6)';
      INPUT_LOAD='(-0.01,0.01)';
      PINUSE='IN';
    'VSENSE':
      PIN_NUMBER='(7)';
      INPUT_LOAD='(-0.01,0.01)';
      PINUSE='IN';
  end_pin;
  body
      PART_NAME='TPS54821';
      PHYS_DES_PREFIX='EU';
      ENVCOMP='';
      PART_NUMBER='H63269-001';
      JEDEC_TYPE='LCC14_14_5MA';
      DESCRIPTION='IC,LIN,QFN,TPS54821,SWITCHING';
      CLASS='IC';
      COMPONENT_TYPE='LCC';
      HEIGHT='0.039 IN';
      LPID='1956';
      SPEED_URL='http://speed.intel.com:8081/speed/module/pdm/item/pdm_item_deta~
il_direct.asp?item_cde=H63269-001&item_rev=01&url_param=unused';
      STATUS='';
      RPL='';
      AML='';
      BUS_UNIT='';
      DAYS='';
      PARENT_PART_TYPE='TPS54821_LCC';
      PARENT_PPT='TPS54821';
      PARENT_PPT_PART='TPS54821_LCC-IC,H63269-001';
  end_body;
end_primitive;
primitive 'TTL08_QFN15-74LVC08A,IC,D90404B';
  pin
    'Y'<0>:
      OUTPUT_LOAD='(20.0,-1.0)';
      PIN_NUMBER='(11,8,6,3)';
      PINUSE='OUT';
    'B'<0>:
      INPUT_LOAD='(-0.6,0.02)';
      PIN_NUMBER='(13,10,5,2)';
      PIN_GROUP='1';
      PINUSE='IN';
    'A'<0>:
      INPUT_LOAD='(-0.6,0.02)';
      PIN_NUMBER='(12,9,4,1)';
      PIN_GROUP='1';
      PINUSE='IN';
  end_pin;
  body
      PHYS_DES_PREFIX='EU';
      PART_NAME='TTL08';
      ENVCOMP='YES;YES;YES;UNK;ok;VLD';
      PART_NUMBER='D90404-001';
      JEDEC_TYPE='QFN14_14_14_5MB';
      CLASS='IC';
      DESCRIPTION='(USE SYM_2 OR SYM_4) QUAD AND';
      HEIGHT='0.039 IN';
      COMPONENT_TYPE='LCC';
      LPID='1642';
      SPEED_URL='http://speed.intel.com:8081/speed/module/pdm/item/pdm_item_deta~
il_direct.asp?item_cde=D90404-001&item_rev=01&url_param=unused';
      STATUS='Conditional';
      RPL='YES';
      AML='2';
      BUS_UNIT='SMO_IC';
      DAYS='84';
      POWER_PINS='(P3V3_STBY:14;GND:7,15)';
      PARENT_PART_TYPE='TTL08_QFN15';
      SCH_MODIFIED_PART='TRUE';
      PARENT_PPT='TTL08';
      PARENT_PPT_PART='TTL08_QFN15-74LVC08A,IC,D90404-001';
  end_body;
end_primitive;
primitive 'TTL1G07_A_SOP-74LVC1G07,IC,C88B';
  pin
    'A':
      PIN_NUMBER='(2)';
      INPUT_LOAD='(-0.01,0.01)';
      PINUSE='IN';
    'Y':
      PIN_NUMBER='(4)';
      OUTPUT_LOAD='(1.00,-1.00)';
      PINUSE='OUT';
  end_pin;
  body
      PART_NAME='TTL1G07_A';
      PHYS_DES_PREFIX='U';
      NC_PINS='(1)';
      ENVCOMP='YES;YES;YES;UNK;ok;VLD';
      PART_NUMBER='C88419-001';
      JEDEC_TYPE='SSOP5_53_65MA';
      DESCRIPTION='74LVC1G07 BUFFER';
      HEIGHT='0.043 IN';
      COMPONENT_TYPE='SMALLSMT';
      LEAD_LENGTH='';
      LPID='374';
      SPEED_URL='http://speed.intel.com:8081/speed/module/pdm/item/pdm_item_deta~
il_direct.asp?item_cde=C88419-001&item_rev=01&url_param=unused';
      STATUS='Approved';
      RPL='YES';
      AML='6';
      BUS_UNIT='SMO_IC';
      DAYS='28';
      POWER_PINS='(P3V3_STBY:5;GND:3)';
      PARENT_PART_TYPE='TTL1G07_A_SOP';
      SCH_MODIFIED_PART='TRUE';
      PARENT_PPT='TTL1G07_A';
      PARENT_PPT_PART='TTL1G07_A_SOP-74LVC1G07,IC,C88419-001';
  end_body;
end_primitive;
primitive 'TTL1G08_SOTLF-NC7SZ08,IC,D1032B';
  pin
    'Y'<0>:
      PIN_NUMBER='(4)';
      OUTPUT_LOAD='(20.0,-1.0)';
      PINUSE='OUT';
    'A'<0>:
      PIN_NUMBER='(1)';
      INPUT_LOAD='(-0.6,0.005)';
      PIN_GROUP='1';
      PINUSE='IN';
    'B'<0>:
      PIN_NUMBER='(2)';
      INPUT_LOAD='(-0.6,0.005)';
      PIN_GROUP='1';
      PINUSE='IN';
  end_pin;
  body
      CLASS='IC';
      BODY_NAME='TTL1G08';
      PART_NAME='TTL1G08';
      PHYS_DES_PREFIX='U';
      ENVCOMP='YES;YES;CNC;CNC;ok;CIP';
      PART_NUMBER='D10321-001';
      JEDEC_TYPE='SSOP5_53_65MA';
      DESCRIPTION='SINGLE 2-INPUT AND';
      HEIGHT='0.043 IN';
      COMPONENT_TYPE='SUB50';
      LEAD_LENGTH='';
      LPID='374';
      SPEED_URL='http://speed.intel.com:8081/speed/module/pdm/item/pdm_item_deta~
il_direct.asp?item_cde=D10321-001&item_rev=01&url_param=unused';
      STATUS='Conditional';
      RPL='YES';
      AML='6';
      BUS_UNIT='SMO_IC';
      DAYS='49';
      POWER_PINS='(P3V3_STBY:5;GND:3)';
      PARENT_PART_TYPE='TTL1G08';
      SCH_MODIFIED_PART='TRUE';
      PARENT_PPT='TTL1G08';
      PARENT_PPT_PART='TTL1G08_SOTLF-NC7SZ08,IC,D10321-001';
  end_body;
end_primitive;
primitive 'TTL1G08_SOTLF-NC7SZ08,IC,D1032C';
  pin
    'Y'<0>:
      PIN_NUMBER='(4)';
      OUTPUT_LOAD='(20.0,-1.0)';
      PINUSE='OUT';
    'A'<0>:
      PIN_NUMBER='(1)';
      INPUT_LOAD='(-0.6,0.005)';
      PIN_GROUP='1';
      PINUSE='IN';
    'B'<0>:
      PIN_NUMBER='(2)';
      INPUT_LOAD='(-0.6,0.005)';
      PIN_GROUP='1';
      PINUSE='IN';
  end_pin;
  body
      CLASS='IC';
      BODY_NAME='TTL1G08';
      PART_NAME='TTL1G08';
      PHYS_DES_PREFIX='U';
      ENVCOMP='YES;YES;CNC;CNC;ok;CIP';
      PART_NUMBER='D10321-001';
      JEDEC_TYPE='SSOP5_53_65MA';
      DESCRIPTION='SINGLE 2-INPUT AND';
      HEIGHT='0.043 IN';
      COMPONENT_TYPE='SUB50';
      LEAD_LENGTH='';
      LPID='374';
      SPEED_URL='http://speed.intel.com:8081/speed/module/pdm/item/pdm_item_deta~
il_direct.asp?item_cde=D10321-001&item_rev=01&url_param=unused';
      STATUS='Conditional';
      RPL='YES';
      AML='6';
      BUS_UNIT='SMO_IC';
      DAYS='49';
      POWER_PINS='(P3V3:5;GND:3)';
      PARENT_PART_TYPE='TTL1G08';
      SCH_MODIFIED_PART='TRUE';
      PARENT_PPT='TTL1G08';
      PARENT_PPT_PART='TTL1G08_SOTLF-NC7SZ08,IC,D10321-001';
  end_body;
end_primitive;
primitive 'TTL1G126_A_SOT-74HC1G126,IC,A7B';
  pin
    'OE':
      PIN_NUMBER='(1)';
      INPUT_LOAD='(-0.01,0.01)';
      PINUSE='IN';
    'A':
      PIN_NUMBER='(2)';
      INPUT_LOAD='(-0.01,0.01)';
      PINUSE='IN';
    'Y':
      PIN_NUMBER='(4)';
      OUTPUT_LOAD='(1.0,-1.0)';
      PINUSE='OUT';
  end_pin;
  body
      CLASS='IC';
      PART_NAME='TTL1G126_A';
      PHYS_DES_PREFIX='U';
      ENVCOMP='YES;YES;UNK;UNK;ok;CIP';
      PART_NUMBER='A79322-001';
      JEDEC_TYPE='SSOP5_53_65MA';
      DESCRIPTION='SINGLE BUFFER 3S OUT';
      HEIGHT='.043 IN';
      COMPONENT_TYPE='SMALLSMT';
      LPID='';
      SPEED_URL='http://speed.intel.com:8081/speed/module/pdm/item/pdm_item_deta~
il_direct.asp?item_cde=A79322-001&item_rev=01&url_param=unused';
      STATUS='Conditional';
      RPL='NO';
      AML='2';
      BUS_UNIT='SMO_IC';
      DAYS='84';
      POWER_PINS='(P3V3_STBY:5;GND:3)';
      PARENT_PART_TYPE='TTL1G126_A_SOT';
      SCH_MODIFIED_PART='TRUE';
      PARENT_PPT='TTL1G126_A';
      PARENT_PPT_PART='TTL1G126_A_SOT-74HC1G126,IC,A79322-001';
  end_body;
end_primitive;
primitive 'TTL1G32_A_SOT-74LVC1G32,IC,E60B';
  pin
    'A':
      PIN_NUMBER='(1)';
      INPUT_LOAD='(-0.6,0.02)';
      PIN_GROUP='1';
      PINUSE='IN';
    'B':
      PIN_NUMBER='(2)';
      INPUT_LOAD='(-0.6,0.02)';
      PIN_GROUP='1';
      PINUSE='IN';
    'Y':
      PIN_NUMBER='(4)';
      OUTPUT_LOAD='(20.0,-1.0)';
      PINUSE='OUT';
  end_pin;
  body
      PART_NAME='TTL1G32_A';
      PHYS_DES_PREFIX='U';
      ENVCOMP='YES;YES;UNK;UNK;ok;VLD';
      PART_NUMBER='E60229-001';
      JEDEC_TYPE='SSOP5_53_65MA';
      CLASS='IC';
      DESCRIPTION='IC,LOG,GATES,SC70,SGL,2-INPUT,POS-OR';
      HEIGHT='0.043 IN';
      COMPONENT_TYPE='SMALLSMT';
      LEAD_LENGTH='';
      LPID='374';
      SPEED_URL='http://speed.intel.com:8081/speed/module/pdm/item/pdm_item_deta~
il_direct.asp?item_cde=E60229-001&item_rev=01&url_param=unused';
      STATUS='Preliminary';
      RPL='NO';
      AML='1';
      BUS_UNIT='ECG';
      DAYS='???';
      POWER_PINS='(P3V3_STBY:5;GND:3)';
      PARENT_PART_TYPE='TTL1G32_A';
      SCH_MODIFIED_PART='TRUE';
      PARENT_PPT='TTL1G32_A';
      PARENT_PPT_PART='TTL1G32_A_SOT-74LVC1G32,IC,E60229-001';
  end_body;
end_primitive;
primitive 'TTL1G86_SOTLF-74AHCT1G86,IC,D3B';
  pin
    'A':
      PIN_NUMBER='(1)';
      INPUT_LOAD='(-0.01,0.01)';
      PINUSE='IN';
    'B':
      PIN_NUMBER='(2)';
      INPUT_LOAD='(-0.01,0.01)';
      PINUSE='IN';
    'Y':
      PIN_NUMBER='(4)';
      OUTPUT_LOAD='(1.0,-1.0)';
      PINUSE='OUT';
  end_pin;
  body
      CLASS='IC';
      PART_NAME='TTL1G86';
      PHYS_DES_PREFIX='U';
      ENVCOMP='YES;YES;UNK;UNK;ok;VLD';
      PART_NUMBER='D39848-001';
      JEDEC_TYPE='SSOP5_53_65MA';
      DESCRIPTION='SINGLE 2 INPUT XOR';
      HEIGHT='0.043 IN';
      COMPONENT_TYPE='SMALLSMT';
      LEAD_LENGTH='';
      LPID='';
      SPEED_URL='http://speed.intel.com:8081/speed/module/pdm/item/pdm_item_deta~
il_direct.asp?item_cde=D39848-001&item_rev=01&url_param=unused';
      STATUS='Design';
      RPL='YES';
      AML='1';
      BUS_UNIT='SMO_IC';
      DAYS='84';
      POWER_PINS='(P5V_STBY:5;GND:3)';
      PARENT_PART_TYPE='TTL1G86_SOTLF';
      SCH_MODIFIED_PART='TRUE';
      PARENT_PPT='TTL1G86';
      PARENT_PPT_PART='TTL1G86_SOTLF-74AHCT1G86,IC,D39848-001';
  end_body;
end_primitive;
primitive 'TTL3126_QFNLF-74CBTLV3126,IC,DB';
  pin
    'OE'<0>:
      PIN_NUMBER='(1,4,10,13)';
      INPUT_LOAD='(-0.01,0.01)';
      PINUSE='IN';
    'A'<0>:
      PIN_NUMBER='(2,5,9,12)';
      INPUT_LOAD='(-0.01,0.01)';
      OUTPUT_LOAD='(1.00,-1.00)';
      OUTPUT_TYPE='(TS,TS)';
      BIDIRECTIONAL='TRUE';
      PINUSE='BI';
    'B'<0>:
      PIN_NUMBER='(3,6,8,11)';
      INPUT_LOAD='(-0.01,0.01)';
      OUTPUT_LOAD='(1.00,-1.00)';
      OUTPUT_TYPE='(TS,TS)';
      BIDIRECTIONAL='TRUE';
      PINUSE='BI';
  end_pin;
  body
      PART_NAME='TTL3126';
      ENVCOMP='YES;YES;YES;UNK;ok;VLD';
      PART_NUMBER='D18317-001';
      JEDEC_TYPE='QFN14_14_14_5MA';
      CLASS='IC';
      DESCRIPTION='LOW VOLTAGE QUAD BUS SWITCH';
      HEIGHT='0.039 IN';
      COMPONENT_TYPE='LCC';
      LEAD_LENGTH='';
      LPID='1642';
      SPEED_URL='http://speed.intel.com:8081/speed/module/pdm/item/pdm_item_deta~
il_direct.asp?item_cde=D18317-001&item_rev=01&url_param=unused';
      STATUS='Preliminary';
      RPL='YES';
      AML='1';
      BUS_UNIT='SMO_IC';
      DAYS='84';
      POWER_PINS='(P3V3_STBY:14;GND:7,15)';
      PARENT_PART_TYPE='TTL3126_QFNLF';
      SCH_MODIFIED_PART='TRUE';
      PARENT_PPT='TTL3126';
      PARENT_PPT_PART='TTL3126_QFNLF-74CBTLV3126,IC,D18317-001';
  end_body;
end_primitive;
primitive 'U74AHCT1G125G-AL5-R-GP-U_TTL-GA';
  pin
    'OE#':
      PIN_NUMBER='(1)';
      PIN_TYPE='ANALOG';
      NO_LOAD_CHECK='Both';
      NO_IO_CHECK='Both';
      NO_ASSERT_CHECK='TRUE';
      NO_DIR_CHECK='TRUE';
      ALLOW_CONNECT='TRUE';
      PINUSE='UNSPEC';
    'A':
      PIN_NUMBER='(2)';
      PIN_TYPE='ANALOG';
      NO_LOAD_CHECK='Both';
      NO_IO_CHECK='Both';
      NO_ASSERT_CHECK='TRUE';
      NO_DIR_CHECK='TRUE';
      ALLOW_CONNECT='TRUE';
      PINUSE='UNSPEC';
    'GND':
      PIN_NUMBER='(3)';
      PINUSE='POWER';
      NO_LOAD_CHECK='Both';
      NO_IO_CHECK='Both';
      NO_ASSERT_CHECK='TRUE';
      NO_DIR_CHECK='TRUE';
      ALLOW_CONNECT='TRUE';
    'Y':
      PIN_NUMBER='(4)';
      PIN_TYPE='ANALOG';
      NO_LOAD_CHECK='Both';
      NO_IO_CHECK='Both';
      NO_ASSERT_CHECK='TRUE';
      NO_DIR_CHECK='TRUE';
      ALLOW_CONNECT='TRUE';
      PINUSE='UNSPEC';
    'VCC':
      PIN_NUMBER='(5)';
      PINUSE='POWER';
      NO_LOAD_CHECK='Both';
      NO_IO_CHECK='Both';
      NO_ASSERT_CHECK='TRUE';
      NO_DIR_CHECK='TRUE';
      ALLOW_CONNECT='TRUE';
  end_pin;
  body
      PART_NAME='U74AHCT1G125G-AL5-R-GP-U';
      BODY_NAME='U74AHCT1G125G-AL5-R-GP-U';
      PHYS_DES_PREFIX='U';
      CLASS='IC';
      DESCRIPTION='IC CMOS U74AHCT1G125G-AL5-R SO';
      JEDEC_TYPE='SC70-5-1H44';
      PARENT_PART_TYPE='U74AHCT1G125G-AL5-R-GP-U';
      PARENT_PPT='U74AHCT1G125G-AL5-R-GP-U';
      PARENT_PPT_PART='U74AHCT1G125G-AL5-R-GP-U_TTL-G4-U74AHCT1G125G-AL5-R-GP-U,73.1G125.D0G';
  end_body;
end_primitive;
primitive 'VERT_BATT_3PIN_PIP-3PVERT,C686A';
  pin
    'N':
      PIN_NUMBER='(3)';
      PIN_TYPE='ANALOG';
      NO_LOAD_CHECK='BOTH';
      NO_IO_CHECK='BOTH';
      ALLOW_CONNECT='TRUE';
      PINUSE='UNSPEC';
    'P1':
      PIN_NUMBER='(1)';
      PIN_TYPE='ANALOG';
      NO_LOAD_CHECK='BOTH';
      NO_IO_CHECK='BOTH';
      ALLOW_CONNECT='TRUE';
      PINUSE='UNSPEC';
    'P2':
      PIN_NUMBER='(2)';
      PIN_TYPE='ANALOG';
      NO_LOAD_CHECK='BOTH';
      NO_IO_CHECK='BOTH';
      ALLOW_CONNECT='TRUE';
      PINUSE='UNSPEC';
  end_pin;
  body
      PART_NAME='VERT_BATT_3PIN';
      PHYS_DES_PREFIX='BT';
      ENVCOMP='';
      PART_NUMBER='C68619-005';
      JEDEC_TYPE='VERT_BATT_3PIN_PIP';
      CLASS='DISCRETE';
      DESCRIPTION='BAT ACC,HOLDR,THM,CR2032';
      HEIGHT='0.526 IN';
      COMPONENT_TYPE='THMT';
      LEAD_LENGTH='0.122';
      LPID='';
      SPEED_URL='http://speed.intel.com:8081/speed/module/pdm/item/pdm_item_deta~
il_direct.asp?item_cde=C68619-005&item_rev=01&url_param=unused';
      STATUS='';
      RPL='';
      AML='';
      BUS_UNIT='';
      DAYS='';
      PARENT_PART_TYPE='VERT_BATT_3PIN_PIP';
      PARENT_PPT='VERT_BATT_3PIN';
      PARENT_PPT_PART='VERT_BATT_3PIN_PIP-3PVERT,C68619-005';
  end_body;
end_primitive;
primitive 'W25Q128_SKT16-IC,H12709-001';
  pin
    'HOLD_N_IO'<3>:
      PIN_NUMBER='(1)';
      BIDIRECTIONAL='TRUE';
      INPUT_LOAD='(-0.01,0.01)';
      OUTPUT_LOAD='(1.0,-1.0)';
      PINUSE='BI';
    'VCC':
      PIN_NUMBER='(2)';
      PINUSE='POWER';
      NO_LOAD_CHECK='Both';
      NO_IO_CHECK='Both';
      NO_ASSERT_CHECK='TRUE';
      NO_DIR_CHECK='TRUE';
      ALLOW_CONNECT='TRUE';
    'RESET_N':
      PIN_NUMBER='(3)';
      INPUT_LOAD='(-0.01,0.01)';
      PINUSE='IN';
    'NC'<0>:
      PIN_NUMBER='(4)';
      PINUSE='NC';
      NO_LOAD_CHECK='Both';
      NO_IO_CHECK='Both';
      ALLOW_CONNECT='TRUE';
    'NC'<1>:
      PIN_NUMBER='(5)';
      PINUSE='NC';
      NO_LOAD_CHECK='Both';
      NO_IO_CHECK='Both';
      ALLOW_CONNECT='TRUE';
    'NC'<2>:
      PIN_NUMBER='(6)';
      PINUSE='NC';
      NO_LOAD_CHECK='Both';
      NO_IO_CHECK='Both';
      ALLOW_CONNECT='TRUE';
    'CS_N':
      PIN_NUMBER='(7)';
      INPUT_LOAD='(-0.01,0.01)';
      PINUSE='IN';
    'DO_IO'<1>:
      PIN_NUMBER='(8)';
      BIDIRECTIONAL='TRUE';
      INPUT_LOAD='(-0.01,0.01)';
      OUTPUT_LOAD='(1.0,-1.0)';
      PINUSE='BI';
    'WP_N_IO'<2>:
      PIN_NUMBER='(9)';
      BIDIRECTIONAL='TRUE';
      INPUT_LOAD='(-0.01,0.01)';
      OUTPUT_LOAD='(1.0,-1.0)';
      PINUSE='BI';
    'GND':
      PIN_NUMBER='(10)';
      PINUSE='GROUND';
      NO_LOAD_CHECK='Both';
      NO_IO_CHECK='Both';
      NO_ASSERT_CHECK='TRUE';
      NO_DIR_CHECK='TRUE';
      ALLOW_CONNECT='TRUE';
    'NC'<3>:
      PIN_NUMBER='(11)';
      PINUSE='NC';
      NO_LOAD_CHECK='Both';
      NO_IO_CHECK='Both';
      ALLOW_CONNECT='TRUE';
    'NC'<4>:
      PIN_NUMBER='(12)';
      PINUSE='NC';
      NO_LOAD_CHECK='Both';
      NO_IO_CHECK='Both';
      ALLOW_CONNECT='TRUE';
    'NC'<5>:
      PIN_NUMBER='(13)';
      PINUSE='NC';
      NO_LOAD_CHECK='Both';
      NO_IO_CHECK='Both';
      ALLOW_CONNECT='TRUE';
    'NC'<6>:
      PIN_NUMBER='(14)';
      PINUSE='NC';
      NO_LOAD_CHECK='Both';
      NO_IO_CHECK='Both';
      ALLOW_CONNECT='TRUE';
    'DI_IO'<0>:
      PIN_NUMBER='(15)';
      BIDIRECTIONAL='TRUE';
      INPUT_LOAD='(-0.01,0.01)';
      OUTPUT_LOAD='(1.0,-1.0)';
      PINUSE='BI';
    'CLK':
      PIN_NUMBER='(16)';
      INPUT_LOAD='(-0.01,0.01)';
      PINUSE='IN';
  end_pin;
  body
      PART_NAME='W25Q128';
      PHYS_DES_PREFIX='U';
      ENVCOMP='';
      PART_NUMBER='H12709-001';
      JEDEC_TYPE='XSOI16_30_50IA';
      ALT_SYMBOLS='';
      DESCRIPTION='(USE SYM_3)IC,FLASH,128MB SPI NOR,SOIC,16';
      CLASS='IC';
      COMPONENT_TYPE='SOIC';
      HEIGHT='0.104 IN';
      LPID='';
      SPEED_URL='http://speed.intel.com:8081/speed/module/pdm/item/pdm_item_deta~
il_direct.asp?item_cde=H12709-001&item_rev=01&url_param=unused';
      STATUS='';
      RPL='';
      AML='';
      BUS_UNIT='';
      DAYS='';
      PARENT_PART_TYPE='W25Q128_SKT16';
      PARENT_PPT='W25Q128';
      PARENT_PPT_PART='W25Q128_SKT16-IC,H12709-001';
  end_body;
end_primitive;
primitive 'W25Q256FVFIG-GP_MEMORY-G4-W25QA';
  pin
    'HOLD#/IO3':
      PIN_NUMBER='(1)';
      BIDIRECTIONAL='TRUE';
      INPUT_LOAD='(-0.01,0.01)';
      OUTPUT_LOAD='(1.0,-1.0)';
      PINUSE='BI';
    'VCC':
      PIN_NUMBER='(2)';
      PINUSE='POWER';
      NO_LOAD_CHECK='Both';
      NO_IO_CHECK='Both';
      NO_ASSERT_CHECK='TRUE';
      NO_DIR_CHECK='TRUE';
      ALLOW_CONNECT='TRUE';
    'RESET#':
      PIN_NUMBER='(3)';
      INPUT_LOAD='(-0.01,0.01)';
      PINUSE='IN';
    'NC#4':
      PIN_NUMBER='(4)';
      PIN_TYPE='ANALOG';
      NO_LOAD_CHECK='Both';
      NO_IO_CHECK='Both';
      NO_ASSERT_CHECK='TRUE';
      NO_DIR_CHECK='TRUE';
      ALLOW_CONNECT='TRUE';
      PINUSE='UNSPEC';
    'NC#5':
      PIN_NUMBER='(5)';
      PIN_TYPE='ANALOG';
      NO_LOAD_CHECK='Both';
      NO_IO_CHECK='Both';
      NO_ASSERT_CHECK='TRUE';
      NO_DIR_CHECK='TRUE';
      ALLOW_CONNECT='TRUE';
      PINUSE='UNSPEC';
    'NC#6':
      PIN_NUMBER='(6)';
      PIN_TYPE='ANALOG';
      NO_LOAD_CHECK='Both';
      NO_IO_CHECK='Both';
      NO_ASSERT_CHECK='TRUE';
      NO_DIR_CHECK='TRUE';
      ALLOW_CONNECT='TRUE';
      PINUSE='UNSPEC';
    'CS#':
      PIN_NUMBER='(7)';
      INPUT_LOAD='(-0.01,0.01)';
      PINUSE='IN';
    'DO/IO1':
      PIN_NUMBER='(8)';
      BIDIRECTIONAL='TRUE';
      INPUT_LOAD='(-0.01,0.01)';
      OUTPUT_LOAD='(1.0,-1.0)';
      PINUSE='BI';
    'WP#/IO2':
      PIN_NUMBER='(9)';
      BIDIRECTIONAL='TRUE';
      INPUT_LOAD='(-0.01,0.01)';
      OUTPUT_LOAD='(1.0,-1.0)';
      PINUSE='BI';
    'GND':
      PIN_NUMBER='(10)';
      PINUSE='POWER';
      NO_LOAD_CHECK='Both';
      NO_IO_CHECK='Both';
      NO_ASSERT_CHECK='TRUE';
      NO_DIR_CHECK='TRUE';
      ALLOW_CONNECT='TRUE';
    'NC#11':
      PIN_NUMBER='(11)';
      PIN_TYPE='ANALOG';
      NO_LOAD_CHECK='Both';
      NO_IO_CHECK='Both';
      NO_ASSERT_CHECK='TRUE';
      NO_DIR_CHECK='TRUE';
      ALLOW_CONNECT='TRUE';
      PINUSE='UNSPEC';
    'NC#12':
      PIN_NUMBER='(12)';
      PIN_TYPE='ANALOG';
      NO_LOAD_CHECK='Both';
      NO_IO_CHECK='Both';
      NO_ASSERT_CHECK='TRUE';
      NO_DIR_CHECK='TRUE';
      ALLOW_CONNECT='TRUE';
      PINUSE='UNSPEC';
    'NC#13':
      PIN_NUMBER='(13)';
      PIN_TYPE='ANALOG';
      NO_LOAD_CHECK='Both';
      NO_IO_CHECK='Both';
      NO_ASSERT_CHECK='TRUE';
      NO_DIR_CHECK='TRUE';
      ALLOW_CONNECT='TRUE';
      PINUSE='UNSPEC';
    'NC#14':
      PIN_NUMBER='(14)';
      PIN_TYPE='ANALOG';
      NO_LOAD_CHECK='Both';
      NO_IO_CHECK='Both';
      NO_ASSERT_CHECK='TRUE';
      NO_DIR_CHECK='TRUE';
      ALLOW_CONNECT='TRUE';
      PINUSE='UNSPEC';
    'DI/IO0':
      PIN_NUMBER='(15)';
      BIDIRECTIONAL='TRUE';
      INPUT_LOAD='(-0.01,0.01)';
      OUTPUT_LOAD='(1.0,-1.0)';
      PINUSE='BI';
    'CLK':
      PIN_NUMBER='(16)';
      INPUT_LOAD='(-0.01,0.01)';
      PINUSE='IN';
  end_pin;
  body
      PART_NAME='W25Q256FVFIG-GP';
      BODY_NAME='W25Q256FVFIG-GP';
      PHYS_DES_PREFIX='U';
      CLASS='IC';
      DESCRIPTION='IC FEROM W25Q256FVFIG SOIC 16P';
      JEDEC_TYPE='SOIC16-6H104';
      PARENT_PART_TYPE='W25Q256FVFIG-GP';
      PARENT_PPT='W25Q256FVFIG-GP';
      PARENT_PPT_PART='W25Q256FVFIG-GP_MEMORY-G4-W25Q256FVFIG-GP,72.25256.H01';
  end_body;
end_primitive;
primitive 'W25Q256_XSOI-IC,H25002-001';
  pin
    'WP_N_IO'<2>:
      PIN_NUMBER='(9)';
      BIDIRECTIONAL='TRUE';
      INPUT_LOAD='(-0.01,0.01)';
      OUTPUT_LOAD='(1.0,-1.0)';
      PINUSE='BI';
    'NC'<0>:
      PIN_NUMBER='(14)';
      PINUSE='NC';
      NO_LOAD_CHECK='Both';
      NO_IO_CHECK='Both';
      NO_ASSERT_CHECK='TRUE';
      NO_DIR_CHECK='TRUE';
      ALLOW_CONNECT='TRUE';
    'NC'<1>:
      PIN_NUMBER='(13)';
      PINUSE='NC';
      NO_LOAD_CHECK='Both';
      NO_IO_CHECK='Both';
      NO_ASSERT_CHECK='TRUE';
      NO_DIR_CHECK='TRUE';
      ALLOW_CONNECT='TRUE';
    'NC'<2>:
      PIN_NUMBER='(12)';
      PINUSE='NC';
      NO_LOAD_CHECK='Both';
      NO_IO_CHECK='Both';
      NO_ASSERT_CHECK='TRUE';
      NO_DIR_CHECK='TRUE';
      ALLOW_CONNECT='TRUE';
    'NC'<3>:
      PIN_NUMBER='(11)';
      PINUSE='NC';
      NO_LOAD_CHECK='Both';
      NO_IO_CHECK='Both';
      NO_ASSERT_CHECK='TRUE';
      NO_DIR_CHECK='TRUE';
      ALLOW_CONNECT='TRUE';
    'NC'<4>:
      PIN_NUMBER='(6)';
      PINUSE='NC';
      NO_LOAD_CHECK='Both';
      NO_IO_CHECK='Both';
      NO_ASSERT_CHECK='TRUE';
      NO_DIR_CHECK='TRUE';
      ALLOW_CONNECT='TRUE';
    'NC'<5>:
      PIN_NUMBER='(5)';
      PINUSE='NC';
      NO_LOAD_CHECK='Both';
      NO_IO_CHECK='Both';
      NO_ASSERT_CHECK='TRUE';
      NO_DIR_CHECK='TRUE';
      ALLOW_CONNECT='TRUE';
    'NC'<6>:
      PIN_NUMBER='(4)';
      PINUSE='NC';
      NO_LOAD_CHECK='Both';
      NO_IO_CHECK='Both';
      NO_ASSERT_CHECK='TRUE';
      NO_DIR_CHECK='TRUE';
      ALLOW_CONNECT='TRUE';
    'GND':
      PIN_NUMBER='(10)';
      PINUSE='GROUND';
      NO_LOAD_CHECK='Both';
      NO_IO_CHECK='Both';
      NO_ASSERT_CHECK='TRUE';
      NO_DIR_CHECK='TRUE';
      ALLOW_CONNECT='TRUE';
    'DO_IO'<1>:
      PIN_NUMBER='(8)';
      BIDIRECTIONAL='TRUE';
      INPUT_LOAD='(-0.01,0.01)';
      OUTPUT_LOAD='(1.0,-1.0)';
      PINUSE='BI';
    'CLK':
      PIN_NUMBER='(16)';
      INPUT_LOAD='(-0.01,0.01)';
      PINUSE='IN';
    'VCC':
      PIN_NUMBER='(2)';
      PINUSE='POWER';
      NO_LOAD_CHECK='Both';
      NO_IO_CHECK='Both';
      NO_ASSERT_CHECK='TRUE';
      NO_DIR_CHECK='TRUE';
      ALLOW_CONNECT='TRUE';
    'CS_N':
      PIN_NUMBER='(7)';
      INPUT_LOAD='(-0.01,0.01)';
      PINUSE='IN';
    'DI_IO'<0>:
      PIN_NUMBER='(15)';
      BIDIRECTIONAL='TRUE';
      INPUT_LOAD='(-0.01,0.01)';
      OUTPUT_LOAD='(1.0,-1.0)';
      PINUSE='BI';
    'RESET_N':
      PIN_NUMBER='(3)';
      INPUT_LOAD='(-0.01,0.01)';
      PINUSE='IN';
    'HOLD_N_IO'<3>:
      PIN_NUMBER='(1)';
      BIDIRECTIONAL='TRUE';
      INPUT_LOAD='(-0.01,0.01)';
      OUTPUT_LOAD='(1.0,-1.0)';
      PINUSE='BI';
  end_pin;
  body
      PART_NAME='W25Q256';
      BODY_NAME='W25Q256';
      PHYS_DES_PREFIX='U';
      ENVCOMP='YES;YES;YES;UNK;ok;VLD';
      PART_NUMBER='H25002-001';
      JEDEC_TYPE='XSOI16_30_50IA';
      DESCRIPTION='IC,FLASH,SPI NOR 256MBIT,SOIC,16';
      CLASS='IC';
      COMPONENT_TYPE='SOIC';
      HEIGHT='0.104 IN';
      LPID='';
      SPEED_URL='http://speed.intel.com:8081/speed/module/pdm/item/pdm_item_deta~
il_direct.asp?item_cde=H25002-001&item_rev=01&url_param=unused';
      STATUS='Design';
      RPL='NO';
      AML='1';
      BUS_UNIT='SMO_IC';
      DAYS='???';
      PARENT_PART_TYPE='W25Q256_XSOI';
      PARENT_PPT='W25Q256';
      PARENT_PPT_PART='W25Q256_XSOI-IC,H25002-001';
  end_body;
end_primitive;
primitive 'ZENER_SM-13V,IC,H69095-001';
  pin
    'A':
      PIN_NUMBER='(2)';
      PINUSE='UNSPEC';
      NO_LOAD_CHECK='BOTH';
      NO_IO_CHECK='BOTH';
      ALLOW_CONNECT='TRUE';
    'C':
      PIN_NUMBER='(1)';
      PINUSE='UNSPEC';
      NO_LOAD_CHECK='BOTH';
      NO_IO_CHECK='BOTH';
      ALLOW_CONNECT='TRUE';
  end_pin;
  body
      PART_NAME='ZENER';
      PHYS_DES_PREFIX='VR';
      ENVCOMP='';
      PART_NUMBER='H69095-001';
      JEDEC_TYPE='SCR3125A';
      CLASS='IC';
      DESCRIPTION='IC,DS,DIO,SMC,SMCJ13A,ZENER';
      HEIGHT='0.103 IN';
      COMPONENT_TYPE='SMTOTHER';
      LEAD_LENGTH='';
      LPID='472';
      SPEED_URL='http://speed.intel.com:8081/speed/module/pdm/item/pdm_item_deta~
il_direct.asp?item_cde=H69095-001&item_rev=01&url_param=unused';
      STATUS='';
      RPL='';
      AML='';
      BUS_UNIT='';
      DAYS='';
      PARENT_PART_TYPE='ZENER_SM';
      PARENT_PPT='ZENER';
      PARENT_PPT_PART='ZENER_SM-13V,IC,H69095-001';
  end_body;
end_primitive;
END.
